(kicad_pcb (version 20221018) (generator pcbnew)

  (general
    (thickness 1.6)
  )

  (paper "A4")
  (title_block
    (title "NUC Computer Cluster Power Breakout HW")
    (date "2023-10-18")
    (rev "1.4.3")
    (company "Antmicro Ltd.")
  )

  (layers
    (0 "F.Cu" mixed)
    (1 "In1.Cu" power)
    (2 "In2.Cu" mixed)
    (31 "B.Cu" power)
    (32 "B.Adhes" user "B.Adhesive")
    (33 "F.Adhes" user "F.Adhesive")
    (34 "B.Paste" user)
    (35 "F.Paste" user)
    (36 "B.SilkS" user "B.Silkscreen")
    (37 "F.SilkS" user "F.Silkscreen")
    (38 "B.Mask" user)
    (39 "F.Mask" user)
    (40 "Dwgs.User" user "User.Drawings")
    (41 "Cmts.User" user "User.Comments")
    (42 "Eco1.User" user "User.Eco1")
    (43 "Eco2.User" user "User.Eco2")
    (44 "Edge.Cuts" user)
    (45 "Margin" user)
    (46 "B.CrtYd" user "B.Courtyard")
    (47 "F.CrtYd" user "F.Courtyard")
    (48 "B.Fab" user)
    (49 "F.Fab" user)
  )

  (setup
    (stackup
      (layer "F.SilkS" (type "Top Silk Screen"))
      (layer "F.Paste" (type "Top Solder Paste"))
      (layer "F.Mask" (type "Top Solder Mask") (color "Black") (thickness 0.01))
      (layer "F.Cu" (type "copper") (thickness 0.035))
      (layer "dielectric 1" (type "core") (thickness 0.48) (material "FR4") (epsilon_r 4.5) (loss_tangent 0.02))
      (layer "In1.Cu" (type "copper") (thickness 0.035))
      (layer "dielectric 2" (type "prepreg") (thickness 0.48) (material "FR4") (epsilon_r 4.5) (loss_tangent 0.02))
      (layer "In2.Cu" (type "copper") (thickness 0.035))
      (layer "dielectric 3" (type "core") (thickness 0.48) (material "FR4") (epsilon_r 4.5) (loss_tangent 0.02))
      (layer "B.Cu" (type "copper") (thickness 0.035))
      (layer "B.Mask" (type "Bottom Solder Mask") (color "Black") (thickness 0.01))
      (layer "B.Paste" (type "Bottom Solder Paste"))
      (layer "B.SilkS" (type "Bottom Silk Screen"))
      (copper_finish "None")
      (dielectric_constraints no)
    )
    (pad_to_mask_clearance 0)
    (pcbplotparams
      (layerselection 0x00010fc_ffffffff)
      (plot_on_all_layers_selection 0x0000000_00000000)
      (disableapertmacros false)
      (usegerberextensions false)
      (usegerberattributes true)
      (usegerberadvancedattributes true)
      (creategerberjobfile true)
      (dashed_line_dash_ratio 12.000000)
      (dashed_line_gap_ratio 3.000000)
      (svgprecision 6)
      (plotframeref false)
      (viasonmask false)
      (mode 1)
      (useauxorigin false)
      (hpglpennumber 1)
      (hpglpenspeed 20)
      (hpglpendiameter 15.000000)
      (dxfpolygonmode true)
      (dxfimperialunits true)
      (dxfusepcbnewfont true)
      (psnegative false)
      (psa4output false)
      (plotreference true)
      (plotvalue true)
      (plotinvisibletext false)
      (sketchpadsonfab false)
      (subtractmaskfromsilk false)
      (outputformat 1)
      (mirror false)
      (drillshape 1)
      (scaleselection 1)
      (outputdirectory "")
    )
  )

  (net 0 "")
  (net 1 "VCC3V3")
  (net 2 "VCC5V0")
  (net 3 "VCC5V0_USB")
  (net 4 "GND")
  (net 5 "/FTDI/OSCI")
  (net 6 "/FTDI/FTDI_VPLL")
  (net 7 "1V8_FT")
  (net 8 "/FTDI/FTDI_VPHY")
  (net 9 "/FTDI/SDA_FTDI_2")
  (net 10 "VBUS")
  (net 11 "VCC12V0")
  (net 12 "Net-(U15-BST)")
  (net 13 "Net-(U15-SW)")
  (net 14 "/FTDI/USB_D+")
  (net 15 "/FTDI/USB_D-")
  (net 16 "Net-(U4-BST)")
  (net 17 "SCL")
  (net 18 "SDA")
  (net 19 "Net-(J2-Pad1)")
  (net 20 "Net-(J3-Pad1)")
  (net 21 "C_MEAS_1")
  (net 22 "C_MEAS_2")
  (net 23 "/Power Cycling & Current Measurement/PC_1")
  (net 24 "/Power Cycling & Current Measurement/PC_2")
  (net 25 "C_MEAS_5")
  (net 26 "/Power Cycling & Current Measurement/PC_5")
  (net 27 "C_MEAS_4")
  (net 28 "C_MEAS_3")
  (net 29 "/Power Cycling & Current Measurement/PC_4")
  (net 30 "/Power Cycling & Current Measurement/PC_3")
  (net 31 "/FTDI/FTDI_RST")
  (net 32 "Net-(U4-SW)")
  (net 33 "/FTDI/WP")
  (net 34 "Net-(U14-REF)")
  (net 35 "Net-(D2-A)")
  (net 36 "Net-(D3-A)")
  (net 37 "Net-(D4-A)")
  (net 38 "Net-(D5-C)")
  (net 39 "Net-(D5-A)")
  (net 40 "Net-(D6-A)")
  (net 41 "LOAD_1")
  (net 42 "LOAD_3")
  (net 43 "LOAD_5")
  (net 44 "LOAD_2")
  (net 45 "LOAD_4")
  (net 46 "/Power Cycling & Current Measurement/C_ADC1")
  (net 47 "/Power Cycling & Current Measurement/C_ADC2")
  (net 48 "/Power Cycling & Current Measurement/C_ADC3")
  (net 49 "/Power Cycling & Current Measurement/C_ADC4")
  (net 50 "/Power Cycling & Current Measurement/C_ADC5")
  (net 51 "PSU_ON")
  (net 52 "Net-(D7-A)")
  (net 53 "Net-(D8-A)")
  (net 54 "Net-(Q11-Pad1)")
  (net 55 "Net-(J10-PadS24)")
  (net 56 "Net-(J10-PadS12)")
  (net 57 "Net-(J10-PadS11)")
  (net 58 "Net-(J10-PadS10)")
  (net 59 "Net-(J10-PadS9)")
  (net 60 "Net-(J10-PadS5)")
  (net 61 "Net-(J10-PadS6)")
  (net 62 "Net-(J10-PadS7)")
  (net 63 "Net-(J10-PadS8)")
  (net 64 "Net-(J10-PadS1)")
  (net 65 "Net-(J10-PadS2)")
  (net 66 "Net-(J10-PadS3)")
  (net 67 "Net-(J10-PadS4)")
  (net 68 "Net-(J10-PadS23)")
  (net 69 "Net-(J10-PadS21)")
  (net 70 "Net-(J10-PadS22)")
  (net 71 "Net-(J10-PadS19)")
  (net 72 "Net-(J10-PadS17)")
  (net 73 "Net-(J10-PadS18)")
  (net 74 "Net-(J10-PadS20)")
  (net 75 "Net-(J10-PadS16)")
  (net 76 "VCC3V3_USB")
  (net 77 "GNDD")
  (net 78 "Net-(D9-A)")
  (net 79 "Net-(D10-A)")
  (net 80 "SDA_FTDI")
  (net 81 "SCL_FTDI")
  (net 82 "Net-(D11-A)")
  (net 83 "Net-(D15-A)")
  (net 84 "Net-(D16-A)")
  (net 85 "Net-(D17-A)")
  (net 86 "Net-(D18-A)")
  (net 87 "Net-(D19-A)")
  (net 88 "unconnected-(D20-IO2-Pad2)")
  (net 89 "unconnected-(J2-PadMP)")
  (net 90 "/Power Cycling & Current Measurement/V_ADC1")
  (net 91 "unconnected-(J3-PadMP)")
  (net 92 "unconnected-(J10-P19-PadP19{slash}20)")
  (net 93 "Net-(QA1-G)")
  (net 94 "Net-(QA2-G)")
  (net 95 "Net-(QA3-G)")
  (net 96 "Net-(QA4-G)")
  (net 97 "Net-(QA5-G)")
  (net 98 "Net-(QB1-G)")
  (net 99 "SDA_CON")
  (net 100 "Net-(QB2-G)")
  (net 101 "Net-(QB3-G)")
  (net 102 "Net-(QB4-G)")
  (net 103 "Net-(QB5-G)")
  (net 104 "Net-(U5-REF)")
  (net 105 "Net-(U10-A0)")
  (net 106 "Net-(U10-A1)")
  (net 107 "Net-(U10-A2)")
  (net 108 "Net-(U10-~{INT})")
  (net 109 "Net-(U14-A1)")
  (net 110 "Net-(U14-A0)")
  (net 111 "Net-(U15-FB)")
  (net 112 "Net-(U4-FB)")
  (net 113 "Net-(U1-CC_{1})")
  (net 114 "Net-(U1-CC_{2})")
  (net 115 "Net-(U6-A)")
  (net 116 "Net-(U5-BDBUS1)")
  (net 117 "Net-(U1-SBU_{1})")
  (net 118 "Net-(U1-SBU_{2})")
  (net 119 "unconnected-(U3-NC-Pad4)")
  (net 120 "unconnected-(U4-EN-Pad5)")
  (net 121 "unconnected-(U5-EECS-Pad1)")
  (net 122 "unconnected-(U5-ADBUS4-Pad17)")
  (net 123 "unconnected-(U5-ADBUS5-Pad18)")
  (net 124 "unconnected-(U5-ADBUS6-Pad19)")
  (net 125 "/FTDI/OSCO")
  (net 126 "unconnected-(U5-ADBUS7-Pad20)")
  (net 127 "unconnected-(U5-BDBUS0-Pad22)")
  (net 128 "unconnected-(U5-BDBUS2-Pad24)")
  (net 129 "unconnected-(U5-BDBUS3-Pad25)")
  (net 130 "unconnected-(U5-BDBUS4-Pad26)")
  (net 131 "unconnected-(U5-BDBUS5-Pad27)")
  (net 132 "unconnected-(U5-BDBUS6-Pad28)")
  (net 133 "unconnected-(U5-BDBUS7-Pad29)")
  (net 134 "unconnected-(U5-~{SUSPEND}-Pad30)")
  (net 135 "unconnected-(U5-CDBUS0-Pad32)")
  (net 136 "Net-(FB3-Pad1)")
  (net 137 "Net-(J9-Pad8)")
  (net 138 "unconnected-(U5-CDBUS1-Pad33)")
  (net 139 "unconnected-(U5-CDBUS2-Pad34)")
  (net 140 "unconnected-(U5-CDBUS3-Pad35)")
  (net 141 "unconnected-(U5-CDBUS4-Pad37)")
  (net 142 "unconnected-(U5-CDBUS5-Pad38)")
  (net 143 "unconnected-(U5-CDBUS6-Pad39)")
  (net 144 "Net-(R2-Pad1)")
  (net 145 "LED_DATA")
  (net 146 "unconnected-(U5-CDBUS7-Pad40)")
  (net 147 "Net-(R74-Pad2)")
  (net 148 "unconnected-(U5-DDBUS0-Pad42)")
  (net 149 "unconnected-(U5-DDBUS1-Pad46)")
  (net 150 "unconnected-(U5-DDBUS2-Pad47)")
  (net 151 "unconnected-(U5-DDBUS3-Pad48)")
  (net 152 "unconnected-(U5-DDBUS4-Pad49)")
  (net 153 "unconnected-(U5-DDBUS5-Pad51)")
  (net 154 "unconnected-(U5-DDBUS6-Pad52)")
  (net 155 "unconnected-(U5-DDBUS7-Pad53)")
  (net 156 "unconnected-(U5-~{PWR_{EN}}-Pad54)")
  (net 157 "unconnected-(U5-EEDATA-Pad55)")
  (net 158 "unconnected-(U5-EECLK-Pad56)")
  (net 159 "unconnected-(U6-NC-Pad1)")
  (net 160 "unconnected-(U10-P5-Pad10)")
  (net 161 "unconnected-(U10-P6-Pad11)")
  (net 162 "unconnected-(U10-P7-Pad12)")
  (net 163 "unconnected-(U14-CH5-Pad6)")
  (net 164 "unconnected-(U14-CH6-Pad7)")
  (net 165 "unconnected-(U15-EN-Pad5)")
  (net 166 "unconnected-(S1-Pad1)")
  (net 167 "unconnected-(S1-SH-PadS1)")

  (footprint "antmicro-footprints:R_0402_1005Metric" (layer "F.Cu")
    (at 167.95 96.5 90)
    (descr "Resistor SMD 0402")
    (tags "resistor SMD 0402")
    (property "Author" "Antmicro")
    (property "Current" "1A")
    (property "DNP" "DNP")
    (property "License" "Apache-2.0")
    (property "MPN" "ERJ2GE0R00X")
    (property "Manufacturer" "Panasonic")
    (property "Sheetfile" "pow-cycl-curr-meas.kicad_sch")
    (property "Sheetname" "Power Cycling & Current Measurement")
    (property "Tolerance" "")
    (property "Val" "0R")
    (property "dnp" "")
    (property "exclude_from_bom" "")
    (property "ki_description" "SMD Chip Resistor, Jumper, 0 ohm, 100 mW, 0402 [1005 Metric], Thick Film, General Purpose")
    (property "ki_keywords" "0402, SMT, RESISTOR, PASSIVE")
    (attr smd exclude_from_bom)
    (fp_text reference "R15" (at 0.85 0.45 90) (layer "F.SilkS")
        (effects (font (size 0.7 0.7) (thickness 0.15)) (justify left bottom))
    )
    (fp_text value "R_0R_0402" (at -1.011843 1.772047 90) (layer "F.Fab")
        (effects (font (size 0.7 0.7) (thickness 0.15)) (justify left bottom))
    )
    (fp_text user "${REFERENCE}" (at -0.95 3.168 90) (layer "F.Fab") hide
        (effects (font (size 0.7 0.7) (thickness 0.15)) (justify left bottom))
    )
    (fp_text user "License: Apache-2.0" (at -0.95 5.169 90) (layer "F.Fab") hide
        (effects (font (size 0.7 0.7) (thickness 0.15)) (justify left bottom))
    )
    (fp_text user "Author: Antmicro" (at -0.95 4.169 90) (layer "F.Fab") hide
        (effects (font (size 0.7 0.7) (thickness 0.15)) (justify left bottom))
    )
    (fp_rect (start -0.925 -0.47) (end 0.925 0.47)
      (stroke (width 0.05) (type default)) (fill none) (layer "F.CrtYd"))
    (fp_rect (start -0.5 -0.25) (end 0.5 0.25)
      (stroke (width 0.15) (type solid)) (fill none) (layer "F.Fab"))
    (pad "1" smd roundrect (at -0.48 0 90) (size 0.59 0.64) (layers "F.Cu" "F.Paste" "F.Mask") (roundrect_rratio 0.25)
      (net 1 "VCC3V3") (pintype "passive"))
    (pad "2" smd roundrect (at 0.48 0 90) (size 0.59 0.64) (layers "F.Cu" "F.Paste" "F.Mask") (roundrect_rratio 0.25)
      (net 106 "Net-(U10-A1)") (pintype "passive"))
  )

  (footprint "antmicro-footprints:R_0402_1005Metric" (layer "F.Cu")
    (at 169.05 96.5 -90)
    (descr "Resistor SMD 0402")
    (tags "resistor SMD 0402")
    (property "Author" "Antmicro")
    (property "Current" "1A")
    (property "License" "Apache-2.0")
    (property "MPN" "ERJ2GE0R00X")
    (property "Manufacturer" "Panasonic")
    (property "Sheetfile" "pow-cycl-curr-meas.kicad_sch")
    (property "Sheetname" "Power Cycling & Current Measurement")
    (property "Tolerance" "")
    (property "Val" "0R")
    (property "ki_description" "SMD Chip Resistor, Jumper, 0 ohm, 100 mW, 0402 [1005 Metric], Thick Film, General Purpose")
    (property "ki_keywords" "0402, SMT, RESISTOR, PASSIVE")
    (attr smd)
    (fp_text reference "R16" (at -0.85 -0.4 -90) (layer "F.SilkS")
        (effects (font (size 0.7 0.7) (thickness 0.15)) (justify left bottom))
    )
    (fp_text value "R_0R_0402" (at -1.011843 1.772047 -90) (layer "F.Fab")
        (effects (font (size 0.7 0.7) (thickness 0.15)) (justify left bottom))
    )
    (fp_text user "Author: Antmicro" (at -0.95 4.169 -90) (layer "F.Fab") hide
        (effects (font (size 0.7 0.7) (thickness 0.15)) (justify left bottom))
    )
    (fp_text user "${REFERENCE}" (at -0.95 3.168 -90) (layer "F.Fab") hide
        (effects (font (size 0.7 0.7) (thickness 0.15)) (justify left bottom))
    )
    (fp_text user "License: Apache-2.0" (at -0.95 5.169 -90) (layer "F.Fab") hide
        (effects (font (size 0.7 0.7) (thickness 0.15)) (justify left bottom))
    )
    (fp_rect (start -0.925 -0.47) (end 0.925 0.47)
      (stroke (width 0.05) (type default)) (fill none) (layer "F.CrtYd"))
    (fp_rect (start -0.5 -0.25) (end 0.5 0.25)
      (stroke (width 0.15) (type solid)) (fill none) (layer "F.Fab"))
    (pad "1" smd roundrect (at -0.48 0 270) (size 0.59 0.64) (layers "F.Cu" "F.Paste" "F.Mask") (roundrect_rratio 0.25)
      (net 106 "Net-(U10-A1)") (pintype "passive"))
    (pad "2" smd roundrect (at 0.48 0 270) (size 0.59 0.64) (layers "F.Cu" "F.Paste" "F.Mask") (roundrect_rratio 0.25)
      (net 4 "GND") (pintype "passive"))
  )

  (footprint "antmicro-footprints:R_0402_1005Metric" (layer "F.Cu")
    (at 146.75 101 90)
    (descr "Resistor SMD 0402")
    (tags "resistor SMD 0402")
    (property "Author" "Antmicro")
    (property "Current" "1A")
    (property "DNP" "DNP")
    (property "License" "Apache-2.0")
    (property "MPN" "ERJ2GE0R00X")
    (property "Manufacturer" "Panasonic")
    (property "Sheetfile" "pow-cycl-curr-meas.kicad_sch")
    (property "Sheetname" "Power Cycling & Current Measurement")
    (property "Tolerance" "")
    (property "Val" "0R")
    (property "dnp" "")
    (property "exclude_from_bom" "")
    (property "ki_description" "SMD Chip Resistor, Jumper, 0 ohm, 100 mW, 0402 [1005 Metric], Thick Film, General Purpose")
    (property "ki_keywords" "0402, SMT, RESISTOR, PASSIVE")
    (attr smd exclude_from_bom)
    (fp_text reference "R32" (at -3.1 0.45 90) (layer "F.SilkS")
        (effects (font (size 0.7 0.7) (thickness 0.15)) (justify left bottom))
    )
    (fp_text value "R_0R_0402" (at -1.011843 1.772047 90) (layer "F.Fab")
        (effects (font (size 0.7 0.7) (thickness 0.15)) (justify left bottom))
    )
    (fp_text user "License: Apache-2.0" (at -0.95 5.169 90) (layer "F.Fab") hide
        (effects (font (size 0.7 0.7) (thickness 0.15)) (justify left bottom))
    )
    (fp_text user "${REFERENCE}" (at -0.95 3.168 90) (layer "F.Fab") hide
        (effects (font (size 0.7 0.7) (thickness 0.15)) (justify left bottom))
    )
    (fp_text user "Author: Antmicro" (at -0.95 4.169 90) (layer "F.Fab") hide
        (effects (font (size 0.7 0.7) (thickness 0.15)) (justify left bottom))
    )
    (fp_rect (start -0.925 -0.47) (end 0.925 0.47)
      (stroke (width 0.05) (type default)) (fill none) (layer "F.CrtYd"))
    (fp_rect (start -0.5 -0.25) (end 0.5 0.25)
      (stroke (width 0.15) (type solid)) (fill none) (layer "F.Fab"))
    (pad "1" smd roundrect (at -0.48 0 90) (size 0.59 0.64) (layers "F.Cu" "F.Paste" "F.Mask") (roundrect_rratio 0.25)
      (net 1 "VCC3V3") (pintype "passive"))
    (pad "2" smd roundrect (at 0.48 0 90) (size 0.59 0.64) (layers "F.Cu" "F.Paste" "F.Mask") (roundrect_rratio 0.25)
      (net 110 "Net-(U14-A0)") (pintype "passive"))
  )

  (footprint "antmicro-footprints:R_0402_1005Metric" (layer "F.Cu")
    (at 148.75 101 -90)
    (descr "Resistor SMD 0402")
    (tags "resistor SMD 0402")
    (property "Author" "Antmicro")
    (property "Current" "1A")
    (property "License" "Apache-2.0")
    (property "MPN" "ERJ2GE0R00X")
    (property "Manufacturer" "Panasonic")
    (property "Sheetfile" "pow-cycl-curr-meas.kicad_sch")
    (property "Sheetname" "Power Cycling & Current Measurement")
    (property "Tolerance" "")
    (property "Val" "0R")
    (property "ki_description" "SMD Chip Resistor, Jumper, 0 ohm, 100 mW, 0402 [1005 Metric], Thick Film, General Purpose")
    (property "ki_keywords" "0402, SMT, RESISTOR, PASSIVE")
    (attr smd)
    (fp_text reference "R33" (at -0.85 -0.3 -90) (layer "F.SilkS")
        (effects (font (size 0.7 0.7) (thickness 0.15)) (justify left bottom))
    )
    (fp_text value "R_0R_0402" (at -1.011843 1.772047 -90) (layer "F.Fab")
        (effects (font (size 0.7 0.7) (thickness 0.15)) (justify left bottom))
    )
    (fp_text user "License: Apache-2.0" (at -0.95 5.169 -90) (layer "F.Fab") hide
        (effects (font (size 0.7 0.7) (thickness 0.15)) (justify left bottom))
    )
    (fp_text user "Author: Antmicro" (at -0.95 4.169 -90) (layer "F.Fab") hide
        (effects (font (size 0.7 0.7) (thickness 0.15)) (justify left bottom))
    )
    (fp_text user "${REFERENCE}" (at -0.95 3.168 -90) (layer "F.Fab") hide
        (effects (font (size 0.7 0.7) (thickness 0.15)) (justify left bottom))
    )
    (fp_rect (start -0.925 -0.47) (end 0.925 0.47)
      (stroke (width 0.05) (type default)) (fill none) (layer "F.CrtYd"))
    (fp_rect (start -0.5 -0.25) (end 0.5 0.25)
      (stroke (width 0.15) (type solid)) (fill none) (layer "F.Fab"))
    (pad "1" smd roundrect (at -0.48 0 270) (size 0.59 0.64) (layers "F.Cu" "F.Paste" "F.Mask") (roundrect_rratio 0.25)
      (net 110 "Net-(U14-A0)") (pintype "passive"))
    (pad "2" smd roundrect (at 0.48 0 270) (size 0.59 0.64) (layers "F.Cu" "F.Paste" "F.Mask") (roundrect_rratio 0.25)
      (net 4 "GND") (pintype "passive"))
  )

  (footprint "antmicro-footprints:TP_SMD_1mm" (layer "F.Cu")
    (at 100.757932 105.326324 90)
    (property "Author" "Antmicro")
    (property "License" "Apache-2.0")
    (property "MPN" "")
    (property "Manufacturer" "")
    (property "Sheetfile" "ftdi-module.kicad_sch")
    (property "Sheetname" "FTDI")
    (property "exclude_from_bom" "")
    (property "ki_description" "Test point 1mm SMD")
    (property "ki_keywords" "TESTPOINT")
    (attr exclude_from_pos_files exclude_from_bom)
    (fp_text reference "3V3" (at 0.676324 -1.057932 180) (layer "F.SilkS")
        (effects (font (size 0.7 0.7) (thickness 0.15)) (justify left bottom))
    )
    (fp_text value "TP_1mm_SMD" (at 0 1.4 90) (layer "F.Fab")
        (effects (font (size 0.7 0.7) (thickness 0.15)) (justify left bottom))
    )
    (fp_text user "Author: Antmicro" (at -0.5 4 90) (layer "F.Fab") hide
        (effects (font (size 0.7 0.7) (thickness 0.15)) (justify left bottom))
    )
    (fp_text user "License: Apache-2.0" (at -0.5 5.2 90) (layer "F.Fab") hide
        (effects (font (size 0.7 0.7) (thickness 0.15)) (justify left bottom))
    )
    (fp_text user "${REFERENCE}" (at -0.5 2.8 90) (layer "F.Fab") hide
        (effects (font (size 0.7 0.7) (thickness 0.15)) (justify left bottom))
    )
    (fp_circle (center 0 0) (end 0.6 0)
      (stroke (width 0.05) (type default)) (fill none) (layer "F.CrtYd"))
    (pad "1" smd circle (at 0 0 90) (size 1 1) (layers "F.Cu" "F.Mask")
      (net 1 "VCC3V3") (pinfunction "1") (pintype "passive"))
  )

  (footprint "antmicro-footprints:C_0603_1608Metric" (layer "F.Cu")
    (at 98.75 93.7 180)
    (descr "Capacitor SMD 0603")
    (tags "capacitor 0603")
    (property "Author" "Antmicro")
    (property "Dielectric" "")
    (property "License" "Apache-2.0")
    (property "MPN" "C1608X5R1E106M080AC")
    (property "Manufacturer" "TDK")
    (property "Sheetfile" "daughterboard-supply.kicad_sch")
    (property "Sheetname" "daughterboard-supply")
    (property "Val" "10u")
    (property "Voltage" "25V")
    (property "ki_description" "SMD Multilayer Ceramic Capacitor, 10 µF, 25 V, 0603 [1608 Metric], ± 20%, X5R, C")
    (property "ki_keywords" "0603, SMT, CAPACITOR, PASSIVE, CERAMIC, MLCC")
    (attr smd)
    (fp_text reference "C24" (at -1.25 -1.6) (layer "F.SilkS")
        (effects (font (size 0.7 0.7) (thickness 0.15)) (justify right bottom))
    )
    (fp_text value "C_10u_25V_0603" (at -1.42757 1.770288) (layer "F.Fab")
        (effects (font (size 0.7 0.7) (thickness 0.15)) (justify right bottom))
    )
    (fp_text user "${REFERENCE}" (at -1.682 3.895) (layer "F.Fab") hide
        (effects (font (size 0.7 0.7) (thickness 0.15)) (justify right bottom))
    )
    (fp_text user "Author: Antmicro" (at -1.682 4.894) (layer "F.Fab") hide
        (effects (font (size 0.7 0.7) (thickness 0.15)) (justify right bottom))
    )
    (fp_text user "License: Apache-2.0" (at -1.682 5.895) (layer "F.Fab") hide
        (effects (font (size 0.7 0.7) (thickness 0.15)) (justify right bottom))
    )
    (fp_line (start -0.15 -0.4) (end 0.15 -0.4)
      (stroke (width 0.15) (type solid)) (layer "F.SilkS"))
    (fp_line (start -0.15 0.4) (end 0.15 0.4)
      (stroke (width 0.15) (type solid)) (layer "F.SilkS"))
    (fp_rect (start -1.25 -0.65) (end 1.25 0.65)
      (stroke (width 0.05) (type solid)) (fill none) (layer "F.CrtYd"))
    (fp_rect (start -0.8 -0.4) (end 0.8 0.4)
      (stroke (width 0.15) (type solid)) (fill none) (layer "F.Fab"))
    (pad "1" smd roundrect (at -0.7 0 180) (size 0.8 1) (layers "F.Cu" "F.Paste" "F.Mask") (roundrect_rratio 0.2)
      (net 4 "GND") (pintype "passive"))
    (pad "2" smd roundrect (at 0.7 0 180) (size 0.8 1) (layers "F.Cu" "F.Paste" "F.Mask") (roundrect_rratio 0.2)
      (net 11 "VCC12V0") (pintype "passive"))
  )

  (footprint "antmicro-footprints:C_0402_1005Metric" (layer "F.Cu")
    (at 99.75 88.6 180)
    (descr "Capacitor SMD 0402")
    (tags "capacitor SMD 0402")
    (property "Author" "Antmicro")
    (property "Dielectric" "X5R")
    (property "License" "Apache-2.0")
    (property "MPN" "GRM155R61H104KE14D")
    (property "Manufacturer" "Murata")
    (property "Sheetfile" "daughterboard-supply.kicad_sch")
    (property "Sheetname" "daughterboard-supply")
    (property "Val" "100n")
    (property "Voltage" "50V")
    (property "ki_description" "SMD Multilayer Ceramic Capacitor, 0.1 µF, 50 V, 0402 [1005 Metric], ± 10%, X5R, GRM Series")
    (property "ki_keywords" "0402, SMT, CAPACITOR, PASSIVE, CERAMIC, MLCC")
    (attr smd)
    (fp_text reference "C25" (at -3.15 -0.45) (layer "F.SilkS")
        (effects (font (size 0.7 0.7) (thickness 0.15)) (justify right bottom))
    )
    (fp_text value "C_100n_0402" (at -1.022927 2.155213) (layer "F.Fab")
        (effects (font (size 0.7 0.7) (thickness 0.15)) (justify right bottom))
    )
    (fp_text user "License: Apache-2.0" (at -0.939 5.799) (layer "F.Fab") hide
        (effects (font (size 0.7 0.7) (thickness 0.15)) (justify right bottom))
    )
    (fp_text user "${REFERENCE}" (at -0.939 4.599) (layer "F.Fab") hide
        (effects (font (size 0.7 0.7) (thickness 0.15)) (justify right bottom))
    )
    (fp_text user "Author: Antmicro" (at -0.939 3.399) (layer "F.Fab") hide
        (effects (font (size 0.7 0.7) (thickness 0.15)) (justify right bottom))
    )
    (fp_rect (start -0.925 -0.47) (end 0.925 0.47)
      (stroke (width 0.05) (type default)) (fill none) (layer "F.CrtYd"))
    (fp_line (start -0.494 -0.25) (end 0.504 -0.25)
      (stroke (width 0.15) (type solid)) (layer "F.Fab"))
    (fp_line (start -0.494 0.248) (end -0.494 -0.25)
      (stroke (width 0.15) (type solid)) (layer "F.Fab"))
    (fp_line (start 0.504 -0.25) (end 0.504 0.248)
      (stroke (width 0.15) (type solid)) (layer "F.Fab"))
    (fp_line (start 0.504 0.248) (end -0.494 0.248)
      (stroke (width 0.15) (type solid)) (layer "F.Fab"))
    (pad "1" smd roundrect (at -0.48 0 180) (size 0.59 0.64) (layers "F.Cu" "F.Paste" "F.Mask") (roundrect_rratio 0.25)
      (net 12 "Net-(U15-BST)") (pintype "passive"))
    (pad "2" smd roundrect (at 0.48 0 180) (size 0.59 0.64) (layers "F.Cu" "F.Paste" "F.Mask") (roundrect_rratio 0.25)
      (net 13 "Net-(U15-SW)") (pintype "passive"))
  )

  (footprint "antmicro-footprints:C_0603_1608Metric" (layer "F.Cu")
    (at 97.5 88.35 180)
    (descr "Capacitor SMD 0603")
    (tags "capacitor 0603")
    (property "Author" "Antmicro")
    (property "Dielectric" "")
    (property "License" "Apache-2.0")
    (property "MPN" "GRM188R60J226MEA0D")
    (property "Manufacturer" "Murata")
    (property "Sheetfile" "daughterboard-supply.kicad_sch")
    (property "Sheetname" "daughterboard-supply")
    (property "Val" "22u")
    (property "Voltage" "")
    (property "ki_description" "SMD Multilayer Ceramic Capacitor, 22 µF, 6.3 V, 0603 [1608 Metric], ± 20%, X5R, GRM Series")
    (property "ki_keywords" "0603, SMT, CAPACITOR, PASSIVE, CERAMIC, MLCC")
    (attr smd)
    (fp_text reference "C26" (at -4.35 1.15) (layer "F.SilkS")
        (effects (font (size 0.7 0.7) (thickness 0.15)) (justify right bottom))
    )
    (fp_text value "C_22u_0603" (at -1.42757 1.770288) (layer "F.Fab")
        (effects (font (size 0.7 0.7) (thickness 0.15)) (justify right bottom))
    )
    (fp_text user "${REFERENCE}" (at -1.682 3.895) (layer "F.Fab") hide
        (effects (font (size 0.7 0.7) (thickness 0.15)) (justify right bottom))
    )
    (fp_text user "Author: Antmicro" (at -1.682 4.894) (layer "F.Fab") hide
        (effects (font (size 0.7 0.7) (thickness 0.15)) (justify right bottom))
    )
    (fp_text user "License: Apache-2.0" (at -1.682 5.895) (layer "F.Fab") hide
        (effects (font (size 0.7 0.7) (thickness 0.15)) (justify right bottom))
    )
    (fp_line (start -0.15 -0.4) (end 0.15 -0.4)
      (stroke (width 0.15) (type solid)) (layer "F.SilkS"))
    (fp_line (start -0.15 0.4) (end 0.15 0.4)
      (stroke (width 0.15) (type solid)) (layer "F.SilkS"))
    (fp_rect (start -1.25 -0.65) (end 1.25 0.65)
      (stroke (width 0.05) (type solid)) (fill none) (layer "F.CrtYd"))
    (fp_rect (start -0.8 -0.4) (end 0.8 0.4)
      (stroke (width 0.15) (type solid)) (fill none) (layer "F.Fab"))
    (pad "1" smd roundrect (at -0.7 0 180) (size 0.8 1) (layers "F.Cu" "F.Paste" "F.Mask") (roundrect_rratio 0.2)
      (net 4 "GND") (pintype "passive"))
    (pad "2" smd roundrect (at 0.7 0 180) (size 0.8 1) (layers "F.Cu" "F.Paste" "F.Mask") (roundrect_rratio 0.2)
      (net 2 "VCC5V0") (pintype "passive"))
  )

  (footprint "antmicro-footprints:C_0603_1608Metric" (layer "F.Cu")
    (at 97.5 86.85 180)
    (descr "Capacitor SMD 0603")
    (tags "capacitor 0603")
    (property "Author" "Antmicro")
    (property "Dielectric" "")
    (property "License" "Apache-2.0")
    (property "MPN" "GRM188R60J226MEA0D")
    (property "Manufacturer" "Murata")
    (property "Sheetfile" "daughterboard-supply.kicad_sch")
    (property "Sheetname" "daughterboard-supply")
    (property "Val" "22u")
    (property "Voltage" "")
    (property "ki_description" "SMD Multilayer Ceramic Capacitor, 22 µF, 6.3 V, 0603 [1608 Metric], ± 20%, X5R, GRM Series")
    (property "ki_keywords" "0603, SMT, CAPACITOR, PASSIVE, CERAMIC, MLCC")
    (attr smd)
    (fp_text reference "C27" (at -1.15 0.9) (layer "F.SilkS")
        (effects (font (size 0.7 0.7) (thickness 0.15)) (justify right bottom))
    )
    (fp_text value "C_22u_0603" (at -1.42757 1.770288) (layer "F.Fab")
        (effects (font (size 0.7 0.7) (thickness 0.15)) (justify right bottom))
    )
    (fp_text user "Author: Antmicro" (at -1.682 4.894) (layer "F.Fab") hide
        (effects (font (size 0.7 0.7) (thickness 0.15)) (justify right bottom))
    )
    (fp_text user "${REFERENCE}" (at -1.682 3.895) (layer "F.Fab") hide
        (effects (font (size 0.7 0.7) (thickness 0.15)) (justify right bottom))
    )
    (fp_text user "License: Apache-2.0" (at -1.682 5.895) (layer "F.Fab") hide
        (effects (font (size 0.7 0.7) (thickness 0.15)) (justify right bottom))
    )
    (fp_line (start -0.15 -0.4) (end 0.15 -0.4)
      (stroke (width 0.15) (type solid)) (layer "F.SilkS"))
    (fp_line (start -0.15 0.4) (end 0.15 0.4)
      (stroke (width 0.15) (type solid)) (layer "F.SilkS"))
    (fp_rect (start -1.25 -0.65) (end 1.25 0.65)
      (stroke (width 0.05) (type solid)) (fill none) (layer "F.CrtYd"))
    (fp_rect (start -0.8 -0.4) (end 0.8 0.4)
      (stroke (width 0.15) (type solid)) (fill none) (layer "F.Fab"))
    (pad "1" smd roundrect (at -0.7 0 180) (size 0.8 1) (layers "F.Cu" "F.Paste" "F.Mask") (roundrect_rratio 0.2)
      (net 4 "GND") (pintype "passive"))
    (pad "2" smd roundrect (at 0.7 0 180) (size 0.8 1) (layers "F.Cu" "F.Paste" "F.Mask") (roundrect_rratio 0.2)
      (net 2 "VCC5V0") (pintype "passive"))
  )

  (footprint "antmicro-footprints:Conn_JST_SH_1x4_BM04B-SRSS-TB-LF-SN" (layer "F.Cu")
    (at 185.625 94.95)
    (property "Author" "Antmicro")
    (property "DNP" "DNP")
    (property "License" "Apache-2.0")
    (property "MPN" "BM04B-SRSS-TB(LF)(SN) ")
    (property "Manufacturer" "JST Automotive Connectors")
    (property "Sheetfile" "d1600e-psu-breakout-board.kicad_sch")
    (property "Sheetname" "")
    (property "dnp" "")
    (property "exclude_from_bom" "")
    (property "ki_description" "Pin Header, Top Entry, Wire-to-Board, 1 mm, 1 Rows, 4 Contacts, Surface Mount, SR")
    (property "ki_keywords" "VERTICAL, SMT, WIRE-BOARD, CONNECTOR")
    (attr smd exclude_from_bom)
    (fp_text reference "J2" (at 3.025 0.6 90) (layer "F.SilkS")
        (effects (font (size 0.7 0.7) (thickness 0.15)) (justify left bottom))
    )
    (fp_text value "JST_SH_1x4_BM04B-SRSS-TB-LF-SN" (at -3.25 5) (layer "F.Fab")
        (effects (font (size 0.7 0.7) (thickness 0.15)) (justify left bottom))
    )
    (fp_text user "License: Apache-2.0" (at -3.25 9.4) (layer "F.Fab") hide
        (effects (font (size 0.7 0.7) (thickness 0.15)) (justify left bottom))
    )
    (fp_text user "${REFERENCE}" (at -3.25 8.2) (layer "F.Fab") hide
        (effects (font (size 0.7 0.7) (thickness 0.15)) (justify left bottom))
    )
    (fp_text user "Author: Antmicro" (at -3.25 7) (layer "F.Fab") hide
        (effects (font (size 0.7 0.7) (thickness 0.15)) (justify left bottom))
    )
    (fp_line (start -1.125 -2.999) (end -1.125 -2.201)
      (stroke (width 0.15) (type solid)) (layer "F.SilkS"))
    (fp_line (start -1.125 2.999) (end -1.125 2.201)
      (stroke (width 0.15) (type solid)) (layer "F.SilkS"))
    (fp_line (start -0.251 -2.999) (end -1.125 -2.999)
      (stroke (width 0.15) (type solid)) (layer "F.SilkS"))
    (fp_line (start -0.251 2.999) (end -1.125 2.999)
      (stroke (width 0.15) (type solid)) (layer "F.SilkS"))
    (fp_line (start 1.774 -1.7) (end 1.774 1.702)
      (stroke (width 0.15) (type solid)) (layer "F.SilkS"))
    (fp_circle (center -1.6 -2.1) (end -1.55 -2.1)
      (stroke (width 0.15) (type solid)) (fill solid) (layer "F.SilkS"))
    (fp_rect (start -2.05 -3.95) (end 2.05 3.95)
      (stroke (width 0.05) (type solid)) (fill none) (layer "F.CrtYd"))
    (fp_rect (start -1.8 -3) (end 1.8 3)
      (stroke (width 0.15) (type solid)) (fill none) (layer "F.Fab"))
    (pad "1" smd roundrect (at -1.45 -1.5 270) (size 0.6 1.55) (layers "F.Cu" "F.Paste" "F.Mask") (roundrect_rratio 0.25)
      (net 19 "Net-(J2-Pad1)") (pintype "passive"))
    (pad "2" smd roundrect (at -1.45 -0.5 270) (size 0.6 1.55) (layers "F.Cu" "F.Paste" "F.Mask") (roundrect_rratio 0.25)
      (net 18 "SDA") (pintype "passive"))
    (pad "3" smd roundrect (at -1.45 0.5 270) (size 0.6 1.55) (layers "F.Cu" "F.Paste" "F.Mask") (roundrect_rratio 0.25)
      (net 17 "SCL") (pintype "passive"))
    (pad "4" smd roundrect (at -1.45 1.5 270) (size 0.6 1.55) (layers "F.Cu" "F.Paste" "F.Mask") (roundrect_rratio 0.25)
      (net 4 "GND") (pintype "passive"))
    (pad "MP" smd roundrect (at 1.075 -2.8 270) (size 1.2 1.8) (layers "F.Cu" "F.Paste" "F.Mask") (roundrect_rratio 0.25)
      (net 89 "unconnected-(J2-PadMP)") (pintype "passive+no_connect"))
    (pad "MP" smd roundrect (at 1.075 2.8 270) (size 1.2 1.8) (layers "F.Cu" "F.Paste" "F.Mask") (roundrect_rratio 0.25)
      (net 89 "unconnected-(J2-PadMP)") (pintype "passive+no_connect"))
  )

  (footprint "antmicro-footprints:L_WE-LHMI-5030" (layer "F.Cu")
    (at 93.25 90.1 90)
    (property "Author" "Antmicro")
    (property "IMax" "4.1A")
    (property "ISat" "5.45A")
    (property "License" "Apache-2.0")
    (property "MPN" "74437336033")
    (property "Manufacturer" "Würth Elektronik")
    (property "Sheetfile" "daughterboard-supply.kicad_sch")
    (property "Sheetname" "daughterboard-supply")
    (property "Size" "5.2x5.2")
    (property "Val" "3u3/4.1A")
    (property "ki_description" "Power Inductor (SMT), 3.3 µH, 4.1 A, Shielded, 8.4 A, WE-LHMI")
    (property "ki_keywords" "SMT, INDUCTOR, PASSIVE")
    (attr smd)
    (fp_text reference "L2" (at 3.25 -2.7) (layer "F.SilkS")
        (effects (font (size 0.7 0.7) (thickness 0.15)) (justify left bottom))
    )
    (fp_text value "L_3u3_4.1A_WE-LHMI-5030" (at 0 3.9 270) (layer "F.Fab")
        (effects (font (size 0.7 0.7) (thickness 0.15)) (justify left bottom))
    )
    (fp_text user "Author: Antmicro" (at -3.5 5.9 90) (layer "F.Fab") hide
        (effects (font (size 0.7 0.7) (thickness 0.15)) (justify left bottom))
    )
    (fp_text user "${REFERENCE}" (at -3.5 7.1 90) (layer "F.Fab") hide
        (effects (font (size 0.7 0.7) (thickness 0.15)) (justify left bottom))
    )
    (fp_text user "License: Apache-2.0" (at -3.5 8.3 90) (layer "F.Fab") hide
        (effects (font (size 0.7 0.7) (thickness 0.15)) (justify left bottom))
    )
    (fp_line (start -2.725 -1.6125) (end -2.725 -1.125)
      (stroke (width 0.15) (type solid)) (layer "F.SilkS"))
    (fp_line (start -2.725 1.6125) (end -2.725 1.125)
      (stroke (width 0.15) (type solid)) (layer "F.SilkS"))
    (fp_line (start -1.6 -2.725) (end 1.6 -2.725)
      (stroke (width 0.15) (type solid)) (layer "F.SilkS"))
    (fp_line (start 1.6 2.725) (end -1.6 2.725)
      (stroke (width 0.15) (type solid)) (layer "F.SilkS"))
    (fp_line (start 2.725 -1.6125) (end 2.725 -1.125)
      (stroke (width 0.15) (type solid)) (layer "F.SilkS"))
    (fp_line (start 2.725 1.6125) (end 2.725 1.125)
      (stroke (width 0.15) (type solid)) (layer "F.SilkS"))
    (fp_arc (start -2.725 -1.6125) (mid -2.392906 -2.401745) (end -1.6 -2.725)
      (stroke (width 0.15) (type solid)) (layer "F.SilkS"))
    (fp_arc (start -1.6 2.725) (mid -2.392906 2.401745) (end -2.725 1.6125)
      (stroke (width 0.15) (type solid)) (layer "F.SilkS"))
    (fp_arc (start 1.6 -2.725) (mid 2.392906 -2.401745) (end 2.725 -1.6125)
      (stroke (width 0.15) (type solid)) (layer "F.SilkS"))
    (fp_arc (start 2.725 1.6125) (mid 2.392906 2.401745) (end 1.6 2.725)
      (stroke (width 0.15) (type solid)) (layer "F.SilkS"))
    (fp_line (start -3.5 1.15) (end -3.5 -1.15)
      (stroke (width 0.05) (type solid)) (layer "F.CrtYd"))
    (fp_line (start -3.1 -2.85) (end 3.1 -2.85)
      (stroke (width 0.05) (type solid)) (layer "F.CrtYd"))
    (fp_line (start -3.1 -1.15) (end -3.5 -1.15)
      (stroke (width 0.05) (type solid)) (layer "F.CrtYd"))
    (fp_line (start -3.1 -1.15) (end -3.1 -2.85)
      (stroke (width 0.05) (type solid)) (layer "F.CrtYd"))
    (fp_line (start -3.1 1.15) (end -3.5 1.15)
      (stroke (width 0.05) (type solid)) (layer "F.CrtYd"))
    (fp_line (start -3.1 2.85) (end -3.1 1.15)
      (stroke (width 0.05) (type solid)) (layer "F.CrtYd"))
    (fp_line (start 3.1 -2.85) (end 3.1 -1.15)
      (stroke (width 0.05) (type solid)) (layer "F.CrtYd"))
    (fp_line (start 3.1 -1.15) (end 3.5 -1.15)
      (stroke (width 0.05) (type solid)) (layer "F.CrtYd"))
    (fp_line (start 3.1 1.15) (end 3.1 2.85)
      (stroke (width 0.05) (type solid)) (layer "F.CrtYd"))
    (fp_line (start 3.1 1.15) (end 3.5 1.15)
      (stroke (width 0.05) (type solid)) (layer "F.CrtYd"))
    (fp_line (start 3.1 2.85) (end -3.1 2.85)
      (stroke (width 0.05) (type solid)) (layer "F.CrtYd"))
    (fp_line (start 3.5 -1.15) (end 3.5 1.15)
      (stroke (width 0.05) (type solid)) (layer "F.CrtYd"))
    (fp_rect (start -2.85 -2.6) (end 2.85 2.6)
      (stroke (width 0.15) (type solid)) (fill none) (layer "F.Fab"))
    (pad "1" smd roundrect (at -2.25 0 270) (size 2 1.8) (layers "F.Cu" "F.Paste" "F.Mask") (roundrect_rratio 0.1)
      (net 13 "Net-(U15-SW)") (pintype "passive"))
    (pad "2" smd roundrect (at 2.25 0 90) (size 2 1.8) (layers "F.Cu" "F.Paste" "F.Mask") (roundrect_rratio 0.1)
      (net 2 "VCC5V0") (pintype "passive"))
  )

  (footprint "antmicro-footprints:SOT-23-3" (layer "F.Cu")
    (at 112.5 86.8)
    (property "Author" "Antmicro")
    (property "License" "Apache-2.0")
    (property "MPN" "2N7002")
    (property "Manufacturer" "ON Semiconductor")
    (property "Sheetfile" "power-switch.kicad_sch")
    (property "Sheetname" "Power switch 1")
    (property "ki_description" "Power MOSFET, N Channel, 60 V, 115 mA, 1.2 ohm, SOT-23, Surface Mount")
    (property "ki_keywords" "SMT, TRANSISTOR, SEMICONDUCTOR, NMOS")
    (attr smd)
    (fp_text reference "Q6" (at 0.8 2.4) (layer "F.SilkS")
        (effects (font (size 0.7 0.7) (thickness 0.15)) (justify left bottom))
    )
    (fp_text value "2N7002_SOT-23-3" (at -1.9 2.7) (layer "F.Fab")
        (effects (font (size 0.7 0.7) (thickness 0.15)) (justify left bottom))
    )
    (fp_text user "${REFERENCE}" (at -1.837 4) (layer "F.Fab") hide
        (effects (font (size 0.7 0.7) (thickness 0.15)) (justify left bottom))
    )
    (fp_text user "License: Apache-2.0" (at -1.8 6.8) (layer "F.Fab") hide
        (effects (font (size 0.7 0.7) (thickness 0.15)) (justify left bottom))
    )
    (fp_text user "Author: Antmicro" (at -1.837 5.3) (layer "F.Fab") hide
        (effects (font (size 0.7 0.7) (thickness 0.15)) (justify left bottom))
    )
    (fp_line (start -1.45 -1.35) (end -0.85 -1.35)
      (stroke (width 0.15) (type solid)) (layer "F.SilkS"))
    (fp_line (start -0.85 -1.35) (end -0.7 -1.5)
      (stroke (width 0.15) (type solid)) (layer "F.SilkS"))
    (fp_line (start -0.7 1.5) (end -0.7 1.35)
      (stroke (width 0.15) (type solid)) (layer "F.SilkS"))
    (fp_line (start 0.7 -1.5) (end -0.7 -1.5)
      (stroke (width 0.15) (type solid)) (layer "F.SilkS"))
    (fp_line (start 0.7 -0.4) (end 0.7 -1.5)
      (stroke (width 0.15) (type solid)) (layer "F.SilkS"))
    (fp_line (start 0.7 0.4) (end 0.7 1.5)
      (stroke (width 0.15) (type solid)) (layer "F.SilkS"))
    (fp_line (start 0.7 1.5) (end -0.7 1.5)
      (stroke (width 0.15) (type solid)) (layer "F.SilkS"))
    (fp_line (start -1.75 -0.5) (end -1.75 -1.4)
      (stroke (width 0.05) (type solid)) (layer "F.CrtYd"))
    (fp_line (start -1.75 0.5) (end -0.85 0.5)
      (stroke (width 0.05) (type solid)) (layer "F.CrtYd"))
    (fp_line (start -1.75 1.4) (end -1.75 0.5)
      (stroke (width 0.05) (type solid)) (layer "F.CrtYd"))
    (fp_line (start -0.9 -1.6) (end -0.9 -1.4)
      (stroke (width 0.05) (type solid)) (layer "F.CrtYd"))
    (fp_line (start -0.9 -1.6) (end 0.825 -1.6)
      (stroke (width 0.05) (type solid)) (layer "F.CrtYd"))
    (fp_line (start -0.9 -1.4) (end -1.75 -1.4)
      (stroke (width 0.05) (type solid)) (layer "F.CrtYd"))
    (fp_line (start -0.85 -0.5) (end -1.75 -0.5)
      (stroke (width 0.05) (type solid)) (layer "F.CrtYd"))
    (fp_line (start -0.85 0.5) (end -0.85 -0.5)
      (stroke (width 0.05) (type solid)) (layer "F.CrtYd"))
    (fp_line (start -0.85 1.4) (end -1.75 1.4)
      (stroke (width 0.05) (type solid)) (layer "F.CrtYd"))
    (fp_line (start -0.85 1.65) (end -0.85 1.4)
      (stroke (width 0.05) (type solid)) (layer "F.CrtYd"))
    (fp_line (start 0.825 -1.6) (end 0.825 -0.45)
      (stroke (width 0.05) (type solid)) (layer "F.CrtYd"))
    (fp_line (start 0.825 -0.45) (end 1.75 -0.45)
      (stroke (width 0.05) (type solid)) (layer "F.CrtYd"))
    (fp_line (start 0.85 0.45) (end 0.85 1.65)
      (stroke (width 0.05) (type solid)) (layer "F.CrtYd"))
    (fp_line (start 0.85 1.65) (end -0.85 1.65)
      (stroke (width 0.05) (type solid)) (layer "F.CrtYd"))
    (fp_line (start 1.75 -0.45) (end 1.75 0.45)
      (stroke (width 0.05) (type solid)) (layer "F.CrtYd"))
    (fp_line (start 1.75 0.45) (end 0.85 0.45)
      (stroke (width 0.05) (type solid)) (layer "F.CrtYd"))
    (fp_line (start -0.712 -1.325) (end -0.712 1.523)
      (stroke (width 0.15) (type solid)) (layer "F.Fab"))
    (fp_line (start -0.712 1.519) (end 0.688 1.519)
      (stroke (width 0.15) (type solid)) (layer "F.Fab"))
    (fp_line (start -0.437 -1.526) (end -0.712 -1.325)
      (stroke (width 0.15) (type solid)) (layer "F.Fab"))
    (fp_line (start -0.437 -1.526) (end 0.688 -1.526)
      (stroke (width 0.15) (type solid)) (layer "F.Fab"))
    (fp_line (start 0.688 1.519) (end 0.688 -1.52)
      (stroke (width 0.15) (type solid)) (layer "F.Fab"))
    (pad "1" smd roundrect (at -1.1 -0.951) (size 1 0.6) (layers "F.Cu" "F.Paste" "F.Mask") (roundrect_rratio 0.15)
      (net 23 "/Power Cycling & Current Measurement/PC_1") (pinfunction "G") (pintype "passive"))
    (pad "2" smd roundrect (at -1.1 0.949) (size 1 0.6) (layers "F.Cu" "F.Paste" "F.Mask") (roundrect_rratio 0.15)
      (net 4 "GND") (pinfunction "S") (pintype "passive"))
    (pad "3" smd roundrect (at 1.1 -0.0005) (size 1 0.6) (layers "F.Cu" "F.Paste" "F.Mask") (roundrect_rratio 0.15)
      (net 83 "Net-(D15-A)") (pinfunction "D") (pintype "passive"))
  )

  (footprint "antmicro-footprints:SOT-23-3" (layer "F.Cu")
    (at 129.8 86.9)
    (property "Author" "Antmicro")
    (property "License" "Apache-2.0")
    (property "MPN" "2N7002")
    (property "Manufacturer" "ON Semiconductor")
    (property "Sheetfile" "power-switch.kicad_sch")
    (property "Sheetname" "Power switch 2")
    (property "ki_description" "Power MOSFET, N Channel, 60 V, 115 mA, 1.2 ohm, SOT-23, Surface Mount")
    (property "ki_keywords" "SMT, TRANSISTOR, SEMICONDUCTOR, NMOS")
    (attr smd)
    (fp_text reference "Q7" (at 0.55 2.5) (layer "F.SilkS")
        (effects (font (size 0.7 0.7) (thickness 0.15)) (justify left bottom))
    )
    (fp_text value "2N7002_SOT-23-3" (at -1.9 2.7) (layer "F.Fab")
        (effects (font (size 0.7 0.7) (thickness 0.15)) (justify left bottom))
    )
    (fp_text user "Author: Antmicro" (at -1.837 5.3) (layer "F.Fab") hide
        (effects (font (size 0.7 0.7) (thickness 0.15)) (justify left bottom))
    )
    (fp_text user "License: Apache-2.0" (at -1.8 6.8) (layer "F.Fab") hide
        (effects (font (size 0.7 0.7) (thickness 0.15)) (justify left bottom))
    )
    (fp_text user "${REFERENCE}" (at -1.837 4) (layer "F.Fab") hide
        (effects (font (size 0.7 0.7) (thickness 0.15)) (justify left bottom))
    )
    (fp_line (start -1.45 -1.35) (end -0.85 -1.35)
      (stroke (width 0.15) (type solid)) (layer "F.SilkS"))
    (fp_line (start -0.85 -1.35) (end -0.7 -1.5)
      (stroke (width 0.15) (type solid)) (layer "F.SilkS"))
    (fp_line (start -0.7 1.5) (end -0.7 1.35)
      (stroke (width 0.15) (type solid)) (layer "F.SilkS"))
    (fp_line (start 0.7 -1.5) (end -0.7 -1.5)
      (stroke (width 0.15) (type solid)) (layer "F.SilkS"))
    (fp_line (start 0.7 -0.4) (end 0.7 -1.5)
      (stroke (width 0.15) (type solid)) (layer "F.SilkS"))
    (fp_line (start 0.7 0.4) (end 0.7 1.5)
      (stroke (width 0.15) (type solid)) (layer "F.SilkS"))
    (fp_line (start 0.7 1.5) (end -0.7 1.5)
      (stroke (width 0.15) (type solid)) (layer "F.SilkS"))
    (fp_line (start -1.75 -0.5) (end -1.75 -1.4)
      (stroke (width 0.05) (type solid)) (layer "F.CrtYd"))
    (fp_line (start -1.75 0.5) (end -0.85 0.5)
      (stroke (width 0.05) (type solid)) (layer "F.CrtYd"))
    (fp_line (start -1.75 1.4) (end -1.75 0.5)
      (stroke (width 0.05) (type solid)) (layer "F.CrtYd"))
    (fp_line (start -0.9 -1.6) (end -0.9 -1.4)
      (stroke (width 0.05) (type solid)) (layer "F.CrtYd"))
    (fp_line (start -0.9 -1.6) (end 0.825 -1.6)
      (stroke (width 0.05) (type solid)) (layer "F.CrtYd"))
    (fp_line (start -0.9 -1.4) (end -1.75 -1.4)
      (stroke (width 0.05) (type solid)) (layer "F.CrtYd"))
    (fp_line (start -0.85 -0.5) (end -1.75 -0.5)
      (stroke (width 0.05) (type solid)) (layer "F.CrtYd"))
    (fp_line (start -0.85 0.5) (end -0.85 -0.5)
      (stroke (width 0.05) (type solid)) (layer "F.CrtYd"))
    (fp_line (start -0.85 1.4) (end -1.75 1.4)
      (stroke (width 0.05) (type solid)) (layer "F.CrtYd"))
    (fp_line (start -0.85 1.65) (end -0.85 1.4)
      (stroke (width 0.05) (type solid)) (layer "F.CrtYd"))
    (fp_line (start 0.825 -1.6) (end 0.825 -0.45)
      (stroke (width 0.05) (type solid)) (layer "F.CrtYd"))
    (fp_line (start 0.825 -0.45) (end 1.75 -0.45)
      (stroke (width 0.05) (type solid)) (layer "F.CrtYd"))
    (fp_line (start 0.85 0.45) (end 0.85 1.65)
      (stroke (width 0.05) (type solid)) (layer "F.CrtYd"))
    (fp_line (start 0.85 1.65) (end -0.85 1.65)
      (stroke (width 0.05) (type solid)) (layer "F.CrtYd"))
    (fp_line (start 1.75 -0.45) (end 1.75 0.45)
      (stroke (width 0.05) (type solid)) (layer "F.CrtYd"))
    (fp_line (start 1.75 0.45) (end 0.85 0.45)
      (stroke (width 0.05) (type solid)) (layer "F.CrtYd"))
    (fp_line (start -0.712 -1.325) (end -0.712 1.523)
      (stroke (width 0.15) (type solid)) (layer "F.Fab"))
    (fp_line (start -0.712 1.519) (end 0.688 1.519)
      (stroke (width 0.15) (type solid)) (layer "F.Fab"))
    (fp_line (start -0.437 -1.526) (end -0.712 -1.325)
      (stroke (width 0.15) (type solid)) (layer "F.Fab"))
    (fp_line (start -0.437 -1.526) (end 0.688 -1.526)
      (stroke (width 0.15) (type solid)) (layer "F.Fab"))
    (fp_line (start 0.688 1.519) (end 0.688 -1.52)
      (stroke (width 0.15) (type solid)) (layer "F.Fab"))
    (pad "1" smd roundrect (at -1.1 -0.951) (size 1 0.6) (layers "F.Cu" "F.Paste" "F.Mask") (roundrect_rratio 0.15)
      (net 24 "/Power Cycling & Current Measurement/PC_2") (pinfunction "G") (pintype "passive"))
    (pad "2" smd roundrect (at -1.1 0.949) (size 1 0.6) (layers "F.Cu" "F.Paste" "F.Mask") (roundrect_rratio 0.15)
      (net 4 "GND") (pinfunction "S") (pintype "passive"))
    (pad "3" smd roundrect (at 1.1 -0.0005) (size 1 0.6) (layers "F.Cu" "F.Paste" "F.Mask") (roundrect_rratio 0.15)
      (net 84 "Net-(D16-A)") (pinfunction "D") (pintype "passive"))
  )

  (footprint "antmicro-footprints:SOIC-8_3.9x4.9x1.75mm_P1.27mm" (layer "F.Cu")
    (at 114.35 82.05 180)
    (property "Author" "Antmicro")
    (property "License" "Apache-2.0")
    (property "MPN" "TMCS1100A2QDRQ1")
    (property "Manufacturer" "Texas Instruments")
    (property "Sheetfile" "pow-cycl-curr-meas.kicad_sch")
    (property "Sheetname" "Power Cycling & Current Measurement")
    (property "ki_description" "Hall current Sensor/transducer")
    (property "ki_keywords" "SMT, SENSOR, IC, POWER")
    (attr smd)
    (fp_text reference "U8" (at 4.4 1.55) (layer "F.SilkS")
        (effects (font (size 0.7 0.7) (thickness 0.15)) (justify right bottom))
    )
    (fp_text value "TMCS1100A2-Q1" (at 0 3.65) (layer "F.Fab")
        (effects (font (size 0.7 0.7) (thickness 0.15)) (justify right bottom))
    )
    (fp_text user "Author: Antmicro" (at -3.476 6.099) (layer "F.Fab") hide
        (effects (font (size 0.7 0.7) (thickness 0.15)) (justify right bottom))
    )
    (fp_text user "License: Apache-2.0" (at -3.476 5.099) (layer "F.Fab") hide
        (effects (font (size 0.7 0.7) (thickness 0.15)) (justify right bottom))
    )
    (fp_text user "${REFERENCE}" (at -3.476 7.099) (layer "F.Fab") hide
        (effects (font (size 0.7 0.7) (thickness 0.15)) (justify right bottom))
    )
    (fp_line (start -1.95 -2.452) (end 1.95 -2.45)
      (stroke (width 0.15) (type solid)) (layer "F.SilkS"))
    (fp_line (start -1.95 2.45) (end 1.95 2.45)
      (stroke (width 0.15) (type solid)) (layer "F.SilkS"))
    (fp_circle (center -2.4 -2.45) (end -2.35 -2.4)
      (stroke (width 0.15) (type solid)) (fill solid) (layer "F.SilkS"))
    (fp_rect (start -3.625 -2.7) (end 3.625 2.7)
      (stroke (width 0.05) (type solid)) (fill none) (layer "F.CrtYd"))
    (fp_line (start -1.95 -1.18) (end -0.683 -2.452)
      (stroke (width 0.15) (type solid)) (layer "F.Fab"))
    (fp_line (start -1.95 2.45) (end -1.95 -1.18)
      (stroke (width 0.15) (type solid)) (layer "F.Fab"))
    (fp_line (start -0.683 -2.452) (end 1.949 -2.452)
      (stroke (width 0.15) (type solid)) (layer "F.Fab"))
    (fp_line (start 1.949 -2.452) (end 1.949 2.45)
      (stroke (width 0.15) (type solid)) (layer "F.Fab"))
    (fp_line (start 1.949 2.45) (end -1.95 2.45)
      (stroke (width 0.15) (type solid)) (layer "F.Fab"))
    (pad "1" smd roundrect (at -2.714 -1.905 270) (size 0.65 1.525) (layers "F.Cu" "F.Paste" "F.Mask") (roundrect_rratio 0.25)
      (net 21 "C_MEAS_1") (pinfunction "IN+") (pintype "input"))
    (pad "2" smd roundrect (at -2.714 -0.635 270) (size 0.65 1.525) (layers "F.Cu" "F.Paste" "F.Mask") (roundrect_rratio 0.25)
      (net 21 "C_MEAS_1") (pinfunction "IN+") (pintype "input"))
    (pad "3" smd roundrect (at -2.714 0.632 270) (size 0.65 1.525) (layers "F.Cu" "F.Paste" "F.Mask") (roundrect_rratio 0.25)
      (net 41 "LOAD_1") (pinfunction "IN-") (pintype "input"))
    (pad "4" smd roundrect (at -2.714 1.902 270) (size 0.65 1.525) (layers "F.Cu" "F.Paste" "F.Mask") (roundrect_rratio 0.25)
      (net 41 "LOAD_1") (pinfunction "IN-") (pintype "input"))
    (pad "5" smd roundrect (at 2.712 1.902 270) (size 0.65 1.525) (layers "F.Cu" "F.Paste" "F.Mask") (roundrect_rratio 0.25)
      (net 4 "GND") (pinfunction "GND") (pintype "power_in"))
    (pad "6" smd roundrect (at 2.712 0.632 270) (size 0.65 1.525) (layers "F.Cu" "F.Paste" "F.Mask") (roundrect_rratio 0.25)
      (net 4 "GND") (pinfunction "VREF") (pintype "input"))
    (pad "7" smd roundrect (at 2.712 -0.635 270) (size 0.65 1.525) (layers "F.Cu" "F.Paste" "F.Mask") (roundrect_rratio 0.25)
      (net 46 "/Power Cycling & Current Measurement/C_ADC1") (pinfunction "VOUT") (pintype "output"))
    (pad "8" smd roundrect (at 2.712 -1.905 270) (size 0.65 1.525) (layers "F.Cu" "F.Paste" "F.Mask") (roundrect_rratio 0.25)
      (net 1 "VCC3V3") (pinfunction "VCC") (pintype "power_in"))
  )

  (footprint "antmicro-footprints:R_0402_1005Metric" (layer "F.Cu")
    (at 145.25 98.5 180)
    (descr "Resistor SMD 0402")
    (tags "resistor SMD 0402")
    (property "Author" "Antmicro")
    (property "Current" "1A")
    (property "License" "Apache-2.0")
    (property "MPN" "ERJ2GE0R00X")
    (property "Manufacturer" "Panasonic")
    (property "Sheetfile" "pow-cycl-curr-meas.kicad_sch")
    (property "Sheetname" "Power Cycling & Current Measurement")
    (property "Tolerance" "")
    (property "Val" "0R")
    (property "ki_description" "SMD Chip Resistor, Jumper, 0 ohm, 100 mW, 0402 [1005 Metric], Thick Film, General Purpose")
    (property "ki_keywords" "0402, SMT, RESISTOR, PASSIVE")
    (zone_connect 1)
    (attr smd)
    (fp_text reference "R31" (at 1 0.5 180) (layer "F.SilkS")
        (effects (font (size 0.7 0.7) (thickness 0.15)) (justify left bottom))
    )
    (fp_text value "R_0R_0402" (at -1.011843 1.772047 180) (layer "F.Fab")
        (effects (font (size 0.7 0.7) (thickness 0.15)) (justify left bottom))
    )
    (fp_text user "License: Apache-2.0" (at -0.95 5.169 180) (layer "F.Fab") hide
        (effects (font (size 0.7 0.7) (thickness 0.15)) (justify left bottom))
    )
    (fp_text user "Author: Antmicro" (at -0.95 4.169 180) (layer "F.Fab") hide
        (effects (font (size 0.7 0.7) (thickness 0.15)) (justify left bottom))
    )
    (fp_text user "${REFERENCE}" (at -0.95 3.168 180) (layer "F.Fab") hide
        (effects (font (size 0.7 0.7) (thickness 0.15)) (justify left bottom))
    )
    (fp_rect (start -0.925 -0.47) (end 0.925 0.47)
      (stroke (width 0.05) (type default)) (fill none) (layer "F.CrtYd"))
    (fp_rect (start -0.5 -0.25) (end 0.5 0.25)
      (stroke (width 0.15) (type solid)) (fill none) (layer "F.Fab"))
    (pad "1" smd roundrect (at -0.48 0 180) (size 0.59 0.64) (layers "F.Cu" "F.Paste" "F.Mask") (roundrect_rratio 0.25)
      (net 109 "Net-(U14-A1)") (pintype "passive"))
    (pad "2" smd roundrect (at 0.48 0 180) (size 0.59 0.64) (layers "F.Cu" "F.Paste" "F.Mask") (roundrect_rratio 0.25)
      (net 4 "GND") (pintype "passive"))
  )

  (footprint "antmicro-footprints:R_0402_1005Metric" (layer "F.Cu")
    (at 160.5 87)
    (descr "Resistor SMD 0402")
    (tags "resistor SMD 0402")
    (property "Author" "Antmicro")
    (property "License" "Apache-2.0")
    (property "MPN" "CR0402-FX-1002GLF")
    (property "Manufacturer" "Bourns")
    (property "Sheetfile" "power-switch.kicad_sch")
    (property "Sheetname" "Power switch 4")
    (property "Tolerance" "1%")
    (property "Val" "10k")
    (property "ki_description" "SMD Chip Resistor, 10 kohm, ± 1%, 62.5 mW, 0402 [1005 Metric], Thick Film, General Purpose")
    (property "ki_keywords" "0402, SMT, RESISTOR, PASSIVE")
    (attr smd)
    (fp_text reference "R26" (at -2 0.1) (layer "F.SilkS")
        (effects (font (size 0.7 0.7) (thickness 0.15)))
    )
    (fp_text value "R_10k_0402" (at 0 1.17) (layer "F.Fab") hide
        (effects (font (size 1 1) (thickness 0.15)))
    )
    (fp_text user "Author: Antmicro" (at -0.95 4.169) (layer "F.Fab") hide
        (effects (font (size 0.7 0.7) (thickness 0.15)) (justify left bottom))
    )
    (fp_text user "${REFERENCE}" (at 0 0) (layer "F.Fab")
        (effects (font (size 0.7 0.7) (thickness 0.15)))
    )
    (fp_text user "License: Apache-2.0" (at -0.95 5.169) (layer "F.Fab") hide
        (effects (font (size 0.7 0.7) (thickness 0.15)) (justify left bottom))
    )
    (fp_rect (start -0.925 -0.47) (end 0.925 0.47)
      (stroke (width 0.05) (type default)) (fill none) (layer "F.CrtYd"))
    (fp_rect (start -0.5 -0.25) (end 0.5 0.25)
      (stroke (width 0.15) (type solid)) (fill none) (layer "F.Fab"))
    (pad "1" smd roundrect (at -0.48 0) (size 0.59 0.64) (layers "F.Cu" "F.Paste" "F.Mask") (roundrect_rratio 0.25)
      (net 1 "VCC3V3") (pintype "passive"))
    (pad "2" smd roundrect (at 0.48 0) (size 0.59 0.64) (layers "F.Cu" "F.Paste" "F.Mask") (roundrect_rratio 0.25)
      (net 29 "/Power Cycling & Current Measurement/PC_4") (pintype "passive"))
  )

  (footprint "antmicro-footprints:R_0402_1005Metric" (layer "F.Cu")
    (at 126.9 86.9)
    (descr "Resistor SMD 0402")
    (tags "resistor SMD 0402")
    (property "Author" "Antmicro")
    (property "License" "Apache-2.0")
    (property "MPN" "CR0402-FX-1002GLF")
    (property "Manufacturer" "Bourns")
    (property "Sheetfile" "power-switch.kicad_sch")
    (property "Sheetname" "Power switch 2")
    (property "Tolerance" "1%")
    (property "Val" "10k")
    (property "ki_description" "SMD Chip Resistor, 10 kohm, ± 1%, 62.5 mW, 0402 [1005 Metric], Thick Film, General Purpose")
    (property "ki_keywords" "0402, SMT, RESISTOR, PASSIVE")
    (attr smd)
    (fp_text reference "R21" (at -0.9 1.3) (layer "F.SilkS")
        (effects (font (size 0.7 0.7) (thickness 0.15)) (justify left bottom))
    )
    (fp_text value "R_10k_0402" (at -1.011843 1.772047) (layer "F.Fab")
        (effects (font (size 0.7 0.7) (thickness 0.15)) (justify left bottom))
    )
    (fp_text user "Author: Antmicro" (at -0.95 4.169) (layer "F.Fab") hide
        (effects (font (size 0.7 0.7) (thickness 0.15)) (justify left bottom))
    )
    (fp_text user "${REFERENCE}" (at -0.95 3.168) (layer "F.Fab") hide
        (effects (font (size 0.7 0.7) (thickness 0.15)) (justify left bottom))
    )
    (fp_text user "License: Apache-2.0" (at -0.95 5.169) (layer "F.Fab") hide
        (effects (font (size 0.7 0.7) (thickness 0.15)) (justify left bottom))
    )
    (fp_rect (start -0.925 -0.47) (end 0.925 0.47)
      (stroke (width 0.05) (type default)) (fill none) (layer "F.CrtYd"))
    (fp_rect (start -0.5 -0.25) (end 0.5 0.25)
      (stroke (width 0.15) (type solid)) (fill none) (layer "F.Fab"))
    (pad "1" smd roundrect (at -0.48 0) (size 0.59 0.64) (layers "F.Cu" "F.Paste" "F.Mask") (roundrect_rratio 0.25)
      (net 1 "VCC3V3") (pintype "passive"))
    (pad "2" smd roundrect (at 0.48 0) (size 0.59 0.64) (layers "F.Cu" "F.Paste" "F.Mask") (roundrect_rratio 0.25)
      (net 24 "/Power Cycling & Current Measurement/PC_2") (pintype "passive"))
  )

  (footprint "antmicro-footprints:R_0402_1005Metric" (layer "F.Cu")
    (at 145.75 101 90)
    (descr "Resistor SMD 0402")
    (tags "resistor SMD 0402")
    (property "Author" "Antmicro")
    (property "Current" "1A")
    (property "DNP" "DNP")
    (property "License" "Apache-2.0")
    (property "MPN" "ERJ2GE0R00X")
    (property "Manufacturer" "Panasonic")
    (property "Sheetfile" "pow-cycl-curr-meas.kicad_sch")
    (property "Sheetname" "Power Cycling & Current Measurement")
    (property "Tolerance" "")
    (property "Val" "0R")
    (property "dnp" "")
    (property "exclude_from_bom" "")
    (property "ki_description" "SMD Chip Resistor, Jumper, 0 ohm, 100 mW, 0402 [1005 Metric], Thick Film, General Purpose")
    (property "ki_keywords" "0402, SMT, RESISTOR, PASSIVE")
    (attr smd exclude_from_bom)
    (fp_text reference "R30" (at -3.1 0.4 90) (layer "F.SilkS")
        (effects (font (size 0.7 0.7) (thickness 0.15)) (justify left bottom))
    )
    (fp_text value "R_0R_0402" (at -1.011843 1.772047 90) (layer "F.Fab")
        (effects (font (size 0.7 0.7) (thickness 0.15)) (justify left bottom))
    )
    (fp_text user "${REFERENCE}" (at -0.95 3.168 90) (layer "F.Fab") hide
        (effects (font (size 0.7 0.7) (thickness 0.15)) (justify left bottom))
    )
    (fp_text user "License: Apache-2.0" (at -0.95 5.169 90) (layer "F.Fab") hide
        (effects (font (size 0.7 0.7) (thickness 0.15)) (justify left bottom))
    )
    (fp_text user "Author: Antmicro" (at -0.95 4.169 90) (layer "F.Fab") hide
        (effects (font (size 0.7 0.7) (thickness 0.15)) (justify left bottom))
    )
    (fp_rect (start -0.925 -0.47) (end 0.925 0.47)
      (stroke (width 0.05) (type default)) (fill none) (layer "F.CrtYd"))
    (fp_rect (start -0.5 -0.25) (end 0.5 0.25)
      (stroke (width 0.15) (type solid)) (fill none) (layer "F.Fab"))
    (pad "1" smd roundrect (at -0.48 0 90) (size 0.59 0.64) (layers "F.Cu" "F.Paste" "F.Mask") (roundrect_rratio 0.25)
      (net 1 "VCC3V3") (pintype "passive"))
    (pad "2" smd roundrect (at 0.48 0 90) (size 0.59 0.64) (layers "F.Cu" "F.Paste" "F.Mask") (roundrect_rratio 0.25)
      (net 109 "Net-(U14-A1)") (pintype "passive"))
  )

  (footprint "antmicro-footprints:SOT-23-3" (layer "F.Cu")
    (at 177.65 88.7)
    (property "Author" "Antmicro")
    (property "License" "Apache-2.0")
    (property "MPN" "2N7002")
    (property "Manufacturer" "ON Semiconductor")
    (property "Sheetfile" "power-switch.kicad_sch")
    (property "Sheetname" "Power switch 5")
    (property "ki_description" "Power MOSFET, N Channel, 60 V, 115 mA, 1.2 ohm, SOT-23, Surface Mount")
    (property "ki_keywords" "SMT, TRANSISTOR, SEMICONDUCTOR, NMOS")
    (attr smd)
    (fp_text reference "Q10" (at -3.05 2.95) (layer "F.SilkS")
        (effects (font (size 0.7 0.7) (thickness 0.15)) (justify left bottom))
    )
    (fp_text value "2N7002_SOT-23-3" (at -1.9 2.7) (layer "F.Fab")
        (effects (font (size 0.7 0.7) (thickness 0.15)) (justify left bottom))
    )
    (fp_text user "${REFERENCE}" (at -1.837 4) (layer "F.Fab") hide
        (effects (font (size 0.7 0.7) (thickness 0.15)) (justify left bottom))
    )
    (fp_text user "Author: Antmicro" (at -1.837 5.3) (layer "F.Fab") hide
        (effects (font (size 0.7 0.7) (thickness 0.15)) (justify left bottom))
    )
    (fp_text user "License: Apache-2.0" (at -1.8 6.8) (layer "F.Fab") hide
        (effects (font (size 0.7 0.7) (thickness 0.15)) (justify left bottom))
    )
    (fp_line (start -1.45 -1.35) (end -0.85 -1.35)
      (stroke (width 0.15) (type solid)) (layer "F.SilkS"))
    (fp_line (start -0.85 -1.35) (end -0.7 -1.5)
      (stroke (width 0.15) (type solid)) (layer "F.SilkS"))
    (fp_line (start -0.7 1.5) (end -0.7 1.35)
      (stroke (width 0.15) (type solid)) (layer "F.SilkS"))
    (fp_line (start 0.7 -1.5) (end -0.7 -1.5)
      (stroke (width 0.15) (type solid)) (layer "F.SilkS"))
    (fp_line (start 0.7 -0.4) (end 0.7 -1.5)
      (stroke (width 0.15) (type solid)) (layer "F.SilkS"))
    (fp_line (start 0.7 0.4) (end 0.7 1.5)
      (stroke (width 0.15) (type solid)) (layer "F.SilkS"))
    (fp_line (start 0.7 1.5) (end -0.7 1.5)
      (stroke (width 0.15) (type solid)) (layer "F.SilkS"))
    (fp_line (start -1.75 -0.5) (end -1.75 -1.4)
      (stroke (width 0.05) (type solid)) (layer "F.CrtYd"))
    (fp_line (start -1.75 0.5) (end -0.85 0.5)
      (stroke (width 0.05) (type solid)) (layer "F.CrtYd"))
    (fp_line (start -1.75 1.4) (end -1.75 0.5)
      (stroke (width 0.05) (type solid)) (layer "F.CrtYd"))
    (fp_line (start -0.9 -1.6) (end -0.9 -1.4)
      (stroke (width 0.05) (type solid)) (layer "F.CrtYd"))
    (fp_line (start -0.9 -1.6) (end 0.825 -1.6)
      (stroke (width 0.05) (type solid)) (layer "F.CrtYd"))
    (fp_line (start -0.9 -1.4) (end -1.75 -1.4)
      (stroke (width 0.05) (type solid)) (layer "F.CrtYd"))
    (fp_line (start -0.85 -0.5) (end -1.75 -0.5)
      (stroke (width 0.05) (type solid)) (layer "F.CrtYd"))
    (fp_line (start -0.85 0.5) (end -0.85 -0.5)
      (stroke (width 0.05) (type solid)) (layer "F.CrtYd"))
    (fp_line (start -0.85 1.4) (end -1.75 1.4)
      (stroke (width 0.05) (type solid)) (layer "F.CrtYd"))
    (fp_line (start -0.85 1.65) (end -0.85 1.4)
      (stroke (width 0.05) (type solid)) (layer "F.CrtYd"))
    (fp_line (start 0.825 -1.6) (end 0.825 -0.45)
      (stroke (width 0.05) (type solid)) (layer "F.CrtYd"))
    (fp_line (start 0.825 -0.45) (end 1.75 -0.45)
      (stroke (width 0.05) (type solid)) (layer "F.CrtYd"))
    (fp_line (start 0.85 0.45) (end 0.85 1.65)
      (stroke (width 0.05) (type solid)) (layer "F.CrtYd"))
    (fp_line (start 0.85 1.65) (end -0.85 1.65)
      (stroke (width 0.05) (type solid)) (layer "F.CrtYd"))
    (fp_line (start 1.75 -0.45) (end 1.75 0.45)
      (stroke (width 0.05) (type solid)) (layer "F.CrtYd"))
    (fp_line (start 1.75 0.45) (end 0.85 0.45)
      (stroke (width 0.05) (type solid)) (layer "F.CrtYd"))
    (fp_line (start -0.712 -1.325) (end -0.712 1.523)
      (stroke (width 0.15) (type solid)) (layer "F.Fab"))
    (fp_line (start -0.712 1.519) (end 0.688 1.519)
      (stroke (width 0.15) (type solid)) (layer "F.Fab"))
    (fp_line (start -0.437 -1.526) (end -0.712 -1.325)
      (stroke (width 0.15) (type solid)) (layer "F.Fab"))
    (fp_line (start -0.437 -1.526) (end 0.688 -1.526)
      (stroke (width 0.15) (type solid)) (layer "F.Fab"))
    (fp_line (start 0.688 1.519) (end 0.688 -1.52)
      (stroke (width 0.15) (type solid)) (layer "F.Fab"))
    (pad "1" smd roundrect (at -1.1 -0.951) (size 1 0.6) (layers "F.Cu" "F.Paste" "F.Mask") (roundrect_rratio 0.15)
      (net 26 "/Power Cycling & Current Measurement/PC_5") (pinfunction "G") (pintype "passive"))
    (pad "2" smd roundrect (at -1.1 0.949) (size 1 0.6) (layers "F.Cu" "F.Paste" "F.Mask") (roundrect_rratio 0.15)
      (net 4 "GND") (pinfunction "S") (pintype "passive"))
    (pad "3" smd roundrect (at 1.1 -0.0005) (size 1 0.6) (layers "F.Cu" "F.Paste" "F.Mask") (roundrect_rratio 0.15)
      (net 87 "Net-(D19-A)") (pinfunction "D") (pintype "passive"))
  )

  (footprint "antmicro-footprints:SOT-23-3" (layer "F.Cu")
    (at 163.35 86.95)
    (property "Author" "Antmicro")
    (property "License" "Apache-2.0")
    (property "MPN" "2N7002")
    (property "Manufacturer" "ON Semiconductor")
    (property "Sheetfile" "power-switch.kicad_sch")
    (property "Sheetname" "Power switch 4")
    (property "ki_description" "Power MOSFET, N Channel, 60 V, 115 mA, 1.2 ohm, SOT-23, Surface Mount")
    (property "ki_keywords" "SMT, TRANSISTOR, SEMICONDUCTOR, NMOS")
    (attr smd)
    (fp_text reference "Q9" (at 0.1 2.6) (layer "F.SilkS")
        (effects (font (size 0.7 0.7) (thickness 0.15)) (justify left bottom))
    )
    (fp_text value "2N7002_SOT-23-3" (at -1.9 2.7) (layer "F.Fab")
        (effects (font (size 0.7 0.7) (thickness 0.15)) (justify left bottom))
    )
    (fp_text user "License: Apache-2.0" (at -1.8 6.8) (layer "F.Fab") hide
        (effects (font (size 0.7 0.7) (thickness 0.15)) (justify left bottom))
    )
    (fp_text user "${REFERENCE}" (at -1.837 4) (layer "F.Fab") hide
        (effects (font (size 0.7 0.7) (thickness 0.15)) (justify left bottom))
    )
    (fp_text user "Author: Antmicro" (at -1.837 5.3) (layer "F.Fab") hide
        (effects (font (size 0.7 0.7) (thickness 0.15)) (justify left bottom))
    )
    (fp_line (start -1.45 -1.35) (end -0.85 -1.35)
      (stroke (width 0.15) (type solid)) (layer "F.SilkS"))
    (fp_line (start -0.85 -1.35) (end -0.7 -1.5)
      (stroke (width 0.15) (type solid)) (layer "F.SilkS"))
    (fp_line (start -0.7 1.5) (end -0.7 1.35)
      (stroke (width 0.15) (type solid)) (layer "F.SilkS"))
    (fp_line (start 0.7 -1.5) (end -0.7 -1.5)
      (stroke (width 0.15) (type solid)) (layer "F.SilkS"))
    (fp_line (start 0.7 -0.4) (end 0.7 -1.5)
      (stroke (width 0.15) (type solid)) (layer "F.SilkS"))
    (fp_line (start 0.7 0.4) (end 0.7 1.5)
      (stroke (width 0.15) (type solid)) (layer "F.SilkS"))
    (fp_line (start 0.7 1.5) (end -0.7 1.5)
      (stroke (width 0.15) (type solid)) (layer "F.SilkS"))
    (fp_line (start -1.75 -0.5) (end -1.75 -1.4)
      (stroke (width 0.05) (type solid)) (layer "F.CrtYd"))
    (fp_line (start -1.75 0.5) (end -0.85 0.5)
      (stroke (width 0.05) (type solid)) (layer "F.CrtYd"))
    (fp_line (start -1.75 1.4) (end -1.75 0.5)
      (stroke (width 0.05) (type solid)) (layer "F.CrtYd"))
    (fp_line (start -0.9 -1.6) (end -0.9 -1.4)
      (stroke (width 0.05) (type solid)) (layer "F.CrtYd"))
    (fp_line (start -0.9 -1.6) (end 0.825 -1.6)
      (stroke (width 0.05) (type solid)) (layer "F.CrtYd"))
    (fp_line (start -0.9 -1.4) (end -1.75 -1.4)
      (stroke (width 0.05) (type solid)) (layer "F.CrtYd"))
    (fp_line (start -0.85 -0.5) (end -1.75 -0.5)
      (stroke (width 0.05) (type solid)) (layer "F.CrtYd"))
    (fp_line (start -0.85 0.5) (end -0.85 -0.5)
      (stroke (width 0.05) (type solid)) (layer "F.CrtYd"))
    (fp_line (start -0.85 1.4) (end -1.75 1.4)
      (stroke (width 0.05) (type solid)) (layer "F.CrtYd"))
    (fp_line (start -0.85 1.65) (end -0.85 1.4)
      (stroke (width 0.05) (type solid)) (layer "F.CrtYd"))
    (fp_line (start 0.825 -1.6) (end 0.825 -0.45)
      (stroke (width 0.05) (type solid)) (layer "F.CrtYd"))
    (fp_line (start 0.825 -0.45) (end 1.75 -0.45)
      (stroke (width 0.05) (type solid)) (layer "F.CrtYd"))
    (fp_line (start 0.85 0.45) (end 0.85 1.65)
      (stroke (width 0.05) (type solid)) (layer "F.CrtYd"))
    (fp_line (start 0.85 1.65) (end -0.85 1.65)
      (stroke (width 0.05) (type solid)) (layer "F.CrtYd"))
    (fp_line (start 1.75 -0.45) (end 1.75 0.45)
      (stroke (width 0.05) (type solid)) (layer "F.CrtYd"))
    (fp_line (start 1.75 0.45) (end 0.85 0.45)
      (stroke (width 0.05) (type solid)) (layer "F.CrtYd"))
    (fp_line (start -0.712 -1.325) (end -0.712 1.523)
      (stroke (width 0.15) (type solid)) (layer "F.Fab"))
    (fp_line (start -0.712 1.519) (end 0.688 1.519)
      (stroke (width 0.15) (type solid)) (layer "F.Fab"))
    (fp_line (start -0.437 -1.526) (end -0.712 -1.325)
      (stroke (width 0.15) (type solid)) (layer "F.Fab"))
    (fp_line (start -0.437 -1.526) (end 0.688 -1.526)
      (stroke (width 0.15) (type solid)) (layer "F.Fab"))
    (fp_line (start 0.688 1.519) (end 0.688 -1.52)
      (stroke (width 0.15) (type solid)) (layer "F.Fab"))
    (pad "1" smd roundrect (at -1.1 -0.951) (size 1 0.6) (layers "F.Cu" "F.Paste" "F.Mask") (roundrect_rratio 0.15)
      (net 29 "/Power Cycling & Current Measurement/PC_4") (pinfunction "G") (pintype "passive"))
    (pad "2" smd roundrect (at -1.1 0.949) (size 1 0.6) (layers "F.Cu" "F.Paste" "F.Mask") (roundrect_rratio 0.15)
      (net 4 "GND") (pinfunction "S") (pintype "passive"))
    (pad "3" smd roundrect (at 1.1 -0.0005) (size 1 0.6) (layers "F.Cu" "F.Paste" "F.Mask") (roundrect_rratio 0.15)
      (net 85 "Net-(D17-A)") (pinfunction "D") (pintype "passive"))
  )

  (footprint "antmicro-footprints:SOT-23-3" (layer "F.Cu")
    (at 146.4 86.95)
    (property "Author" "Antmicro")
    (property "License" "Apache-2.0")
    (property "MPN" "2N7002")
    (property "Manufacturer" "ON Semiconductor")
    (property "Sheetfile" "power-switch.kicad_sch")
    (property "Sheetname" "Power switch 3")
    (property "ki_description" "Power MOSFET, N Channel, 60 V, 115 mA, 1.2 ohm, SOT-23, Surface Mount")
    (property "ki_keywords" "SMT, TRANSISTOR, SEMICONDUCTOR, NMOS")
    (attr smd)
    (fp_text reference "Q8" (at 0.5 2.6) (layer "F.SilkS")
        (effects (font (size 0.7 0.7) (thickness 0.15)) (justify left bottom))
    )
    (fp_text value "2N7002_SOT-23-3" (at -1.9 2.7) (layer "F.Fab")
        (effects (font (size 0.7 0.7) (thickness 0.15)) (justify left bottom))
    )
    (fp_text user "Author: Antmicro" (at -1.837 5.3) (layer "F.Fab") hide
        (effects (font (size 0.7 0.7) (thickness 0.15)) (justify left bottom))
    )
    (fp_text user "License: Apache-2.0" (at -1.8 6.8) (layer "F.Fab") hide
        (effects (font (size 0.7 0.7) (thickness 0.15)) (justify left bottom))
    )
    (fp_text user "${REFERENCE}" (at -1.837 4) (layer "F.Fab") hide
        (effects (font (size 0.7 0.7) (thickness 0.15)) (justify left bottom))
    )
    (fp_line (start -1.45 -1.35) (end -0.85 -1.35)
      (stroke (width 0.15) (type solid)) (layer "F.SilkS"))
    (fp_line (start -0.85 -1.35) (end -0.7 -1.5)
      (stroke (width 0.15) (type solid)) (layer "F.SilkS"))
    (fp_line (start -0.7 1.5) (end -0.7 1.35)
      (stroke (width 0.15) (type solid)) (layer "F.SilkS"))
    (fp_line (start 0.7 -1.5) (end -0.7 -1.5)
      (stroke (width 0.15) (type solid)) (layer "F.SilkS"))
    (fp_line (start 0.7 -0.4) (end 0.7 -1.5)
      (stroke (width 0.15) (type solid)) (layer "F.SilkS"))
    (fp_line (start 0.7 0.4) (end 0.7 1.5)
      (stroke (width 0.15) (type solid)) (layer "F.SilkS"))
    (fp_line (start 0.7 1.5) (end -0.7 1.5)
      (stroke (width 0.15) (type solid)) (layer "F.SilkS"))
    (fp_line (start -1.75 -0.5) (end -1.75 -1.4)
      (stroke (width 0.05) (type solid)) (layer "F.CrtYd"))
    (fp_line (start -1.75 0.5) (end -0.85 0.5)
      (stroke (width 0.05) (type solid)) (layer "F.CrtYd"))
    (fp_line (start -1.75 1.4) (end -1.75 0.5)
      (stroke (width 0.05) (type solid)) (layer "F.CrtYd"))
    (fp_line (start -0.9 -1.6) (end -0.9 -1.4)
      (stroke (width 0.05) (type solid)) (layer "F.CrtYd"))
    (fp_line (start -0.9 -1.6) (end 0.825 -1.6)
      (stroke (width 0.05) (type solid)) (layer "F.CrtYd"))
    (fp_line (start -0.9 -1.4) (end -1.75 -1.4)
      (stroke (width 0.05) (type solid)) (layer "F.CrtYd"))
    (fp_line (start -0.85 -0.5) (end -1.75 -0.5)
      (stroke (width 0.05) (type solid)) (layer "F.CrtYd"))
    (fp_line (start -0.85 0.5) (end -0.85 -0.5)
      (stroke (width 0.05) (type solid)) (layer "F.CrtYd"))
    (fp_line (start -0.85 1.4) (end -1.75 1.4)
      (stroke (width 0.05) (type solid)) (layer "F.CrtYd"))
    (fp_line (start -0.85 1.65) (end -0.85 1.4)
      (stroke (width 0.05) (type solid)) (layer "F.CrtYd"))
    (fp_line (start 0.825 -1.6) (end 0.825 -0.45)
      (stroke (width 0.05) (type solid)) (layer "F.CrtYd"))
    (fp_line (start 0.825 -0.45) (end 1.75 -0.45)
      (stroke (width 0.05) (type solid)) (layer "F.CrtYd"))
    (fp_line (start 0.85 0.45) (end 0.85 1.65)
      (stroke (width 0.05) (type solid)) (layer "F.CrtYd"))
    (fp_line (start 0.85 1.65) (end -0.85 1.65)
      (stroke (width 0.05) (type solid)) (layer "F.CrtYd"))
    (fp_line (start 1.75 -0.45) (end 1.75 0.45)
      (stroke (width 0.05) (type solid)) (layer "F.CrtYd"))
    (fp_line (start 1.75 0.45) (end 0.85 0.45)
      (stroke (width 0.05) (type solid)) (layer "F.CrtYd"))
    (fp_line (start -0.712 -1.325) (end -0.712 1.523)
      (stroke (width 0.15) (type solid)) (layer "F.Fab"))
    (fp_line (start -0.712 1.519) (end 0.688 1.519)
      (stroke (width 0.15) (type solid)) (layer "F.Fab"))
    (fp_line (start -0.437 -1.526) (end -0.712 -1.325)
      (stroke (width 0.15) (type solid)) (layer "F.Fab"))
    (fp_line (start -0.437 -1.526) (end 0.688 -1.526)
      (stroke (width 0.15) (type solid)) (layer "F.Fab"))
    (fp_line (start 0.688 1.519) (end 0.688 -1.52)
      (stroke (width 0.15) (type solid)) (layer "F.Fab"))
    (pad "1" smd roundrect (at -1.1 -0.951) (size 1 0.6) (layers "F.Cu" "F.Paste" "F.Mask") (roundrect_rratio 0.15)
      (net 30 "/Power Cycling & Current Measurement/PC_3") (pinfunction "G") (pintype "passive"))
    (pad "2" smd roundrect (at -1.1 0.949) (size 1 0.6) (layers "F.Cu" "F.Paste" "F.Mask") (roundrect_rratio 0.15)
      (net 4 "GND") (pinfunction "S") (pintype "passive"))
    (pad "3" smd roundrect (at 1.1 -0.0005) (size 1 0.6) (layers "F.Cu" "F.Paste" "F.Mask") (roundrect_rratio 0.15)
      (net 86 "Net-(D18-A)") (pinfunction "D") (pintype "passive"))
  )

  (footprint "antmicro-footprints:C_0402_1005Metric" (layer "F.Cu")
    (at 143.9775 84.5775 -90)
    (descr "Capacitor SMD 0402")
    (tags "capacitor SMD 0402")
    (property "Author" "Antmicro")
    (property "Dielectric" "X5R")
    (property "License" "Apache-2.0")
    (property "MPN" "GRM155R61H104KE14D")
    (property "Manufacturer" "Murata")
    (property "Sheetfile" "pow-cycl-curr-meas.kicad_sch")
    (property "Sheetname" "Power Cycling & Current Measurement")
    (property "Val" "100n")
    (property "Voltage" "50V")
    (property "ki_description" "SMD Multilayer Ceramic Capacitor, 0.1 µF, 50 V, 0402 [1005 Metric], ± 10%, X5R, GRM Series")
    (property "ki_keywords" "0402, SMT, CAPACITOR, PASSIVE, CERAMIC, MLCC")
    (attr smd)
    (fp_text reference "C32" (at 1.0225 0.8775 90) (layer "F.SilkS")
        (effects (font (size 0.7 0.7) (thickness 0.15)))
    )
    (fp_text value "C_100n_0402" (at 0 1.17 90) (layer "F.Fab") hide
        (effects (font (size 1 1) (thickness 0.15)))
    )
    (fp_text user "Author: Antmicro" (at -0.939 3.399 -90) (layer "F.Fab") hide
        (effects (font (size 0.7 0.7) (thickness 0.15)) (justify left bottom))
    )
    (fp_text user "${REFERENCE}" (at 0 0 90) (layer "F.Fab")
        (effects (font (size 0.7 0.7) (thickness 0.15)))
    )
    (fp_text user "License: Apache-2.0" (at -0.939 5.799 -90) (layer "F.Fab") hide
        (effects (font (size 0.7 0.7) (thickness 0.15)) (justify left bottom))
    )
    (fp_rect (start -0.925 -0.47) (end 0.925 0.47)
      (stroke (width 0.05) (type default)) (fill none) (layer "F.CrtYd"))
    (fp_line (start -0.494 -0.25) (end 0.504 -0.25)
      (stroke (width 0.15) (type solid)) (layer "F.Fab"))
    (fp_line (start -0.494 0.248) (end -0.494 -0.25)
      (stroke (width 0.15) (type solid)) (layer "F.Fab"))
    (fp_line (start 0.504 -0.25) (end 0.504 0.248)
      (stroke (width 0.15) (type solid)) (layer "F.Fab"))
    (fp_line (start 0.504 0.248) (end -0.494 0.248)
      (stroke (width 0.15) (type solid)) (layer "F.Fab"))
    (pad "1" smd roundrect (at -0.48 0 270) (size 0.59 0.64) (layers "F.Cu" "F.Paste" "F.Mask") (roundrect_rratio 0.25)
      (net 1 "VCC3V3") (pintype "passive"))
    (pad "2" smd roundrect (at 0.48 0 270) (size 0.59 0.64) (layers "F.Cu" "F.Paste" "F.Mask") (roundrect_rratio 0.25)
      (net 4 "GND") (pintype "passive"))
  )

  (footprint "antmicro-footprints:SOIC-8_3.9x4.9x1.75mm_P1.27mm" (layer "F.Cu")
    (at 131.67 82.15 180)
    (property "Author" "Antmicro")
    (property "License" "Apache-2.0")
    (property "MPN" "TMCS1100A2QDRQ1")
    (property "Manufacturer" "Texas Instruments")
    (property "Sheetfile" "pow-cycl-curr-meas.kicad_sch")
    (property "Sheetname" "Power Cycling & Current Measurement")
    (property "ki_description" "Hall current Sensor/transducer")
    (property "ki_keywords" "SMT, SENSOR, IC, POWER")
    (attr smd)
    (fp_text reference "U9" (at 1.42 2.8) (layer "F.SilkS")
        (effects (font (size 0.7 0.7) (thickness 0.15)) (justify right bottom))
    )
    (fp_text value "TMCS1100A2-Q1" (at 0 3.65) (layer "F.Fab")
        (effects (font (size 0.7 0.7) (thickness 0.15)) (justify right bottom))
    )
    (fp_text user "${REFERENCE}" (at -3.476 7.099) (layer "F.Fab") hide
        (effects (font (size 0.7 0.7) (thickness 0.15)) (justify right bottom))
    )
    (fp_text user "License: Apache-2.0" (at -3.476 5.099) (layer "F.Fab") hide
        (effects (font (size 0.7 0.7) (thickness 0.15)) (justify right bottom))
    )
    (fp_text user "Author: Antmicro" (at -3.476 6.099) (layer "F.Fab") hide
        (effects (font (size 0.7 0.7) (thickness 0.15)) (justify right bottom))
    )
    (fp_line (start -1.95 -2.452) (end 1.95 -2.45)
      (stroke (width 0.15) (type solid)) (layer "F.SilkS"))
    (fp_line (start -1.95 2.45) (end 1.95 2.45)
      (stroke (width 0.15) (type solid)) (layer "F.SilkS"))
    (fp_circle (center -2.4 -2.45) (end -2.35 -2.4)
      (stroke (width 0.15) (type solid)) (fill solid) (layer "F.SilkS"))
    (fp_rect (start -3.625 -2.7) (end 3.625 2.7)
      (stroke (width 0.05) (type solid)) (fill none) (layer "F.CrtYd"))
    (fp_line (start -1.95 -1.18) (end -0.683 -2.452)
      (stroke (width 0.15) (type solid)) (layer "F.Fab"))
    (fp_line (start -1.95 2.45) (end -1.95 -1.18)
      (stroke (width 0.15) (type solid)) (layer "F.Fab"))
    (fp_line (start -0.683 -2.452) (end 1.949 -2.452)
      (stroke (width 0.15) (type solid)) (layer "F.Fab"))
    (fp_line (start 1.949 -2.452) (end 1.949 2.45)
      (stroke (width 0.15) (type solid)) (layer "F.Fab"))
    (fp_line (start 1.949 2.45) (end -1.95 2.45)
      (stroke (width 0.15) (type solid)) (layer "F.Fab"))
    (pad "1" smd roundrect (at -2.714 -1.905 270) (size 0.65 1.525) (layers "F.Cu" "F.Paste" "F.Mask") (roundrect_rratio 0.25)
      (net 22 "C_MEAS_2") (pinfunction "IN+") (pintype "input"))
    (pad "2" smd roundrect (at -2.714 -0.635 270) (size 0.65 1.525) (layers "F.Cu" "F.Paste" "F.Mask") (roundrect_rratio 0.25)
      (net 22 "C_MEAS_2") (pinfunction "IN+") (pintype "input"))
    (pad "3" smd roundrect (at -2.714 0.632 270) (size 0.65 1.525) (layers "F.Cu" "F.Paste" "F.Mask") (roundrect_rratio 0.25)
      (net 44 "LOAD_2") (pinfunction "IN-") (pintype "input"))
    (pad "4" smd roundrect (at -2.714 1.902 270) (size 0.65 1.525) (layers "F.Cu" "F.Paste" "F.Mask") (roundrect_rratio 0.25)
      (net 44 "LOAD_2") (pinfunction "IN-") (pintype "input"))
    (pad "5" smd roundrect (at 2.712 1.902 270) (size 0.65 1.525) (layers "F.Cu" "F.Paste" "F.Mask") (roundrect_rratio 0.25)
      (net 4 "GND") (pinfunction "GND") (pintype "power_in"))
    (pad "6" smd roundrect (at 2.712 0.632 270) (size 0.65 1.525) (layers "F.Cu" "F.Paste" "F.Mask") (roundrect_rratio 0.25)
      (net 4 "GND") (pinfunction "VREF") (pintype "input"))
    (pad "7" smd roundrect (at 2.712 -0.635 270) (size 0.65 1.525) (layers "F.Cu" "F.Paste" "F.Mask") (roundrect_rratio 0.25)
      (net 47 "/Power Cycling & Current Measurement/C_ADC2") (pinfunction "VOUT") (pintype "output"))
    (pad "8" smd roundrect (at 2.712 -1.905 270) (size 0.65 1.525) (layers "F.Cu" "F.Paste" "F.Mask") (roundrect_rratio 0.25)
      (net 1 "VCC3V3") (pinfunction "VCC") (pintype "power_in"))
  )

  (footprint "antmicro-footprints:C_0402_1005Metric" (layer "F.Cu")
    (at 160.9 84.55 -90)
    (descr "Capacitor SMD 0402")
    (tags "capacitor SMD 0402")
    (property "Author" "Antmicro")
    (property "Dielectric" "X5R")
    (property "License" "Apache-2.0")
    (property "MPN" "GRM155R61H104KE14D")
    (property "Manufacturer" "Murata")
    (property "Sheetfile" "pow-cycl-curr-meas.kicad_sch")
    (property "Sheetname" "Power Cycling & Current Measurement")
    (property "Val" "100n")
    (property "Voltage" "50V")
    (property "ki_description" "SMD Multilayer Ceramic Capacitor, 0.1 µF, 50 V, 0402 [1005 Metric], ± 10%, X5R, GRM Series")
    (property "ki_keywords" "0402, SMT, CAPACITOR, PASSIVE, CERAMIC, MLCC")
    (attr smd)
    (fp_text reference "C31" (at 0.95 0.9 90) (layer "F.SilkS")
        (effects (font (size 0.7 0.7) (thickness 0.15)))
    )
    (fp_text value "C_100n_0402" (at 0 1.17 90) (layer "F.Fab") hide
        (effects (font (size 1 1) (thickness 0.15)))
    )
    (fp_text user "License: Apache-2.0" (at -0.939 5.799 -90) (layer "F.Fab") hide
        (effects (font (size 0.7 0.7) (thickness 0.15)) (justify left bottom))
    )
    (fp_text user "Author: Antmicro" (at -0.939 3.399 -90) (layer "F.Fab") hide
        (effects (font (size 0.7 0.7) (thickness 0.15)) (justify left bottom))
    )
    (fp_text user "${REFERENCE}" (at 0 0 90) (layer "F.Fab")
        (effects (font (size 0.7 0.7) (thickness 0.15)))
    )
    (fp_rect (start -0.925 -0.47) (end 0.925 0.47)
      (stroke (width 0.05) (type default)) (fill none) (layer "F.CrtYd"))
    (fp_line (start -0.494 -0.25) (end 0.504 -0.25)
      (stroke (width 0.15) (type solid)) (layer "F.Fab"))
    (fp_line (start -0.494 0.248) (end -0.494 -0.25)
      (stroke (width 0.15) (type solid)) (layer "F.Fab"))
    (fp_line (start 0.504 -0.25) (end 0.504 0.248)
      (stroke (width 0.15) (type solid)) (layer "F.Fab"))
    (fp_line (start 0.504 0.248) (end -0.494 0.248)
      (stroke (width 0.15) (type solid)) (layer "F.Fab"))
    (pad "1" smd roundrect (at -0.48 0 270) (size 0.59 0.64) (layers "F.Cu" "F.Paste" "F.Mask") (roundrect_rratio 0.25)
      (net 1 "VCC3V3") (pintype "passive"))
    (pad "2" smd roundrect (at 0.48 0 270) (size 0.59 0.64) (layers "F.Cu" "F.Paste" "F.Mask") (roundrect_rratio 0.25)
      (net 4 "GND") (pintype "passive"))
  )

  (footprint "antmicro-footprints:C_0402_1005Metric" (layer "F.Cu")
    (at 127.32 84.6 -90)
    (descr "Capacitor SMD 0402")
    (tags "capacitor SMD 0402")
    (property "Author" "Antmicro")
    (property "Dielectric" "X5R")
    (property "License" "Apache-2.0")
    (property "MPN" "GRM155R61H104KE14D")
    (property "Manufacturer" "Murata")
    (property "Sheetfile" "pow-cycl-curr-meas.kicad_sch")
    (property "Sheetname" "Power Cycling & Current Measurement")
    (property "Val" "100n")
    (property "Voltage" "50V")
    (property "ki_description" "SMD Multilayer Ceramic Capacitor, 0.1 µF, 50 V, 0402 [1005 Metric], ± 10%, X5R, GRM Series")
    (property "ki_keywords" "0402, SMT, CAPACITOR, PASSIVE, CERAMIC, MLCC")
    (attr smd)
    (fp_text reference "C30" (at 2 0.52 -90) (layer "F.SilkS")
        (effects (font (size 0.7 0.7) (thickness 0.15)) (justify left bottom))
    )
    (fp_text value "C_100n_0402" (at -1.022927 2.155213 -90) (layer "F.Fab")
        (effects (font (size 0.7 0.7) (thickness 0.15)) (justify left bottom))
    )
    (fp_text user "License: Apache-2.0" (at -0.939 5.799 -90) (layer "F.Fab") hide
        (effects (font (size 0.7 0.7) (thickness 0.15)) (justify left bottom))
    )
    (fp_text user "${REFERENCE}" (at -0.939 4.599 -90) (layer "F.Fab") hide
        (effects (font (size 0.7 0.7) (thickness 0.15)) (justify left bottom))
    )
    (fp_text user "Author: Antmicro" (at -0.939 3.399 -90) (layer "F.Fab") hide
        (effects (font (size 0.7 0.7) (thickness 0.15)) (justify left bottom))
    )
    (fp_rect (start -0.925 -0.47) (end 0.925 0.47)
      (stroke (width 0.05) (type default)) (fill none) (layer "F.CrtYd"))
    (fp_line (start -0.494 -0.25) (end 0.504 -0.25)
      (stroke (width 0.15) (type solid)) (layer "F.Fab"))
    (fp_line (start -0.494 0.248) (end -0.494 -0.25)
      (stroke (width 0.15) (type solid)) (layer "F.Fab"))
    (fp_line (start 0.504 -0.25) (end 0.504 0.248)
      (stroke (width 0.15) (type solid)) (layer "F.Fab"))
    (fp_line (start 0.504 0.248) (end -0.494 0.248)
      (stroke (width 0.15) (type solid)) (layer "F.Fab"))
    (pad "1" smd roundrect (at -0.48 0 270) (size 0.59 0.64) (layers "F.Cu" "F.Paste" "F.Mask") (roundrect_rratio 0.25)
      (net 1 "VCC3V3") (pintype "passive"))
    (pad "2" smd roundrect (at 0.48 0 270) (size 0.59 0.64) (layers "F.Cu" "F.Paste" "F.Mask") (roundrect_rratio 0.25)
      (net 4 "GND") (pintype "passive"))
  )

  (footprint "antmicro-footprints:R_0402_1005Metric" (layer "F.Cu")
    (at 171.25 96.5 -90)
    (descr "Resistor SMD 0402")
    (tags "resistor SMD 0402")
    (property "Author" "Antmicro")
    (property "Current" "1A")
    (property "License" "Apache-2.0")
    (property "MPN" "ERJ2GE0R00X")
    (property "Manufacturer" "Panasonic")
    (property "Sheetfile" "pow-cycl-curr-meas.kicad_sch")
    (property "Sheetname" "Power Cycling & Current Measurement")
    (property "Tolerance" "")
    (property "Val" "0R")
    (property "ki_description" "SMD Chip Resistor, Jumper, 0 ohm, 100 mW, 0402 [1005 Metric], Thick Film, General Purpose")
    (property "ki_keywords" "0402, SMT, RESISTOR, PASSIVE")
    (attr smd)
    (fp_text reference "R18" (at -0.85 -0.45 -90) (layer "F.SilkS")
        (effects (font (size 0.7 0.7) (thickness 0.15)) (justify left bottom))
    )
    (fp_text value "R_0R_0402" (at -1.011843 1.772047 -90) (layer "F.Fab")
        (effects (font (size 0.7 0.7) (thickness 0.15)) (justify left bottom))
    )
    (fp_text user "License: Apache-2.0" (at -0.95 5.169 -90) (layer "F.Fab") hide
        (effects (font (size 0.7 0.7) (thickness 0.15)) (justify left bottom))
    )
    (fp_text user "${REFERENCE}" (at -0.95 3.168 -90) (layer "F.Fab") hide
        (effects (font (size 0.7 0.7) (thickness 0.15)) (justify left bottom))
    )
    (fp_text user "Author: Antmicro" (at -0.95 4.169 -90) (layer "F.Fab") hide
        (effects (font (size 0.7 0.7) (thickness 0.15)) (justify left bottom))
    )
    (fp_rect (start -0.925 -0.47) (end 0.925 0.47)
      (stroke (width 0.05) (type default)) (fill none) (layer "F.CrtYd"))
    (fp_rect (start -0.5 -0.25) (end 0.5 0.25)
      (stroke (width 0.15) (type solid)) (fill none) (layer "F.Fab"))
    (pad "1" smd roundrect (at -0.48 0 270) (size 0.59 0.64) (layers "F.Cu" "F.Paste" "F.Mask") (roundrect_rratio 0.25)
      (net 107 "Net-(U10-A2)") (pintype "passive"))
    (pad "2" smd roundrect (at 0.48 0 270) (size 0.59 0.64) (layers "F.Cu" "F.Paste" "F.Mask") (roundrect_rratio 0.25)
      (net 4 "GND") (pintype "passive"))
  )

  (footprint "antmicro-footprints:SOIC-8_3.9x4.9x1.75mm_P1.27mm" (layer "F.Cu")
    (at 148.2775 82.1775 180)
    (property "Author" "Antmicro")
    (property "License" "Apache-2.0")
    (property "MPN" "TMCS1100A2QDRQ1")
    (property "Manufacturer" "Texas Instruments")
    (property "Sheetfile" "pow-cycl-curr-meas.kicad_sch")
    (property "Sheetname" "Power Cycling & Current Measurement")
    (property "ki_description" "Hall current Sensor/transducer")
    (property "ki_keywords" "SMT, SENSOR, IC, POWER")
    (attr smd)
    (fp_text reference "U11" (at 1.4275 2.8275) (layer "F.SilkS")
        (effects (font (size 0.7 0.7) (thickness 0.15)) (justify right bottom))
    )
    (fp_text value "TMCS1100A2-Q1" (at 0 3.65) (layer "F.Fab")
        (effects (font (size 0.7 0.7) (thickness 0.15)) (justify right bottom))
    )
    (fp_text user "${REFERENCE}" (at -3.476 7.099) (layer "F.Fab") hide
        (effects (font (size 0.7 0.7) (thickness 0.15)) (justify right bottom))
    )
    (fp_text user "License: Apache-2.0" (at -3.476 5.099) (layer "F.Fab") hide
        (effects (font (size 0.7 0.7) (thickness 0.15)) (justify right bottom))
    )
    (fp_text user "Author: Antmicro" (at -3.476 6.099) (layer "F.Fab") hide
        (effects (font (size 0.7 0.7) (thickness 0.15)) (justify right bottom))
    )
    (fp_line (start -1.95 -2.452) (end 1.95 -2.45)
      (stroke (width 0.15) (type solid)) (layer "F.SilkS"))
    (fp_line (start -1.95 2.45) (end 1.95 2.45)
      (stroke (width 0.15) (type solid)) (layer "F.SilkS"))
    (fp_circle (center -2.4 -2.45) (end -2.35 -2.4)
      (stroke (width 0.15) (type solid)) (fill solid) (layer "F.SilkS"))
    (fp_rect (start -3.625 -2.7) (end 3.625 2.7)
      (stroke (width 0.05) (type solid)) (fill none) (layer "F.CrtYd"))
    (fp_line (start -1.95 -1.18) (end -0.683 -2.452)
      (stroke (width 0.15) (type solid)) (layer "F.Fab"))
    (fp_line (start -1.95 2.45) (end -1.95 -1.18)
      (stroke (width 0.15) (type solid)) (layer "F.Fab"))
    (fp_line (start -0.683 -2.452) (end 1.949 -2.452)
      (stroke (width 0.15) (type solid)) (layer "F.Fab"))
    (fp_line (start 1.949 -2.452) (end 1.949 2.45)
      (stroke (width 0.15) (type solid)) (layer "F.Fab"))
    (fp_line (start 1.949 2.45) (end -1.95 2.45)
      (stroke (width 0.15) (type solid)) (layer "F.Fab"))
    (pad "1" smd roundrect (at -2.714 -1.905 270) (size 0.65 1.525) (layers "F.Cu" "F.Paste" "F.Mask") (roundrect_rratio 0.25)
      (net 28 "C_MEAS_3") (pinfunction "IN+") (pintype "input"))
    (pad "2" smd roundrect (at -2.714 -0.635 270) (size 0.65 1.525) (layers "F.Cu" "F.Paste" "F.Mask") (roundrect_rratio 0.25)
      (net 28 "C_MEAS_3") (pinfunction "IN+") (pintype "input"))
    (pad "3" smd roundrect (at -2.714 0.632 270) (size 0.65 1.525) (layers "F.Cu" "F.Paste" "F.Mask") (roundrect_rratio 0.25)
      (net 42 "LOAD_3") (pinfunction "IN-") (pintype "input"))
    (pad "4" smd roundrect (at -2.714 1.902 270) (size 0.65 1.525) (layers "F.Cu" "F.Paste" "F.Mask") (roundrect_rratio 0.25)
      (net 42 "LOAD_3") (pinfunction "IN-") (pintype "input"))
    (pad "5" smd roundrect (at 2.712 1.902 270) (size 0.65 1.525) (layers "F.Cu" "F.Paste" "F.Mask") (roundrect_rratio 0.25)
      (net 4 "GND") (pinfunction "GND") (pintype "power_in"))
    (pad "6" smd roundrect (at 2.712 0.632 270) (size 0.65 1.525) (layers "F.Cu" "F.Paste" "F.Mask") (roundrect_rratio 0.25)
      (net 4 "GND") (pinfunction "VREF") (pintype "input"))
    (pad "7" smd roundrect (at 2.712 -0.635 270) (size 0.65 1.525) (layers "F.Cu" "F.Paste" "F.Mask") (roundrect_rratio 0.25)
      (net 48 "/Power Cycling & Current Measurement/C_ADC3") (pinfunction "VOUT") (pintype "output"))
    (pad "8" smd roundrect (at 2.712 -1.905 270) (size 0.65 1.525) (layers "F.Cu" "F.Paste" "F.Mask") (roundrect_rratio 0.25)
      (net 1 "VCC3V3") (pinfunction "VCC") (pintype "power_in"))
  )

  (footprint "antmicro-footprints:R_0402_1005Metric" (layer "F.Cu")
    (at 170.15 96.5 90)
    (descr "Resistor SMD 0402")
    (tags "resistor SMD 0402")
    (property "Author" "Antmicro")
    (property "Current" "1A")
    (property "DNP" "DNP")
    (property "License" "Apache-2.0")
    (property "MPN" "ERJ2GE0R00X")
    (property "Manufacturer" "Panasonic")
    (property "Sheetfile" "pow-cycl-curr-meas.kicad_sch")
    (property "Sheetname" "Power Cycling & Current Measurement")
    (property "Tolerance" "")
    (property "Val" "0R")
    (property "dnp" "")
    (property "exclude_from_bom" "")
    (property "ki_description" "SMD Chip Resistor, Jumper, 0 ohm, 100 mW, 0402 [1005 Metric], Thick Film, General Purpose")
    (property "ki_keywords" "0402, SMT, RESISTOR, PASSIVE")
    (attr smd exclude_from_bom)
    (fp_text reference "R17" (at 0.85 0.45 90) (layer "F.SilkS")
        (effects (font (size 0.7 0.7) (thickness 0.15)) (justify left bottom))
    )
    (fp_text value "R_0R_0402" (at -1.011843 1.772047 90) (layer "F.Fab")
        (effects (font (size 0.7 0.7) (thickness 0.15)) (justify left bottom))
    )
    (fp_text user "Author: Antmicro" (at -0.95 4.169 90) (layer "F.Fab") hide
        (effects (font (size 0.7 0.7) (thickness 0.15)) (justify left bottom))
    )
    (fp_text user "License: Apache-2.0" (at -0.95 5.169 90) (layer "F.Fab") hide
        (effects (font (size 0.7 0.7) (thickness 0.15)) (justify left bottom))
    )
    (fp_text user "${REFERENCE}" (at -0.95 3.168 90) (layer "F.Fab") hide
        (effects (font (size 0.7 0.7) (thickness 0.15)) (justify left bottom))
    )
    (fp_rect (start -0.925 -0.47) (end 0.925 0.47)
      (stroke (width 0.05) (type default)) (fill none) (layer "F.CrtYd"))
    (fp_rect (start -0.5 -0.25) (end 0.5 0.25)
      (stroke (width 0.15) (type solid)) (fill none) (layer "F.Fab"))
    (pad "1" smd roundrect (at -0.48 0 90) (size 0.59 0.64) (layers "F.Cu" "F.Paste" "F.Mask") (roundrect_rratio 0.25)
      (net 1 "VCC3V3") (pintype "passive"))
    (pad "2" smd roundrect (at 0.48 0 90) (size 0.59 0.64) (layers "F.Cu" "F.Paste" "F.Mask") (roundrect_rratio 0.25)
      (net 107 "Net-(U10-A2)") (pintype "passive"))
  )

  (footprint "antmicro-footprints:MOLEX_39288080" (layer "F.Cu")
    (at 145.25 74.7 90)
    (property "Author" "Antmicro")
    (property "License" "Apache-2.0")
    (property "MPN" "39-28-8080")
    (property "Manufacturer" "Molex")
    (property "Sheetfile" "d1600e-psu-breakout-board.kicad_sch")
    (property "Sheetname" "")
    (property "ki_description" "Pin Header, THT, Vertical, UL94V-2, Power, Wire-to-Board, 4.2 mm, 2 Rows, 8 Contacts, Mini-fit Jr, 5566 series")
    (property "ki_keywords" "VERTICAL, THT, HEADER, CONNECTOR, MALE, WIRE-BOARD, POWER")
    (attr through_hole)
    (fp_text reference "J5" (at -2 -2.7 90) (layer "F.SilkS")
        (effects (font (size 0.7 0.7) (thickness 0.15)) (justify left bottom))
    )
    (fp_text value "Molex_Mini-Fit-Jr_2x4_39-28-8080" (at 4.49 11.365 90) (layer "F.Fab")
        (effects (font (size 0.7 0.7) (thickness 0.15)) (justify left bottom))
    )
    (fp_text user "License: Apache-2.0" (at -3.5 14.565 90) (layer "F.Fab") hide
        (effects (font (size 0.7 0.7) (thickness 0.15)) (justify left bottom))
    )
    (fp_text user "PTH D1.40 +/- 0.05" (at -3.5 13.365 90) (layer "F.Fab") hide
        (effects (font (size 0.7 0.7) (thickness 0.15)) (justify left bottom))
    )
    (fp_text user "Author: Antmicro" (at -3.5 16.965 90) (layer "F.Fab") hide
        (effects (font (size 0.7 0.7) (thickness 0.15)) (justify left bottom))
    )
    (fp_text user "${REFERENCE}" (at -3.5 15.765 90) (layer "F.Fab") hide
        (effects (font (size 0.7 0.7) (thickness 0.15)) (justify left bottom))
    )
    (fp_line (start -3.1 8.75) (end -3.1 -0.98)
      (stroke (width 0.15) (type solid)) (layer "F.SilkS"))
    (fp_line (start -1.83 -2.25) (end -3.1 -0.98)
      (stroke (width 0.15) (type solid)) (layer "F.SilkS"))
    (fp_line (start -1.83 -2.25) (end 15.7 -2.25)
      (stroke (width 0.15) (type solid)) (layer "F.SilkS"))
    (fp_line (start -0.4 -3.327) (end 0 -2.627)
      (stroke (width 0.15) (type solid)) (layer "F.SilkS"))
    (fp_line (start 0 -2.627) (end 0.4 -3.327)
      (stroke (width 0.15) (type solid)) (layer "F.SilkS"))
    (fp_line (start 0.4 -3.327) (end -0.4 -3.327)
      (stroke (width 0.15) (type solid)) (layer "F.SilkS"))
    (fp_line (start 15.7 -2.25) (end 15.7 8.75)
      (stroke (width 0.15) (type solid)) (layer "F.SilkS"))
    (fp_line (start 15.7 8.75) (end -3.1 8.75)
      (stroke (width 0.15) (type solid)) (layer "F.SilkS"))
    (fp_circle (center 0 -3) (end 0.05 -3)
      (stroke (width 0.15) (type solid)) (fill solid) (layer "F.SilkS"))
    (fp_circle (center 0 5.5) (end 0.513 5.5)
      (stroke (width 1.0262) (type solid)) (fill none) (layer "B.Mask"))
    (fp_circle (center 4.2 0) (end 4.713 0)
      (stroke (width 1.0262) (type solid)) (fill none) (layer "B.Mask"))
    (fp_circle (center 4.2 5.5) (end 4.713 5.5)
      (stroke (width 1.0262) (type solid)) (fill none) (layer "B.Mask"))
    (fp_circle (center 8.4 0) (end 8.913 0)
      (stroke (width 1.0262) (type solid)) (fill none) (layer "B.Mask"))
    (fp_circle (center 8.4 5.5) (end 8.913 5.5)
      (stroke (width 1.0262) (type solid)) (fill none) (layer "B.Mask"))
    (fp_circle (center 12.6 0) (end 13.113 0)
      (stroke (width 1.0262) (type solid)) (fill none) (layer "B.Mask"))
    (fp_circle (center 12.6 5.5) (end 13.113 5.5)
      (stroke (width 1.0262) (type solid)) (fill none) (layer "B.Mask"))
    (fp_poly
      (pts
        (xy -1.026 -1.026)
        (xy 1.026 -1.026)
        (xy 1.026 1.026)
        (xy -1.026 1.026)
      )

      (stroke (width 0.01) (type solid)) (fill solid) (layer "B.Mask"))
    (fp_circle (center 0 5.5) (end 0.513 5.5)
      (stroke (width 1.0262) (type solid)) (fill none) (layer "F.Mask"))
    (fp_circle (center 4.2 0) (end 4.713 0)
      (stroke (width 1.0262) (type solid)) (fill none) (layer "F.Mask"))
    (fp_circle (center 4.2 5.5) (end 4.713 5.5)
      (stroke (width 1.0262) (type solid)) (fill none) (layer "F.Mask"))
    (fp_circle (center 8.4 0) (end 8.913 0)
      (stroke (width 1.0262) (type solid)) (fill none) (layer "F.Mask"))
    (fp_circle (center 8.4 5.5) (end 8.913 5.5)
      (stroke (width 1.0262) (type solid)) (fill none) (layer "F.Mask"))
    (fp_circle (center 12.6 0) (end 13.113 0)
      (stroke (width 1.0262) (type solid)) (fill none) (layer "F.Mask"))
    (fp_circle (center 12.6 5.5) (end 13.113 5.5)
      (stroke (width 1.0262) (type solid)) (fill none) (layer "F.Mask"))
    (fp_poly
      (pts
        (xy -1.026 -1.026)
        (xy 1.026 -1.026)
        (xy 1.026 1.026)
        (xy -1.026 1.026)
      )

      (stroke (width 0.01) (type solid)) (fill solid) (layer "F.Mask"))
    (fp_rect (start -3.5 -2.7) (end 16.1 9.1)
      (stroke (width 0.05) (type solid)) (fill none) (layer "F.CrtYd"))
    (fp_line (start -3.1 8.75) (end -3.1 -0.98)
      (stroke (width 0.15) (type solid)) (layer "F.Fab"))
    (fp_line (start -1.83 -2.25) (end -3.1 -0.98)
      (stroke (width 0.15) (type solid)) (layer "F.Fab"))
    (fp_line (start -1.83 -2.25) (end 15.7 -2.25)
      (stroke (width 0.15) (type solid)) (layer "F.Fab"))
    (fp_line (start -0.4 -3.327) (end 0 -2.627)
      (stroke (width 0.15) (type solid)) (layer "F.Fab"))
    (fp_line (start 0 -2.627) (end 0.4 -3.327)
      (stroke (width 0.15) (type solid)) (layer "F.Fab"))
    (fp_line (start 0.4 -3.327) (end -0.4 -3.327)
      (stroke (width 0.15) (type solid)) (layer "F.Fab"))
    (fp_line (start 15.7 -2.25) (end 15.7 8.75)
      (stroke (width 0.15) (type solid)) (layer "F.Fab"))
    (fp_line (start 15.7 8.75) (end -3.1 8.75)
      (stroke (width 0.15) (type solid)) (layer "F.Fab"))
    (pad "1" thru_hole rect (at 0 0 90) (size 1.9 1.9) (drill 1.4) (layers "*.Cu")
      (net 4 "GND") (pinfunction "1") (pintype "bidirectional"))
    (pad "2" thru_hole circle (at 4.2 0 90) (size 1.9 1.9) (drill 1.4) (layers "*.Cu")
      (net 4 "GND") (pinfunction "2") (pintype "bidirectional"))
    (pad "3" thru_hole circle (at 8.4 0 90) (size 1.9 1.9) (drill 1.4) (layers "*.Cu")
      (net 4 "GND") (pinfunction "3") (pintype "bidirectional"))
    (pad "4" thru_hole circle (at 12.6 0 90) (size 1.9 1.9) (drill 1.4) (layers "*.Cu")
      (net 4 "GND") (pinfunction "4") (pintype "bidirectional"))
    (pad "5" thru_hole circle (at 0 5.5 90) (size 1.9 1.9) (drill 1.4) (layers "*.Cu")
      (net 42 "LOAD_3") (pinfunction "5") (pintype "bidirectional"))
    (pad "6" thru_hole circle (at 4.2 5.5 90) (size 1.9 1.9) (drill 1.4) (layers "*.Cu")
      (net 42 "LOAD_3") (pinfunction "6") (pintype "bidirectional"))
    (pad "7" thru_hole circle (at 8.4 5.5 90) (size 1.9 1.9) (drill 1.4) (layers "*.Cu")
      (net 42 "LOAD_3") (pinfunction "7") (pintype "bidirectional"))
    (pad "8" thru_hole circle (at 12.6 5.5 90) (size 1.9 1.9) (drill 1.4) (layers "*.Cu")
      (net 42 "LOAD_3") (pinfunction "8") (pintype "bidirectional"))
  )

  (footprint "antmicro-footprints:MOLEX_39288080" (layer "F.Cu")
    (at 128.25 74.7 90)
    (property "Author" "Antmicro")
    (property "License" "Apache-2.0")
    (property "MPN" "39-28-8080")
    (property "Manufacturer" "Molex")
    (property "Sheetfile" "d1600e-psu-breakout-board.kicad_sch")
    (property "Sheetname" "")
    (property "ki_description" "Pin Header, THT, Vertical, UL94V-2, Power, Wire-to-Board, 4.2 mm, 2 Rows, 8 Contacts, Mini-fit Jr, 5566 series")
    (property "ki_keywords" "VERTICAL, THT, HEADER, CONNECTOR, MALE, WIRE-BOARD, POWER")
    (attr through_hole)
    (fp_text reference "J7" (at -1.9 -2.8 90) (layer "F.SilkS")
        (effects (font (size 0.7 0.7) (thickness 0.15)) (justify left bottom))
    )
    (fp_text value "Molex_Mini-Fit-Jr_2x4_39-28-8080" (at 4.49 11.365 90) (layer "F.Fab")
        (effects (font (size 0.7 0.7) (thickness 0.15)) (justify left bottom))
    )
    (fp_text user "PTH D1.40 +/- 0.05" (at -3.5 13.365 90) (layer "F.Fab") hide
        (effects (font (size 0.7 0.7) (thickness 0.15)) (justify left bottom))
    )
    (fp_text user "${REFERENCE}" (at -3.5 15.765 90) (layer "F.Fab") hide
        (effects (font (size 0.7 0.7) (thickness 0.15)) (justify left bottom))
    )
    (fp_text user "License: Apache-2.0" (at -3.5 14.565 90) (layer "F.Fab") hide
        (effects (font (size 0.7 0.7) (thickness 0.15)) (justify left bottom))
    )
    (fp_text user "Author: Antmicro" (at -3.5 16.965 90) (layer "F.Fab") hide
        (effects (font (size 0.7 0.7) (thickness 0.15)) (justify left bottom))
    )
    (fp_line (start -3.1 8.75) (end -3.1 -0.98)
      (stroke (width 0.15) (type solid)) (layer "F.SilkS"))
    (fp_line (start -1.83 -2.25) (end -3.1 -0.98)
      (stroke (width 0.15) (type solid)) (layer "F.SilkS"))
    (fp_line (start -1.83 -2.25) (end 15.7 -2.25)
      (stroke (width 0.15) (type solid)) (layer "F.SilkS"))
    (fp_line (start -0.4 -3.327) (end 0 -2.627)
      (stroke (width 0.15) (type solid)) (layer "F.SilkS"))
    (fp_line (start 0 -2.627) (end 0.4 -3.327)
      (stroke (width 0.15) (type solid)) (layer "F.SilkS"))
    (fp_line (start 0.4 -3.327) (end -0.4 -3.327)
      (stroke (width 0.15) (type solid)) (layer "F.SilkS"))
    (fp_line (start 15.7 -2.25) (end 15.7 8.75)
      (stroke (width 0.15) (type solid)) (layer "F.SilkS"))
    (fp_line (start 15.7 8.75) (end -3.1 8.75)
      (stroke (width 0.15) (type solid)) (layer "F.SilkS"))
    (fp_circle (center 0 -3) (end 0.05 -3)
      (stroke (width 0.15) (type solid)) (fill solid) (layer "F.SilkS"))
    (fp_circle (center 0 5.5) (end 0.513 5.5)
      (stroke (width 1.0262) (type solid)) (fill none) (layer "B.Mask"))
    (fp_circle (center 4.2 0) (end 4.713 0)
      (stroke (width 1.0262) (type solid)) (fill none) (layer "B.Mask"))
    (fp_circle (center 4.2 5.5) (end 4.713 5.5)
      (stroke (width 1.0262) (type solid)) (fill none) (layer "B.Mask"))
    (fp_circle (center 8.4 0) (end 8.913 0)
      (stroke (width 1.0262) (type solid)) (fill none) (layer "B.Mask"))
    (fp_circle (center 8.4 5.5) (end 8.913 5.5)
      (stroke (width 1.0262) (type solid)) (fill none) (layer "B.Mask"))
    (fp_circle (center 12.6 0) (end 13.113 0)
      (stroke (width 1.0262) (type solid)) (fill none) (layer "B.Mask"))
    (fp_circle (center 12.6 5.5) (end 13.113 5.5)
      (stroke (width 1.0262) (type solid)) (fill none) (layer "B.Mask"))
    (fp_poly
      (pts
        (xy -1.026 -1.026)
        (xy 1.026 -1.026)
        (xy 1.026 1.026)
        (xy -1.026 1.026)
      )

      (stroke (width 0.01) (type solid)) (fill solid) (layer "B.Mask"))
    (fp_circle (center 0 5.5) (end 0.513 5.5)
      (stroke (width 1.0262) (type solid)) (fill none) (layer "F.Mask"))
    (fp_circle (center 4.2 0) (end 4.713 0)
      (stroke (width 1.0262) (type solid)) (fill none) (layer "F.Mask"))
    (fp_circle (center 4.2 5.5) (end 4.713 5.5)
      (stroke (width 1.0262) (type solid)) (fill none) (layer "F.Mask"))
    (fp_circle (center 8.4 0) (end 8.913 0)
      (stroke (width 1.0262) (type solid)) (fill none) (layer "F.Mask"))
    (fp_circle (center 8.4 5.5) (end 8.913 5.5)
      (stroke (width 1.0262) (type solid)) (fill none) (layer "F.Mask"))
    (fp_circle (center 12.6 0) (end 13.113 0)
      (stroke (width 1.0262) (type solid)) (fill none) (layer "F.Mask"))
    (fp_circle (center 12.6 5.5) (end 13.113 5.5)
      (stroke (width 1.0262) (type solid)) (fill none) (layer "F.Mask"))
    (fp_poly
      (pts
        (xy -1.026 -1.026)
        (xy 1.026 -1.026)
        (xy 1.026 1.026)
        (xy -1.026 1.026)
      )

      (stroke (width 0.01) (type solid)) (fill solid) (layer "F.Mask"))
    (fp_rect (start -3.5 -2.7) (end 16.1 9.1)
      (stroke (width 0.05) (type solid)) (fill none) (layer "F.CrtYd"))
    (fp_line (start -3.1 8.75) (end -3.1 -0.98)
      (stroke (width 0.15) (type solid)) (layer "F.Fab"))
    (fp_line (start -1.83 -2.25) (end -3.1 -0.98)
      (stroke (width 0.15) (type solid)) (layer "F.Fab"))
    (fp_line (start -1.83 -2.25) (end 15.7 -2.25)
      (stroke (width 0.15) (type solid)) (layer "F.Fab"))
    (fp_line (start -0.4 -3.327) (end 0 -2.627)
      (stroke (width 0.15) (type solid)) (layer "F.Fab"))
    (fp_line (start 0 -2.627) (end 0.4 -3.327)
      (stroke (width 0.15) (type solid)) (layer "F.Fab"))
    (fp_line (start 0.4 -3.327) (end -0.4 -3.327)
      (stroke (width 0.15) (type solid)) (layer "F.Fab"))
    (fp_line (start 15.7 -2.25) (end 15.7 8.75)
      (stroke (width 0.15) (type solid)) (layer "F.Fab"))
    (fp_line (start 15.7 8.75) (end -3.1 8.75)
      (stroke (width 0.15) (type solid)) (layer "F.Fab"))
    (pad "1" thru_hole rect (at 0 0 90) (size 1.9 1.9) (drill 1.4) (layers "*.Cu")
      (net 4 "GND") (pinfunction "1") (pintype "bidirectional"))
    (pad "2" thru_hole circle (at 4.2 0 90) (size 1.9 1.9) (drill 1.4) (layers "*.Cu")
      (net 4 "GND") (pinfunction "2") (pintype "bidirectional"))
    (pad "3" thru_hole circle (at 8.4 0 90) (size 1.9 1.9) (drill 1.4) (layers "*.Cu")
      (net 4 "GND") (pinfunction "3") (pintype "bidirectional"))
    (pad "4" thru_hole circle (at 12.6 0 90) (size 1.9 1.9) (drill 1.4) (layers "*.Cu")
      (net 4 "GND") (pinfunction "4") (pintype "bidirectional"))
    (pad "5" thru_hole circle (at 0 5.5 90) (size 1.9 1.9) (drill 1.4) (layers "*.Cu")
      (net 44 "LOAD_2") (pinfunction "5") (pintype "bidirectional"))
    (pad "6" thru_hole circle (at 4.2 5.5 90) (size 1.9 1.9) (drill 1.4) (layers "*.Cu")
      (net 44 "LOAD_2") (pinfunction "6") (pintype "bidirectional"))
    (pad "7" thru_hole circle (at 8.4 5.5 90) (size 1.9 1.9) (drill 1.4) (layers "*.Cu")
      (net 44 "LOAD_2") (pinfunction "7") (pintype "bidirectional"))
    (pad "8" thru_hole circle (at 12.6 5.5 90) (size 1.9 1.9) (drill 1.4) (layers "*.Cu")
      (net 44 "LOAD_2") (pinfunction "8") (pintype "bidirectional"))
  )

  (footprint "antmicro-footprints:TP_SMD_1mm" (layer "F.Cu")
    (at 175.95 96.3008)
    (property "Author" "Antmicro")
    (property "License" "Apache-2.0")
    (property "MPN" "")
    (property "Manufacturer" "")
    (property "Sheetfile" "ftdi-module.kicad_sch")
    (property "Sheetname" "FTDI")
    (property "exclude_from_bom" "")
    (property "ki_description" "Test point 1mm SMD")
    (property "ki_keywords" "TESTPOINT")
    (attr exclude_from_pos_files exclude_from_bom)
    (fp_text reference "SDA1" (at -1.85 -0.0008) (layer "F.SilkS")
        (effects (font (size 0.7 0.7) (thickness 0.15)))
    )
    (fp_text value "TP_1mm_SMD" (at 0 -0.5) (layer "F.Fab") hide
        (effects (font (size 1 1) (thickness 0.15)))
    )
    (fp_text user "License: Apache-2.0" (at -0.5 5.2) (layer "F.Fab") hide
        (effects (font (size 0.7 0.7) (thickness 0.15)) (justify left bottom))
    )
    (fp_text user "${REFERENCE}" (at -0.5 2.8) (layer "F.Fab") hide
        (effects (font (size 0.7 0.7) (thickness 0.15)) (justify left bottom))
    )
    (fp_text user "Author: Antmicro" (at -0.5 4) (layer "F.Fab") hide
        (effects (font (size 0.7 0.7) (thickness 0.15)) (justify left bottom))
    )
    (fp_circle (center 0 0) (end 0.6 0)
      (stroke (width 0.05) (type default)) (fill none) (layer "F.CrtYd"))
    (pad "1" smd circle (at 0 0) (size 1 1) (layers "F.Cu" "F.Mask")
      (net 18 "SDA") (pinfunction "1") (pintype "passive"))
  )

  (footprint "antmicro-footprints:MOLEX_39288080" (layer "F.Cu")
    (at 162.25 74.7 90)
    (property "Author" "Antmicro")
    (property "License" "Apache-2.0")
    (property "MPN" "39-28-8080")
    (property "Manufacturer" "Molex")
    (property "Sheetfile" "d1600e-psu-breakout-board.kicad_sch")
    (property "Sheetname" "")
    (property "ki_description" "Pin Header, THT, Vertical, UL94V-2, Power, Wire-to-Board, 4.2 mm, 2 Rows, 8 Contacts, Mini-fit Jr, 5566 series")
    (property "ki_keywords" "VERTICAL, THT, HEADER, CONNECTOR, MALE, WIRE-BOARD, POWER")
    (attr through_hole)
    (fp_text reference "J8" (at -2.15 -2.65 90) (layer "F.SilkS")
        (effects (font (size 0.7 0.7) (thickness 0.15)) (justify left bottom))
    )
    (fp_text value "Molex_Mini-Fit-Jr_2x4_39-28-8080" (at 4.49 11.365 90) (layer "F.Fab")
        (effects (font (size 0.7 0.7) (thickness 0.15)) (justify left bottom))
    )
    (fp_text user "License: Apache-2.0" (at -3.5 14.565 90) (layer "F.Fab") hide
        (effects (font (size 0.7 0.7) (thickness 0.15)) (justify left bottom))
    )
    (fp_text user "${REFERENCE}" (at -3.5 15.765 90) (layer "F.Fab") hide
        (effects (font (size 0.7 0.7) (thickness 0.15)) (justify left bottom))
    )
    (fp_text user "Author: Antmicro" (at -3.5 16.965 90) (layer "F.Fab") hide
        (effects (font (size 0.7 0.7) (thickness 0.15)) (justify left bottom))
    )
    (fp_text user "PTH D1.40 +/- 0.05" (at -3.5 13.365 90) (layer "F.Fab") hide
        (effects (font (size 0.7 0.7) (thickness 0.15)) (justify left bottom))
    )
    (fp_line (start -3.1 8.75) (end -3.1 -0.98)
      (stroke (width 0.15) (type solid)) (layer "F.SilkS"))
    (fp_line (start -1.83 -2.25) (end -3.1 -0.98)
      (stroke (width 0.15) (type solid)) (layer "F.SilkS"))
    (fp_line (start -1.83 -2.25) (end 15.7 -2.25)
      (stroke (width 0.15) (type solid)) (layer "F.SilkS"))
    (fp_line (start -0.4 -3.327) (end 0 -2.627)
      (stroke (width 0.15) (type solid)) (layer "F.SilkS"))
    (fp_line (start 0 -2.627) (end 0.4 -3.327)
      (stroke (width 0.15) (type solid)) (layer "F.SilkS"))
    (fp_line (start 0.4 -3.327) (end -0.4 -3.327)
      (stroke (width 0.15) (type solid)) (layer "F.SilkS"))
    (fp_line (start 15.7 -2.25) (end 15.7 8.75)
      (stroke (width 0.15) (type solid)) (layer "F.SilkS"))
    (fp_line (start 15.7 8.75) (end -3.1 8.75)
      (stroke (width 0.15) (type solid)) (layer "F.SilkS"))
    (fp_circle (center 0 -3) (end 0.05 -3)
      (stroke (width 0.15) (type solid)) (fill solid) (layer "F.SilkS"))
    (fp_circle (center 0 5.5) (end 0.513 5.5)
      (stroke (width 1.0262) (type solid)) (fill none) (layer "B.Mask"))
    (fp_circle (center 4.2 0) (end 4.713 0)
      (stroke (width 1.0262) (type solid)) (fill none) (layer "B.Mask"))
    (fp_circle (center 4.2 5.5) (end 4.713 5.5)
      (stroke (width 1.0262) (type solid)) (fill none) (layer "B.Mask"))
    (fp_circle (center 8.4 0) (end 8.913 0)
      (stroke (width 1.0262) (type solid)) (fill none) (layer "B.Mask"))
    (fp_circle (center 8.4 5.5) (end 8.913 5.5)
      (stroke (width 1.0262) (type solid)) (fill none) (layer "B.Mask"))
    (fp_circle (center 12.6 0) (end 13.113 0)
      (stroke (width 1.0262) (type solid)) (fill none) (layer "B.Mask"))
    (fp_circle (center 12.6 5.5) (end 13.113 5.5)
      (stroke (width 1.0262) (type solid)) (fill none) (layer "B.Mask"))
    (fp_poly
      (pts
        (xy -1.026 -1.026)
        (xy 1.026 -1.026)
        (xy 1.026 1.026)
        (xy -1.026 1.026)
      )

      (stroke (width 0.01) (type solid)) (fill solid) (layer "B.Mask"))
    (fp_circle (center 0 5.5) (end 0.513 5.5)
      (stroke (width 1.0262) (type solid)) (fill none) (layer "F.Mask"))
    (fp_circle (center 4.2 0) (end 4.713 0)
      (stroke (width 1.0262) (type solid)) (fill none) (layer "F.Mask"))
    (fp_circle (center 4.2 5.5) (end 4.713 5.5)
      (stroke (width 1.0262) (type solid)) (fill none) (layer "F.Mask"))
    (fp_circle (center 8.4 0) (end 8.913 0)
      (stroke (width 1.0262) (type solid)) (fill none) (layer "F.Mask"))
    (fp_circle (center 8.4 5.5) (end 8.913 5.5)
      (stroke (width 1.0262) (type solid)) (fill none) (layer "F.Mask"))
    (fp_circle (center 12.6 0) (end 13.113 0)
      (stroke (width 1.0262) (type solid)) (fill none) (layer "F.Mask"))
    (fp_circle (center 12.6 5.5) (end 13.113 5.5)
      (stroke (width 1.0262) (type solid)) (fill none) (layer "F.Mask"))
    (fp_poly
      (pts
        (xy -1.026 -1.026)
        (xy 1.026 -1.026)
        (xy 1.026 1.026)
        (xy -1.026 1.026)
      )

      (stroke (width 0.01) (type solid)) (fill solid) (layer "F.Mask"))
    (fp_rect (start -3.5 -2.7) (end 16.1 9.1)
      (stroke (width 0.05) (type solid)) (fill none) (layer "F.CrtYd"))
    (fp_line (start -3.1 8.75) (end -3.1 -0.98)
      (stroke (width 0.15) (type solid)) (layer "F.Fab"))
    (fp_line (start -1.83 -2.25) (end -3.1 -0.98)
      (stroke (width 0.15) (type solid)) (layer "F.Fab"))
    (fp_line (start -1.83 -2.25) (end 15.7 -2.25)
      (stroke (width 0.15) (type solid)) (layer "F.Fab"))
    (fp_line (start -0.4 -3.327) (end 0 -2.627)
      (stroke (width 0.15) (type solid)) (layer "F.Fab"))
    (fp_line (start 0 -2.627) (end 0.4 -3.327)
      (stroke (width 0.15) (type solid)) (layer "F.Fab"))
    (fp_line (start 0.4 -3.327) (end -0.4 -3.327)
      (stroke (width 0.15) (type solid)) (layer "F.Fab"))
    (fp_line (start 15.7 -2.25) (end 15.7 8.75)
      (stroke (width 0.15) (type solid)) (layer "F.Fab"))
    (fp_line (start 15.7 8.75) (end -3.1 8.75)
      (stroke (width 0.15) (type solid)) (layer "F.Fab"))
    (pad "1" thru_hole rect (at 0 0 90) (size 1.9 1.9) (drill 1.4) (layers "*.Cu")
      (net 4 "GND") (pinfunction "1") (pintype "bidirectional"))
    (pad "2" thru_hole circle (at 4.2 0 90) (size 1.9 1.9) (drill 1.4) (layers "*.Cu")
      (net 4 "GND") (pinfunction "2") (pintype "bidirectional"))
    (pad "3" thru_hole circle (at 8.4 0 90) (size 1.9 1.9) (drill 1.4) (layers "*.Cu")
      (net 4 "GND") (pinfunction "3") (pintype "bidirectional"))
    (pad "4" thru_hole circle (at 12.6 0 90) (size 1.9 1.9) (drill 1.4) (layers "*.Cu")
      (net 4 "GND") (pinfunction "4") (pintype "bidirectional"))
    (pad "5" thru_hole circle (at 0 5.5 90) (size 1.9 1.9) (drill 1.4) (layers "*.Cu")
      (net 45 "LOAD_4") (pinfunction "5") (pintype "bidirectional"))
    (pad "6" thru_hole circle (at 4.2 5.5 90) (size 1.9 1.9) (drill 1.4) (layers "*.Cu")
      (net 45 "LOAD_4") (pinfunction "6") (pintype "bidirectional"))
    (pad "7" thru_hole circle (at 8.4 5.5 90) (size 1.9 1.9) (drill 1.4) (layers "*.Cu")
      (net 45 "LOAD_4") (pinfunction "7") (pintype "bidirectional"))
    (pad "8" thru_hole circle (at 12.6 5.5 90) (size 1.9 1.9) (drill 1.4) (layers "*.Cu")
      (net 45 "LOAD_4") (pinfunction "8") (pintype "bidirectional"))
  )

  (footprint "antmicro-footprints:R_0402_1005Metric" (layer "F.Cu")
    (at 180.1 92.1 180)
    (descr "Resistor SMD 0402")
    (tags "resistor SMD 0402")
    (property "Author" "Antmicro")
    (property "License" "Apache-2.0")
    (property "MPN" "CR0402-FX-4701GLF")
    (property "Manufacturer" "Bourns")
    (property "Sheetfile" "power-switch.kicad_sch")
    (property "Sheetname" "Power switch 5")
    (property "Tolerance" "1%")
    (property "Val" "4k7")
    (property "ki_description" "SMD Chip Resistor, 4.7 kohm, ± 1%, 62.5 mW, 0402 [1005 Metric], Thick Film, General Purpose")
    (property "ki_keywords" "0402, SMT, RESISTOR, PASSIVE")
    (zone_connect 1)
    (attr smd)
    (fp_text reference "R25" (at 2.25 -1.95 180) (layer "F.SilkS")
        (effects (font (size 0.7 0.7) (thickness 0.15)))
    )
    (fp_text value "R_4k7_0402" (at 0 1.17) (layer "F.Fab") hide
        (effects (font (size 1 1) (thickness 0.15)))
    )
    (fp_text user "${REFERENCE}" (at 0 0) (layer "F.Fab")
        (effects (font (size 0.7 0.7) (thickness 0.15)))
    )
    (fp_text user "License: Apache-2.0" (at -0.95 5.169 180) (layer "F.Fab") hide
        (effects (font (size 0.7 0.7) (thickness 0.15)) (justify left bottom))
    )
    (fp_text user "Author: Antmicro" (at -0.95 4.169 180) (layer "F.Fab") hide
        (effects (font (size 0.7 0.7) (thickness 0.15)) (justify left bottom))
    )
    (fp_rect (start -0.925 -0.47) (end 0.925 0.47)
      (stroke (width 0.05) (type default)) (fill none) (layer "F.CrtYd"))
    (fp_rect (start -0.5 -0.25) (end 0.5 0.25)
      (stroke (width 0.15) (type solid)) (fill none) (layer "F.Fab"))
    (pad "1" smd roundrect (at -0.48 0 180) (size 0.59 0.64) (layers "F.Cu" "F.Paste" "F.Mask") (roundrect_rratio 0.25)
      (net 11 "VCC12V0") (pintype "passive"))
    (pad "2" smd roundrect (at 0.48 0 180) (size 0.59 0.64) (layers "F.Cu" "F.Paste" "F.Mask") (roundrect_rratio 0.25)
      (net 87 "Net-(D19-A)") (pintype "passive"))
  )

  (footprint "antmicro-footprints:R_0402_1005Metric" (layer "F.Cu")
    (at 114.1 91.85 180)
    (descr "Resistor SMD 0402")
    (tags "resistor SMD 0402")
    (property "Author" "Antmicro")
    (property "License" "Apache-2.0")
    (property "MPN" "CR0402-FX-4701GLF")
    (property "Manufacturer" "Bourns")
    (property "Sheetfile" "power-switch.kicad_sch")
    (property "Sheetname" "Power switch 1")
    (property "Tolerance" "1%")
    (property "Val" "4k7")
    (property "ki_description" "SMD Chip Resistor, 4.7 kohm, ± 1%, 62.5 mW, 0402 [1005 Metric], Thick Film, General Purpose")
    (property "ki_keywords" "0402, SMT, RESISTOR, PASSIVE")
    (zone_connect 1)
    (attr smd)
    (fp_text reference "R22" (at 1.15 -1.3 180) (layer "F.SilkS")
        (effects (font (size 0.7 0.7) (thickness 0.15)) (justify left bottom))
    )
    (fp_text value "R_4k7_0402" (at -1.011843 1.772047 180) (layer "F.Fab")
        (effects (font (size 0.7 0.7) (thickness 0.15)) (justify left bottom))
    )
    (fp_text user "License: Apache-2.0" (at -0.95 5.169 180) (layer "F.Fab") hide
        (effects (font (size 0.7 0.7) (thickness 0.15)) (justify left bottom))
    )
    (fp_text user "Author: Antmicro" (at -0.95 4.169 180) (layer "F.Fab") hide
        (effects (font (size 0.7 0.7) (thickness 0.15)) (justify left bottom))
    )
    (fp_text user "${REFERENCE}" (at -0.95 3.168 180) (layer "F.Fab") hide
        (effects (font (size 0.7 0.7) (thickness 0.15)) (justify left bottom))
    )
    (fp_rect (start -0.925 -0.47) (end 0.925 0.47)
      (stroke (width 0.05) (type default)) (fill none) (layer "F.CrtYd"))
    (fp_rect (start -0.5 -0.25) (end 0.5 0.25)
      (stroke (width 0.15) (type solid)) (fill none) (layer "F.Fab"))
    (pad "1" smd roundrect (at -0.48 0 180) (size 0.59 0.64) (layers "F.Cu" "F.Paste" "F.Mask") (roundrect_rratio 0.25)
      (net 11 "VCC12V0") (pintype "passive"))
    (pad "2" smd roundrect (at 0.48 0 180) (size 0.59 0.64) (layers "F.Cu" "F.Paste" "F.Mask") (roundrect_rratio 0.25)
      (net 83 "Net-(D15-A)") (pintype "passive"))
  )

  (footprint "antmicro-footprints:R_0402_1005Metric" (layer "F.Cu")
    (at 178.75 85.8 -90)
    (descr "Resistor SMD 0402")
    (tags "resistor SMD 0402")
    (property "Author" "Antmicro")
    (property "License" "Apache-2.0")
    (property "MPN" "CR0402-FX-1002GLF")
    (property "Manufacturer" "Bourns")
    (property "Sheetfile" "power-switch.kicad_sch")
    (property "Sheetname" "Power switch 5")
    (property "Tolerance" "1%")
    (property "Val" "10k")
    (property "ki_description" "SMD Chip Resistor, 10 kohm, ± 1%, 62.5 mW, 0402 [1005 Metric], Thick Film, General Purpose")
    (property "ki_keywords" "0402, SMT, RESISTOR, PASSIVE")
    (attr smd)
    (fp_text reference "R24" (at -0.1 -0.85 90) (layer "F.SilkS")
        (effects (font (size 0.7 0.7) (thickness 0.15)))
    )
    (fp_text value "R_10k_0402" (at 0 1.17 90) (layer "F.Fab") hide
        (effects (font (size 1 1) (thickness 0.15)))
    )
    (fp_text user "License: Apache-2.0" (at -0.95 5.169 -90) (layer "F.Fab") hide
        (effects (font (size 0.7 0.7) (thickness 0.15)) (justify left bottom))
    )
    (fp_text user "${REFERENCE}" (at 0 0 90) (layer "F.Fab")
        (effects (font (size 0.7 0.7) (thickness 0.15)))
    )
    (fp_text user "Author: Antmicro" (at -0.95 4.169 -90) (layer "F.Fab") hide
        (effects (font (size 0.7 0.7) (thickness 0.15)) (justify left bottom))
    )
    (fp_rect (start -0.925 -0.47) (end 0.925 0.47)
      (stroke (width 0.05) (type default)) (fill none) (layer "F.CrtYd"))
    (fp_rect (start -0.5 -0.25) (end 0.5 0.25)
      (stroke (width 0.15) (type solid)) (fill none) (layer "F.Fab"))
    (pad "1" smd roundrect (at -0.48 0 270) (size 0.59 0.64) (layers "F.Cu" "F.Paste" "F.Mask") (roundrect_rratio 0.25)
      (net 1 "VCC3V3") (pintype "passive"))
    (pad "2" smd roundrect (at 0.48 0 270) (size 0.59 0.64) (layers "F.Cu" "F.Paste" "F.Mask") (roundrect_rratio 0.25)
      (net 26 "/Power Cycling & Current Measurement/PC_5") (pintype "passive"))
  )

  (footprint "antmicro-footprints:MOLEX_39288080" (layer "F.Cu")
    (at 179.5 74.7 90)
    (property "Author" "Antmicro")
    (property "License" "Apache-2.0")
    (property "MPN" "39-28-8080")
    (property "Manufacturer" "Molex")
    (property "Sheetfile" "d1600e-psu-breakout-board.kicad_sch")
    (property "Sheetname" "")
    (property "ki_description" "Pin Header, THT, Vertical, UL94V-2, Power, Wire-to-Board, 4.2 mm, 2 Rows, 8 Contacts, Mini-fit Jr, 5566 series")
    (property "ki_keywords" "VERTICAL, THT, HEADER, CONNECTOR, MALE, WIRE-BOARD, POWER")
    (attr through_hole)
    (fp_text reference "J6" (at -2 -2.65 90) (layer "F.SilkS")
        (effects (font (size 0.7 0.7) (thickness 0.15)) (justify left bottom))
    )
    (fp_text value "Molex_Mini-Fit-Jr_2x4_39-28-8080" (at 4.49 11.365 90) (layer "F.Fab")
        (effects (font (size 0.7 0.7) (thickness 0.15)) (justify left bottom))
    )
    (fp_text user "License: Apache-2.0" (at -3.5 14.565 90) (layer "F.Fab") hide
        (effects (font (size 0.7 0.7) (thickness 0.15)) (justify left bottom))
    )
    (fp_text user "Author: Antmicro" (at -3.5 16.965 90) (layer "F.Fab") hide
        (effects (font (size 0.7 0.7) (thickness 0.15)) (justify left bottom))
    )
    (fp_text user "PTH D1.40 +/- 0.05" (at -3.5 13.365 90) (layer "F.Fab") hide
        (effects (font (size 0.7 0.7) (thickness 0.15)) (justify left bottom))
    )
    (fp_text user "${REFERENCE}" (at -3.5 15.765 90) (layer "F.Fab") hide
        (effects (font (size 0.7 0.7) (thickness 0.15)) (justify left bottom))
    )
    (fp_line (start -3.1 8.75) (end -3.1 -0.98)
      (stroke (width 0.15) (type solid)) (layer "F.SilkS"))
    (fp_line (start -1.83 -2.25) (end -3.1 -0.98)
      (stroke (width 0.15) (type solid)) (layer "F.SilkS"))
    (fp_line (start -1.83 -2.25) (end 15.7 -2.25)
      (stroke (width 0.15) (type solid)) (layer "F.SilkS"))
    (fp_line (start -0.4 -3.327) (end 0 -2.627)
      (stroke (width 0.15) (type solid)) (layer "F.SilkS"))
    (fp_line (start 0 -2.627) (end 0.4 -3.327)
      (stroke (width 0.15) (type solid)) (layer "F.SilkS"))
    (fp_line (start 0.4 -3.327) (end -0.4 -3.327)
      (stroke (width 0.15) (type solid)) (layer "F.SilkS"))
    (fp_line (start 15.7 -2.25) (end 15.7 8.75)
      (stroke (width 0.15) (type solid)) (layer "F.SilkS"))
    (fp_line (start 15.7 8.75) (end -3.1 8.75)
      (stroke (width 0.15) (type solid)) (layer "F.SilkS"))
    (fp_circle (center 0 -3) (end 0.05 -3)
      (stroke (width 0.15) (type solid)) (fill solid) (layer "F.SilkS"))
    (fp_circle (center 0 5.5) (end 0.513 5.5)
      (stroke (width 1.0262) (type solid)) (fill none) (layer "B.Mask"))
    (fp_circle (center 4.2 0) (end 4.713 0)
      (stroke (width 1.0262) (type solid)) (fill none) (layer "B.Mask"))
    (fp_circle (center 4.2 5.5) (end 4.713 5.5)
      (stroke (width 1.0262) (type solid)) (fill none) (layer "B.Mask"))
    (fp_circle (center 8.4 0) (end 8.913 0)
      (stroke (width 1.0262) (type solid)) (fill none) (layer "B.Mask"))
    (fp_circle (center 8.4 5.5) (end 8.913 5.5)
      (stroke (width 1.0262) (type solid)) (fill none) (layer "B.Mask"))
    (fp_circle (center 12.6 0) (end 13.113 0)
      (stroke (width 1.0262) (type solid)) (fill none) (layer "B.Mask"))
    (fp_circle (center 12.6 5.5) (end 13.113 5.5)
      (stroke (width 1.0262) (type solid)) (fill none) (layer "B.Mask"))
    (fp_poly
      (pts
        (xy -1.026 -1.026)
        (xy 1.026 -1.026)
        (xy 1.026 1.026)
        (xy -1.026 1.026)
      )

      (stroke (width 0.01) (type solid)) (fill solid) (layer "B.Mask"))
    (fp_circle (center 0 5.5) (end 0.513 5.5)
      (stroke (width 1.0262) (type solid)) (fill none) (layer "F.Mask"))
    (fp_circle (center 4.2 0) (end 4.713 0)
      (stroke (width 1.0262) (type solid)) (fill none) (layer "F.Mask"))
    (fp_circle (center 4.2 5.5) (end 4.713 5.5)
      (stroke (width 1.0262) (type solid)) (fill none) (layer "F.Mask"))
    (fp_circle (center 8.4 0) (end 8.913 0)
      (stroke (width 1.0262) (type solid)) (fill none) (layer "F.Mask"))
    (fp_circle (center 8.4 5.5) (end 8.913 5.5)
      (stroke (width 1.0262) (type solid)) (fill none) (layer "F.Mask"))
    (fp_circle (center 12.6 0) (end 13.113 0)
      (stroke (width 1.0262) (type solid)) (fill none) (layer "F.Mask"))
    (fp_circle (center 12.6 5.5) (end 13.113 5.5)
      (stroke (width 1.0262) (type solid)) (fill none) (layer "F.Mask"))
    (fp_poly
      (pts
        (xy -1.026 -1.026)
        (xy 1.026 -1.026)
        (xy 1.026 1.026)
        (xy -1.026 1.026)
      )

      (stroke (width 0.01) (type solid)) (fill solid) (layer "F.Mask"))
    (fp_rect (start -3.5 -2.7) (end 16.1 9.1)
      (stroke (width 0.05) (type solid)) (fill none) (layer "F.CrtYd"))
    (fp_line (start -3.1 8.75) (end -3.1 -0.98)
      (stroke (width 0.15) (type solid)) (layer "F.Fab"))
    (fp_line (start -1.83 -2.25) (end -3.1 -0.98)
      (stroke (width 0.15) (type solid)) (layer "F.Fab"))
    (fp_line (start -1.83 -2.25) (end 15.7 -2.25)
      (stroke (width 0.15) (type solid)) (layer "F.Fab"))
    (fp_line (start -0.4 -3.327) (end 0 -2.627)
      (stroke (width 0.15) (type solid)) (layer "F.Fab"))
    (fp_line (start 0 -2.627) (end 0.4 -3.327)
      (stroke (width 0.15) (type solid)) (layer "F.Fab"))
    (fp_line (start 0.4 -3.327) (end -0.4 -3.327)
      (stroke (width 0.15) (type solid)) (layer "F.Fab"))
    (fp_line (start 15.7 -2.25) (end 15.7 8.75)
      (stroke (width 0.15) (type solid)) (layer "F.Fab"))
    (fp_line (start 15.7 8.75) (end -3.1 8.75)
      (stroke (width 0.15) (type solid)) (layer "F.Fab"))
    (pad "1" thru_hole rect (at 0 0 90) (size 1.9 1.9) (drill 1.4) (layers "*.Cu")
      (net 4 "GND") (pinfunction "1") (pintype "bidirectional"))
    (pad "2" thru_hole circle (at 4.2 0 90) (size 1.9 1.9) (drill 1.4) (layers "*.Cu")
      (net 4 "GND") (pinfunction "2") (pintype "bidirectional"))
    (pad "3" thru_hole circle (at 8.4 0 90) (size 1.9 1.9) (drill 1.4) (layers "*.Cu")
      (net 4 "GND") (pinfunction "3") (pintype "bidirectional"))
    (pad "4" thru_hole circle (at 12.6 0 90) (size 1.9 1.9) (drill 1.4) (layers "*.Cu")
      (net 4 "GND") (pinfunction "4") (pintype "bidirectional"))
    (pad "5" thru_hole circle (at 0 5.5 90) (size 1.9 1.9) (drill 1.4) (layers "*.Cu")
      (net 43 "LOAD_5") (pinfunction "5") (pintype "bidirectional"))
    (pad "6" thru_hole circle (at 4.2 5.5 90) (size 1.9 1.9) (drill 1.4) (layers "*.Cu")
      (net 43 "LOAD_5") (pinfunction "6") (pintype "bidirectional"))
    (pad "7" thru_hole circle (at 8.4 5.5 90) (size 1.9 1.9) (drill 1.4) (layers "*.Cu")
      (net 43 "LOAD_5") (pinfunction "7") (pintype "bidirectional"))
    (pad "8" thru_hole circle (at 12.6 5.5 90) (size 1.9 1.9) (drill 1.4) (layers "*.Cu")
      (net 43 "LOAD_5") (pinfunction "8") (pintype "bidirectional"))
  )

  (footprint "antmicro-footprints:R_0402_1005Metric" (layer "F.Cu")
    (at 181.215 93.6)
    (descr "Resistor SMD 0402")
    (tags "resistor SMD 0402")
    (property "Author" "Antmicro")
    (property "Current" "1A")
    (property "DNP" "DNP")
    (property "License" "Apache-2.0")
    (property "MPN" "ERJ2GE0R00X")
    (property "Manufacturer" "Panasonic")
    (property "Sheetfile" "d1600e-psu-breakout-board.kicad_sch")
    (property "Sheetname" "")
    (property "Tolerance" "")
    (property "Val" "0R")
    (property "dnp" "")
    (property "exclude_from_bom" "")
    (property "ki_description" "SMD Chip Resistor, Jumper, 0 ohm, 100 mW, 0402 [1005 Metric], Thick Film, General Purpose")
    (property "ki_keywords" "0402, SMT, RESISTOR, PASSIVE")
    (attr smd exclude_from_bom)
    (fp_text reference "R9" (at -1.365 0.85) (layer "F.SilkS")
        (effects (font (size 0.7 0.7) (thickness 0.15)))
    )
    (fp_text value "R_0R_0402" (at 0 1.17) (layer "F.Fab") hide
        (effects (font (size 1 1) (thickness 0.15)))
    )
    (fp_text user "Author: Antmicro" (at -0.95 4.169) (layer "F.Fab") hide
        (effects (font (size 0.7 0.7) (thickness 0.15)) (justify left bottom))
    )
    (fp_text user "${REFERENCE}" (at 0 0) (layer "F.Fab")
        (effects (font (size 0.7 0.7) (thickness 0.15)))
    )
    (fp_text user "License: Apache-2.0" (at -0.95 5.169) (layer "F.Fab") hide
        (effects (font (size 0.7 0.7) (thickness 0.15)) (justify left bottom))
    )
    (fp_rect (start -0.925 -0.47) (end 0.925 0.47)
      (stroke (width 0.05) (type default)) (fill none) (layer "F.CrtYd"))
    (fp_rect (start -0.5 -0.25) (end 0.5 0.25)
      (stroke (width 0.15) (type solid)) (fill none) (layer "F.Fab"))
    (pad "1" smd roundrect (at -0.48 0) (size 0.59 0.64) (layers "F.Cu" "F.Paste" "F.Mask") (roundrect_rratio 0.25)
      (net 1 "VCC3V3") (pintype "passive"))
    (pad "2" smd roundrect (at 0.48 0) (size 0.59 0.64) (layers "F.Cu" "F.Paste" "F.Mask") (roundrect_rratio 0.25)
      (net 19 "Net-(J2-Pad1)") (pintype "passive"))
  )

  (footprint "antmicro-footprints:SOIC-8_3.9x4.9x1.75mm_P1.27mm" (layer "F.Cu")
    (at 179.75 82.1508 180)
    (property "Author" "Antmicro")
    (property "License" "Apache-2.0")
    (property "MPN" "TMCS1100A2QDRQ1")
    (property "Manufacturer" "Texas Instruments")
    (property "Sheetfile" "pow-cycl-curr-meas.kicad_sch")
    (property "Sheetname" "Power Cycling & Current Measurement")
    (property "ki_description" "Hall current Sensor/transducer")
    (property "ki_keywords" "SMT, SENSOR, IC, POWER")
    (attr smd)
    (fp_text reference "U13" (at 1.2 2.8508) (layer "F.SilkS")
        (effects (font (size 0.7 0.7) (thickness 0.15)) (justify right bottom))
    )
    (fp_text value "TMCS1100A2-Q1" (at 0 3.65) (layer "F.Fab")
        (effects (font (size 0.7 0.7) (thickness 0.15)) (justify right bottom))
    )
    (fp_text user "License: Apache-2.0" (at -3.476 5.099) (layer "F.Fab") hide
        (effects (font (size 0.7 0.7) (thickness 0.15)) (justify right bottom))
    )
    (fp_text user "${REFERENCE}" (at -3.476 7.099) (layer "F.Fab") hide
        (effects (font (size 0.7 0.7) (thickness 0.15)) (justify right bottom))
    )
    (fp_text user "Author: Antmicro" (at -3.476 6.099) (layer "F.Fab") hide
        (effects (font (size 0.7 0.7) (thickness 0.15)) (justify right bottom))
    )
    (fp_line (start -1.95 -2.452) (end 1.95 -2.45)
      (stroke (width 0.15) (type solid)) (layer "F.SilkS"))
    (fp_line (start -1.95 2.45) (end 1.95 2.45)
      (stroke (width 0.15) (type solid)) (layer "F.SilkS"))
    (fp_circle (center -2.4 -2.45) (end -2.35 -2.4)
      (stroke (width 0.15) (type solid)) (fill solid) (layer "F.SilkS"))
    (fp_rect (start -3.625 -2.7) (end 3.625 2.7)
      (stroke (width 0.05) (type solid)) (fill none) (layer "F.CrtYd"))
    (fp_line (start -1.95 -1.18) (end -0.683 -2.452)
      (stroke (width 0.15) (type solid)) (layer "F.Fab"))
    (fp_line (start -1.95 2.45) (end -1.95 -1.18)
      (stroke (width 0.15) (type solid)) (layer "F.Fab"))
    (fp_line (start -0.683 -2.452) (end 1.949 -2.452)
      (stroke (width 0.15) (type solid)) (layer "F.Fab"))
    (fp_line (start 1.949 -2.452) (end 1.949 2.45)
      (stroke (width 0.15) (type solid)) (layer "F.Fab"))
    (fp_line (start 1.949 2.45) (end -1.95 2.45)
      (stroke (width 0.15) (type solid)) (layer "F.Fab"))
    (pad "1" smd roundrect (at -2.714 -1.905 270) (size 0.65 1.525) (layers "F.Cu" "F.Paste" "F.Mask") (roundrect_rratio 0.25)
      (net 25 "C_MEAS_5") (pinfunction "IN+") (pintype "input"))
    (pad "2" smd roundrect (at -2.714 -0.635 270) (size 0.65 1.525) (layers "F.Cu" "F.Paste" "F.Mask") (roundrect_rratio 0.25)
      (net 25 "C_MEAS_5") (pinfunction "IN+") (pintype "input"))
    (pad "3" smd roundrect (at -2.714 0.632 270) (size 0.65 1.525) (layers "F.Cu" "F.Paste" "F.Mask") (roundrect_rratio 0.25)
      (net 43 "LOAD_5") (pinfunction "IN-") (pintype "input"))
    (pad "4" smd roundrect (at -2.714 1.902 270) (size 0.65 1.525) (layers "F.Cu" "F.Paste" "F.Mask") (roundrect_rratio 0.25)
      (net 43 "LOAD_5") (pinfunction "IN-") (pintype "input"))
    (pad "5" smd roundrect (at 2.712 1.902 270) (size 0.65 1.525) (layers "F.Cu" "F.Paste" "F.Mask") (roundrect_rratio 0.25)
      (net 4 "GND") (pinfunction "GND") (pintype "power_in"))
    (pad "6" smd roundrect (at 2.712 0.632 270) (size 0.65 1.525) (layers "F.Cu" "F.Paste" "F.Mask") (roundrect_rratio 0.25)
      (net 4 "GND") (pinfunction "VREF") (pintype "input"))
    (pad "7" smd roundrect (at 2.712 -0.635 270) (size 0.65 1.525) (layers "F.Cu" "F.Paste" "F.Mask") (roundrect_rratio 0.25)
      (net 50 "/Power Cycling & Current Measurement/C_ADC5") (pinfunction "VOUT") (pintype "output"))
    (pad "8" smd roundrect (at 2.712 -1.905 270) (size 0.65 1.525) (layers "F.Cu" "F.Paste" "F.Mask") (roundrect_rratio 0.25)
      (net 1 "VCC3V3") (pinfunction "VCC") (pintype "power_in"))
  )

  (footprint "antmicro-footprints:R_0402_1005Metric" (layer "F.Cu")
    (at 143.5 87)
    (descr "Resistor SMD 0402")
    (tags "resistor SMD 0402")
    (property "Author" "Antmicro")
    (property "License" "Apache-2.0")
    (property "MPN" "CR0402-FX-1002GLF")
    (property "Manufacturer" "Bourns")
    (property "Sheetfile" "power-switch.kicad_sch")
    (property "Sheetname" "Power switch 3")
    (property "Tolerance" "1%")
    (property "Val" "10k")
    (property "ki_description" "SMD Chip Resistor, 10 kohm, ± 1%, 62.5 mW, 0402 [1005 Metric], Thick Film, General Purpose")
    (property "ki_keywords" "0402, SMT, RESISTOR, PASSIVE")
    (attr smd)
    (fp_text reference "R27" (at -2 0.1 180) (layer "F.SilkS")
        (effects (font (size 0.7 0.7) (thickness 0.15)))
    )
    (fp_text value "R_10k_0402" (at 0 1.17) (layer "F.Fab") hide
        (effects (font (size 1 1) (thickness 0.15)))
    )
    (fp_text user "Author: Antmicro" (at -0.95 4.169) (layer "F.Fab") hide
        (effects (font (size 0.7 0.7) (thickness 0.15)) (justify left bottom))
    )
    (fp_text user "${REFERENCE}" (at 0 0) (layer "F.Fab")
        (effects (font (size 0.7 0.7) (thickness 0.15)))
    )
    (fp_text user "License: Apache-2.0" (at -0.95 5.169) (layer "F.Fab") hide
        (effects (font (size 0.7 0.7) (thickness 0.15)) (justify left bottom))
    )
    (fp_rect (start -0.925 -0.47) (end 0.925 0.47)
      (stroke (width 0.05) (type default)) (fill none) (layer "F.CrtYd"))
    (fp_rect (start -0.5 -0.25) (end 0.5 0.25)
      (stroke (width 0.15) (type solid)) (fill none) (layer "F.Fab"))
    (pad "1" smd roundrect (at -0.48 0) (size 0.59 0.64) (layers "F.Cu" "F.Paste" "F.Mask") (roundrect_rratio 0.25)
      (net 1 "VCC3V3") (pintype "passive"))
    (pad "2" smd roundrect (at 0.48 0) (size 0.59 0.64) (layers "F.Cu" "F.Paste" "F.Mask") (roundrect_rratio 0.25)
      (net 30 "/Power Cycling & Current Measurement/PC_3") (pintype "passive"))
  )

  (footprint "antmicro-footprints:R_0402_1005Metric" (layer "F.Cu")
    (at 166.85 96.5 -90)
    (descr "Resistor SMD 0402")
    (tags "resistor SMD 0402")
    (property "Author" "Antmicro")
    (property "Current" "1A")
    (property "License" "Apache-2.0")
    (property "MPN" "ERJ2GE0R00X")
    (property "Manufacturer" "Panasonic")
    (property "Sheetfile" "pow-cycl-curr-meas.kicad_sch")
    (property "Sheetname" "Power Cycling & Current Measurement")
    (property "Tolerance" "")
    (property "Val" "0R")
    (property "ki_description" "SMD Chip Resistor, Jumper, 0 ohm, 100 mW, 0402 [1005 Metric], Thick Film, General Purpose")
    (property "ki_keywords" "0402, SMT, RESISTOR, PASSIVE")
    (attr smd)
    (fp_text reference "R14" (at -0.85 -0.4 -90) (layer "F.SilkS")
        (effects (font (size 0.7 0.7) (thickness 0.15)) (justify left bottom))
    )
    (fp_text value "R_0R_0402" (at -1.011843 1.772047 -90) (layer "F.Fab")
        (effects (font (size 0.7 0.7) (thickness 0.15)) (justify left bottom))
    )
    (fp_text user "Author: Antmicro" (at -0.95 4.169 -90) (layer "F.Fab") hide
        (effects (font (size 0.7 0.7) (thickness 0.15)) (justify left bottom))
    )
    (fp_text user "${REFERENCE}" (at -0.95 3.168 -90) (layer "F.Fab") hide
        (effects (font (size 0.7 0.7) (thickness 0.15)) (justify left bottom))
    )
    (fp_text user "License: Apache-2.0" (at -0.95 5.169 -90) (layer "F.Fab") hide
        (effects (font (size 0.7 0.7) (thickness 0.15)) (justify left bottom))
    )
    (fp_rect (start -0.925 -0.47) (end 0.925 0.47)
      (stroke (width 0.05) (type default)) (fill none) (layer "F.CrtYd"))
    (fp_rect (start -0.5 -0.25) (end 0.5 0.25)
      (stroke (width 0.15) (type solid)) (fill none) (layer "F.Fab"))
    (pad "1" smd roundrect (at -0.48 0 270) (size 0.59 0.64) (layers "F.Cu" "F.Paste" "F.Mask") (roundrect_rratio 0.25)
      (net 105 "Net-(U10-A0)") (pintype "passive"))
    (pad "2" smd roundrect (at 0.48 0 270) (size 0.59 0.64) (layers "F.Cu" "F.Paste" "F.Mask") (roundrect_rratio 0.25)
      (net 4 "GND") (pintype "passive"))
  )

  (footprint "antmicro-footprints:MOLEX_39281103" (layer "F.Cu")
    (at 94.25 78.9 90)
    (property "Author" "Antmicro")
    (property "License" "Apache-2.0")
    (property "MPN" "39-28-1103")
    (property "Manufacturer" "Molex")
    (property "Sheetfile" "daughterboard-supply.kicad_sch")
    (property "Sheetname" "daughterboard-supply")
    (property "ki_description" "Pin Header, THT, Vertical, UL94V-2, Power, Wire-to-Board, 4.2 mm, 2 Rows, 10 Contacts, Mini-fit Jr, 5566 series")
    (property "ki_keywords" "VERTICAL, THT, HEADER, CONNECTOR, MALE, WIRE-BOARD")
    (attr through_hole)
    (fp_text reference "J9" (at -4.3 -2.4 180) (layer "F.SilkS")
        (effects (font (size 0.7 0.7) (thickness 0.15)) (justify left bottom))
    )
    (fp_text value "Molex_Mini-Fit-Jr_2x5_39-28-1103" (at 4.49 11.365 90) (layer "F.Fab")
        (effects (font (size 0.7 0.7) (thickness 0.15)) (justify left bottom))
    )
    (fp_text user "License: Apache-2.0" (at -4.1 13.365 90) (layer "F.Fab") hide
        (effects (font (size 0.7 0.7) (thickness 0.15)) (justify left bottom))
    )
    (fp_text user "PTH D1.40 +/- 0.05" (at -4.1 14.565 90) (layer "F.Fab") hide
        (effects (font (size 0.7 0.7) (thickness 0.15)) (justify left bottom))
    )
    (fp_text user "Author: Antmicro" (at -4.1 16.965 90) (layer "F.Fab") hide
        (effects (font (size 0.7 0.7) (thickness 0.15)) (justify left bottom))
    )
    (fp_text user "${REFERENCE}" (at -4.1 15.765 90) (layer "F.Fab") hide
        (effects (font (size 0.7 0.7) (thickness 0.15)) (justify left bottom))
    )
    (fp_line (start -3.1 8.75) (end -3.1 -0.98)
      (stroke (width 0.15) (type solid)) (layer "F.SilkS"))
    (fp_line (start -1.83 -2.25) (end -3.1 -0.98)
      (stroke (width 0.15) (type solid)) (layer "F.SilkS"))
    (fp_line (start -1.83 -2.25) (end 19.9 -2.25)
      (stroke (width 0.15) (type solid)) (layer "F.SilkS"))
    (fp_line (start -0.4 -3.327) (end 0 -2.627)
      (stroke (width 0.15) (type solid)) (layer "F.SilkS"))
    (fp_line (start 0 -2.627) (end 0.4 -3.327)
      (stroke (width 0.15) (type solid)) (layer "F.SilkS"))
    (fp_line (start 0.4 -3.327) (end -0.4 -3.327)
      (stroke (width 0.15) (type solid)) (layer "F.SilkS"))
    (fp_line (start 19.9 -2.25) (end 19.9 8.75)
      (stroke (width 0.15) (type solid)) (layer "F.SilkS"))
    (fp_line (start 19.9 8.75) (end -3.1 8.75)
      (stroke (width 0.15) (type solid)) (layer "F.SilkS"))
    (fp_circle (center 0 -3.6) (end 0.05 -3.6)
      (stroke (width 0.15) (type solid)) (fill solid) (layer "F.SilkS"))
    (fp_circle (center 0 5.5) (end 0.513 5.5)
      (stroke (width 1.0262) (type solid)) (fill none) (layer "B.Mask"))
    (fp_circle (center 4.2 0) (end 4.713 0)
      (stroke (width 1.0262) (type solid)) (fill none) (layer "B.Mask"))
    (fp_circle (center 4.2 5.5) (end 4.713 5.5)
      (stroke (width 1.0262) (type solid)) (fill none) (layer "B.Mask"))
    (fp_circle (center 8.4 0) (end 8.913 0)
      (stroke (width 1.0262) (type solid)) (fill none) (layer "B.Mask"))
    (fp_circle (center 8.4 5.5) (end 8.913 5.5)
      (stroke (width 1.0262) (type solid)) (fill none) (layer "B.Mask"))
    (fp_circle (center 12.6 0) (end 13.113 0)
      (stroke (width 1.0262) (type solid)) (fill none) (layer "B.Mask"))
    (fp_circle (center 12.6 5.5) (end 13.113 5.5)
      (stroke (width 1.0262) (type solid)) (fill none) (layer "B.Mask"))
    (fp_circle (center 16.8 0) (end 17.313 0)
      (stroke (width 1.0262) (type solid)) (fill none) (layer "B.Mask"))
    (fp_circle (center 16.8 5.5) (end 17.313 5.5)
      (stroke (width 1.0262) (type solid)) (fill none) (layer "B.Mask"))
    (fp_poly
      (pts
        (xy -1.026 -1.026)
        (xy 1.026 -1.026)
        (xy 1.026 1.026)
        (xy -1.026 1.026)
      )

      (stroke (width 0.01) (type solid)) (fill solid) (layer "B.Mask"))
    (fp_circle (center 0 5.5) (end 0.513 5.5)
      (stroke (width 1.0262) (type solid)) (fill none) (layer "F.Mask"))
    (fp_circle (center 4.2 0) (end 4.713 0)
      (stroke (width 1.0262) (type solid)) (fill none) (layer "F.Mask"))
    (fp_circle (center 4.2 5.5) (end 4.713 5.5)
      (stroke (width 1.0262) (type solid)) (fill none) (layer "F.Mask"))
    (fp_circle (center 8.4 0) (end 8.913 0)
      (stroke (width 1.0262) (type solid)) (fill none) (layer "F.Mask"))
    (fp_circle (center 8.4 5.5) (end 8.913 5.5)
      (stroke (width 1.0262) (type solid)) (fill none) (layer "F.Mask"))
    (fp_circle (center 12.6 0) (end 13.113 0)
      (stroke (width 1.0262) (type solid)) (fill none) (layer "F.Mask"))
    (fp_circle (center 12.6 5.5) (end 13.113 5.5)
      (stroke (width 1.0262) (type solid)) (fill none) (layer "F.Mask"))
    (fp_circle (center 16.8 0) (end 17.313 0)
      (stroke (width 1.0262) (type solid)) (fill none) (layer "F.Mask"))
    (fp_circle (center 16.8 5.5) (end 17.313 5.5)
      (stroke (width 1.0262) (type solid)) (fill none) (layer "F.Mask"))
    (fp_poly
      (pts
        (xy -1.026 -1.026)
        (xy 1.026 -1.026)
        (xy 1.026 1.026)
        (xy -1.026 1.026)
      )

      (stroke (width 0.01) (type solid)) (fill solid) (layer "F.Mask"))
    (fp_rect (start -4.1 -3.3) (end 20.9 9.7)
      (stroke (width 0.05) (type solid)) (fill none) (layer "F.CrtYd"))
    (fp_line (start -3.1 8.75) (end -3.1 -0.98)
      (stroke (width 0.15) (type solid)) (layer "F.Fab"))
    (fp_line (start -1.83 -2.25) (end -3.1 -0.98)
      (stroke (width 0.15) (type solid)) (layer "F.Fab"))
    (fp_line (start -1.83 -2.25) (end 19.9 -2.25)
      (stroke (width 0.15) (type solid)) (layer "F.Fab"))
    (fp_line (start -0.4 -3.327) (end 0 -2.627)
      (stroke (width 0.15) (type solid)) (layer "F.Fab"))
    (fp_line (start 0 -2.627) (end 0.4 -3.327)
      (stroke (width 0.15) (type solid)) (layer "F.Fab"))
    (fp_line (start 0.4 -3.327) (end -0.4 -3.327)
      (stroke (width 0.15) (type solid)) (layer "F.Fab"))
    (fp_line (start 19.9 -2.25) (end 19.9 8.75)
      (stroke (width 0.15) (type solid)) (layer "F.Fab"))
    (fp_line (start 19.9 8.75) (end -3.1 8.75)
      (stroke (width 0.15) (type solid)) (layer "F.Fab"))
    (pad "1" thru_hole rect (at 0 0 90) (size 1.9 1.9) (drill 1.4) (layers "*.Cu")
      (net 11 "VCC12V0") (pinfunction "1") (pintype "bidirectional"))
    (pad "2" thru_hole circle (at 4.2 0 90) (size 1.9 1.9) (drill 1.4) (layers "*.Cu")
      (net 11 "VCC12V0") (pinfunction "2") (pintype "bidirectional"))
    (pad "3" thru_hole circle (at 8.4 0 90) (size 1.9 1.9) (drill 1.4) (layers "*.Cu")
      (net 2 "VCC5V0") (pinfunction "3") (pintype "bidirectional"))
    (pad "4" thru_hole circle (at 12.6 0 90) (size 1.9 1.9) (drill 1.4) (layers "*.Cu")
      (net 4 "GND") (pinfunction "4") (pintype "bidirectional"))
    (pad "5" thru_hole circle (at 16.8 0 90) (size 1.9 1.9) (drill 1.4) (layers "*.Cu")
      (net 1 "VCC3V3") (pinfunction "5") (pintype "bidirectional"))
    (pad "6" thru_hole circle (at 0 5.5 90) (size 1.9 1.9) (drill 1.4) (layers "*.Cu")
      (net 4 "GND") (pinfunction "6") (pintype "bidirectional"))
    (pad "7" thru_hole circle (at 4.2 5.5 90) (size 1.9 1.9) (drill 1.4) (layers "*.Cu")
      (net 4 "GND") (pinfunction "7") (pintype "bidirectional"))
    (pad "8" thru_hole circle (at 8.4 5.5 90) (size 1.9 1.9) (drill 1.4) (layers "*.Cu")
      (net 137 "Net-(J9-Pad8)") (pinfunction "8") (pintype "bidirectional"))
    (pad "9" thru_hole circle (at 12.6 5.5 90) (size 1.9 1.9) (drill 1.4) (layers "*.Cu")
      (net 4 "GND") (pinfunction "9") (pintype "bidirectional"))
    (pad "10" thru_hole circle (at 16.8 5.5 90) (size 1.9 1.9) (drill 1.4) (layers "*.Cu")
      (net 1 "VCC3V3") (pinfunction "10") (pintype "bidirectional"))
  )

  (footprint "antmicro-footprints:R_0402_1005Metric" (layer "F.Cu")
    (at 102.35 91.465 -90)
    (descr "Resistor SMD 0402")
    (tags "resistor SMD 0402")
    (property "Author" "Antmicro")
    (property "License" "Apache-2.0")
    (property "MPN" "CR0402-FX-6801GLF")
    (property "Manufacturer" "Bourns")
    (property "Sheetfile" "daughterboard-supply.kicad_sch")
    (property "Sheetname" "daughterboard-supply")
    (property "Tolerance" "1%")
    (property "Val" "6k8")
    (property "ki_description" "SMD Chip Resistor, 6.8 kohm, ± 1%, 63 mW, 0402 [1005 Metric], Thick Film, General Purpose")
    (property "ki_keywords" "0402, SMT, RESISTOR, PASSIVE")
    (attr smd)
    (fp_text reference "R34" (at 1.085 -1.5 -90) (layer "F.SilkS")
        (effects (font (size 0.7 0.7) (thickness 0.15)) (justify left bottom))
    )
    (fp_text value "R_6k8_0402" (at -1.011843 1.772047 -90) (layer "F.Fab")
        (effects (font (size 0.7 0.7) (thickness 0.15)) (justify left bottom))
    )
    (fp_text user "License: Apache-2.0" (at -0.95 5.169 -90) (layer "F.Fab") hide
        (effects (font (size 0.7 0.7) (thickness 0.15)) (justify left bottom))
    )
    (fp_text user "Author: Antmicro" (at -0.95 4.169 -90) (layer "F.Fab") hide
        (effects (font (size 0.7 0.7) (thickness 0.15)) (justify left bottom))
    )
    (fp_text user "${REFERENCE}" (at -0.95 3.168 -90) (layer "F.Fab") hide
        (effects (font (size 0.7 0.7) (thickness 0.15)) (justify left bottom))
    )
    (fp_rect (start -0.925 -0.47) (end 0.925 0.47)
      (stroke (width 0.05) (type default)) (fill none) (layer "F.CrtYd"))
    (fp_rect (start -0.5 -0.25) (end 0.5 0.25)
      (stroke (width 0.15) (type solid)) (fill none) (layer "F.Fab"))
    (pad "1" smd roundrect (at -0.48 0 270) (size 0.59 0.64) (layers "F.Cu" "F.Paste" "F.Mask") (roundrect_rratio 0.25)
      (net 2 "VCC5V0") (pintype "passive"))
    (pad "2" smd roundrect (at 0.48 0 270) (size 0.59 0.64) (layers "F.Cu" "F.Paste" "F.Mask") (roundrect_rratio 0.25)
      (net 111 "Net-(U15-FB)") (pintype "passive"))
  )

  (footprint "antmicro-footprints:R_0402_1005Metric" (layer "F.Cu")
    (at 148.7 91.8 -90)
    (descr "Resistor SMD 0402")
    (tags "resistor SMD 0402")
    (property "Author" "Antmicro")
    (property "License" "Apache-2.0")
    (property "MPN" "CR0402-FX-4701GLF")
    (property "Manufacturer" "Bourns")
    (property "Sheetfile" "power-switch.kicad_sch")
    (property "Sheetname" "Power switch 3")
    (property "Tolerance" "1%")
    (property "Val" "4k7")
    (property "ki_description" "SMD Chip Resistor, 4.7 kohm, ± 1%, 62.5 mW, 0402 [1005 Metric], Thick Film, General Purpose")
    (property "ki_keywords" "0402, SMT, RESISTOR, PASSIVE")
    (zone_connect 1)
    (attr smd)
    (fp_text reference "R29" (at 1.5 -0.1) (layer "F.SilkS")
        (effects (font (size 0.7 0.7) (thickness 0.15)))
    )
    (fp_text value "R_4k7_0402" (at 0 1.17 90) (layer "F.Fab") hide
        (effects (font (size 1 1) (thickness 0.15)))
    )
    (fp_text user "License: Apache-2.0" (at -0.95 5.169 90) (layer "F.Fab") hide
        (effects (font (size 0.7 0.7) (thickness 0.15)) (justify right bottom))
    )
    (fp_text user "${REFERENCE}" (at 0 0 90) (layer "F.Fab")
        (effects (font (size 0.7 0.7) (thickness 0.15)))
    )
    (fp_text user "Author: Antmicro" (at -0.95 4.169 90) (layer "F.Fab") hide
        (effects (font (size 0.7 0.7) (thickness 0.15)) (justify right bottom))
    )
    (fp_rect (start -0.925 -0.47) (end 0.925 0.47)
      (stroke (width 0.05) (type default)) (fill none) (layer "F.CrtYd"))
    (fp_rect (start -0.5 -0.25) (end 0.5 0.25)
      (stroke (width 0.15) (type solid)) (fill none) (layer "F.Fab"))
    (pad "1" smd roundrect (at -0.48 0 270) (size 0.59 0.64) (layers "F.Cu" "F.Paste" "F.Mask") (roundrect_rratio 0.25)
      (net 11 "VCC12V0") (pintype "passive"))
    (pad "2" smd roundrect (at 0.48 0 270) (size 0.59 0.64) (layers "F.Cu" "F.Paste" "F.Mask") (roundrect_rratio 0.25)
      (net 86 "Net-(D18-A)") (pintype "passive"))
  )

  (footprint "antmicro-footprints:SOIC-8_3.9x4.9x1.75mm_P1.27mm" (layer "F.Cu")
    (at 165.25 82.15 180)
    (property "Author" "Antmicro")
    (property "License" "Apache-2.0")
    (property "MPN" "TMCS1100A2QDRQ1")
    (property "Manufacturer" "Texas Instruments")
    (property "Sheetfile" "pow-cycl-curr-meas.kicad_sch")
    (property "Sheetname" "Power Cycling & Current Measurement")
    (property "ki_description" "Hall current Sensor/transducer")
    (property "ki_keywords" "SMT, SENSOR, IC, POWER")
    (attr smd)
    (fp_text reference "U12" (at 1.15 2.85) (layer "F.SilkS")
        (effects (font (size 0.7 0.7) (thickness 0.15)) (justify right bottom))
    )
    (fp_text value "TMCS1100A2-Q1" (at 0 3.65) (layer "F.Fab")
        (effects (font (size 0.7 0.7) (thickness 0.15)) (justify right bottom))
    )
    (fp_text user "${REFERENCE}" (at -3.476 7.099) (layer "F.Fab") hide
        (effects (font (size 0.7 0.7) (thickness 0.15)) (justify right bottom))
    )
    (fp_text user "License: Apache-2.0" (at -3.476 5.099) (layer "F.Fab") hide
        (effects (font (size 0.7 0.7) (thickness 0.15)) (justify right bottom))
    )
    (fp_text user "Author: Antmicro" (at -3.476 6.099) (layer "F.Fab") hide
        (effects (font (size 0.7 0.7) (thickness 0.15)) (justify right bottom))
    )
    (fp_line (start -1.95 -2.452) (end 1.95 -2.45)
      (stroke (width 0.15) (type solid)) (layer "F.SilkS"))
    (fp_line (start -1.95 2.45) (end 1.95 2.45)
      (stroke (width 0.15) (type solid)) (layer "F.SilkS"))
    (fp_circle (center -2.4 -2.45) (end -2.35 -2.4)
      (stroke (width 0.15) (type solid)) (fill solid) (layer "F.SilkS"))
    (fp_rect (start -3.625 -2.7) (end 3.625 2.7)
      (stroke (width 0.05) (type solid)) (fill none) (layer "F.CrtYd"))
    (fp_line (start -1.95 -1.18) (end -0.683 -2.452)
      (stroke (width 0.15) (type solid)) (layer "F.Fab"))
    (fp_line (start -1.95 2.45) (end -1.95 -1.18)
      (stroke (width 0.15) (type solid)) (layer "F.Fab"))
    (fp_line (start -0.683 -2.452) (end 1.949 -2.452)
      (stroke (width 0.15) (type solid)) (layer "F.Fab"))
    (fp_line (start 1.949 -2.452) (end 1.949 2.45)
      (stroke (width 0.15) (type solid)) (layer "F.Fab"))
    (fp_line (start 1.949 2.45) (end -1.95 2.45)
      (stroke (width 0.15) (type solid)) (layer "F.Fab"))
    (pad "1" smd roundrect (at -2.714 -1.905 270) (size 0.65 1.525) (layers "F.Cu" "F.Paste" "F.Mask") (roundrect_rratio 0.25)
      (net 27 "C_MEAS_4") (pinfunction "IN+") (pintype "input"))
    (pad "2" smd roundrect (at -2.714 -0.635 270) (size 0.65 1.525) (layers "F.Cu" "F.Paste" "F.Mask") (roundrect_rratio 0.25)
      (net 27 "C_MEAS_4") (pinfunction "IN+") (pintype "input"))
    (pad "3" smd roundrect (at -2.714 0.632 270) (size 0.65 1.525) (layers "F.Cu" "F.Paste" "F.Mask") (roundrect_rratio 0.25)
      (net 45 "LOAD_4") (pinfunction "IN-") (pintype "input"))
    (pad "4" smd roundrect (at -2.714 1.902 270) (size 0.65 1.525) (layers "F.Cu" "F.Paste" "F.Mask") (roundrect_rratio 0.25)
      (net 45 "LOAD_4") (pinfunction "IN-") (pintype "input"))
    (pad "5" smd roundrect (at 2.712 1.902 270) (size 0.65 1.525) (layers "F.Cu" "F.Paste" "F.Mask") (roundrect_rratio 0.25)
      (net 4 "GND") (pinfunction "GND") (pintype "power_in"))
    (pad "6" smd roundrect (at 2.712 0.632 270) (size 0.65 1.525) (layers "F.Cu" "F.Paste" "F.Mask") (roundrect_rratio 0.25)
      (net 4 "GND") (pinfunction "VREF") (pintype "input"))
    (pad "7" smd roundrect (at 2.712 -0.635 270) (size 0.65 1.525) (layers "F.Cu" "F.Paste" "F.Mask") (roundrect_rratio 0.25)
      (net 49 "/Power Cycling & Current Measurement/C_ADC4") (pinfunction "VOUT") (pintype "output"))
    (pad "8" smd roundrect (at 2.712 -1.905 270) (size 0.65 1.525) (layers "F.Cu" "F.Paste" "F.Mask") (roundrect_rratio 0.25)
      (net 1 "VCC3V3") (pinfunction "VCC") (pintype "power_in"))
  )

  (footprint "antmicro-footprints:R_0402_1005Metric" (layer "F.Cu")
    (at 101.25 92.45 -90)
    (descr "Resistor SMD 0402")
    (tags "resistor SMD 0402")
    (property "Author" "Antmicro")
    (property "License" "Apache-2.0")
    (property "MPN" "CR0402-FX-1301GLF")
    (property "Manufacturer" "Bourns")
    (property "Sheetfile" "daughterboard-supply.kicad_sch")
    (property "Sheetname" "daughterboard-supply")
    (property "Tolerance" "1%")
    (property "Val" "1k3")
    (property "ki_description" "SMD Chip Resistor, 1.3 kohm, ± 1%, 62.5 mW, 0402 [1005 Metric], Thick Film, General Purpose")
    (property "ki_keywords" "0402, SMT, RESISTOR, PASSIVE")
    (attr smd)
    (fp_text reference "R35" (at -0.85 -0.4 -90) (layer "F.SilkS")
        (effects (font (size 0.7 0.7) (thickness 0.15)) (justify left bottom))
    )
    (fp_text value "R_1k3_0402" (at -1.011843 1.772047 -90) (layer "F.Fab")
        (effects (font (size 0.7 0.7) (thickness 0.15)) (justify left bottom))
    )
    (fp_text user "License: Apache-2.0" (at -0.95 5.169 -90) (layer "F.Fab") hide
        (effects (font (size 0.7 0.7) (thickness 0.15)) (justify left bottom))
    )
    (fp_text user "Author: Antmicro" (at -0.95 4.169 -90) (layer "F.Fab") hide
        (effects (font (size 0.7 0.7) (thickness 0.15)) (justify left bottom))
    )
    (fp_text user "${REFERENCE}" (at -0.95 3.168 -90) (layer "F.Fab") hide
        (effects (font (size 0.7 0.7) (thickness 0.15)) (justify left bottom))
    )
    (fp_rect (start -0.925 -0.47) (end 0.925 0.47)
      (stroke (width 0.05) (type default)) (fill none) (layer "F.CrtYd"))
    (fp_rect (start -0.5 -0.25) (end 0.5 0.25)
      (stroke (width 0.15) (type solid)) (fill none) (layer "F.Fab"))
    (pad "1" smd roundrect (at -0.48 0 270) (size 0.59 0.64) (layers "F.Cu" "F.Paste" "F.Mask") (roundrect_rratio 0.25)
      (net 111 "Net-(U15-FB)") (pintype "passive"))
    (pad "2" smd roundrect (at 0.48 0 270) (size 0.59 0.64) (layers "F.Cu" "F.Paste" "F.Mask") (roundrect_rratio 0.25)
      (net 4 "GND") (pintype "passive"))
  )

  (footprint "antmicro-footprints:TP_SMD_1mm" (layer "F.Cu")
    (at 175.6 99)
    (property "Author" "Antmicro")
    (property "License" "Apache-2.0")
    (property "MPN" "")
    (property "Manufacturer" "")
    (property "Sheetfile" "ftdi-module.kicad_sch")
    (property "Sheetname" "FTDI")
    (property "exclude_from_bom" "")
    (property "ki_description" "Test point 1mm SMD")
    (property "ki_keywords" "TESTPOINT")
    (attr exclude_from_pos_files exclude_from_bom)
    (fp_text reference "SCL1" (at -1.825 0 180) (layer "F.SilkS")
        (effects (font (size 0.7 0.7) (thickness 0.15)))
    )
    (fp_text value "TP_1mm_SMD" (at 0 -0.5) (layer "F.Fab") hide
        (effects (font (size 1 1) (thickness 0.15)))
    )
    (fp_text user "${REFERENCE}" (at -0.5 2.8) (layer "F.Fab") hide
        (effects (font (size 0.7 0.7) (thickness 0.15)) (justify left bottom))
    )
    (fp_text user "License: Apache-2.0" (at -0.5 5.2) (layer "F.Fab") hide
        (effects (font (size 0.7 0.7) (thickness 0.15)) (justify left bottom))
    )
    (fp_text user "Author: Antmicro" (at -0.5 4) (layer "F.Fab") hide
        (effects (font (size 0.7 0.7) (thickness 0.15)) (justify left bottom))
    )
    (fp_circle (center 0 0) (end 0.6 0)
      (stroke (width 0.05) (type default)) (fill none) (layer "F.CrtYd"))
    (pad "1" smd circle (at 0 0) (size 1 1) (layers "F.Cu" "F.Mask")
      (net 17 "SCL") (pinfunction "1") (pintype "passive"))
  )

  (footprint "antmicro-footprints:R_0402_1005Metric" (layer "F.Cu")
    (at 165.75 96.5 90)
    (descr "Resistor SMD 0402")
    (tags "resistor SMD 0402")
    (property "Author" "Antmicro")
    (property "Current" "1A")
    (property "DNP" "DNP")
    (property "License" "Apache-2.0")
    (property "MPN" "ERJ2GE0R00X")
    (property "Manufacturer" "Panasonic")
    (property "Sheetfile" "pow-cycl-curr-meas.kicad_sch")
    (property "Sheetname" "Power Cycling & Current Measurement")
    (property "Tolerance" "")
    (property "Val" "0R")
    (property "dnp" "")
    (property "exclude_from_bom" "")
    (property "ki_description" "SMD Chip Resistor, Jumper, 0 ohm, 100 mW, 0402 [1005 Metric], Thick Film, General Purpose")
    (property "ki_keywords" "0402, SMT, RESISTOR, PASSIVE")
    (attr smd exclude_from_bom)
    (fp_text reference "R13" (at 0.85 0.45 90) (layer "F.SilkS")
        (effects (font (size 0.7 0.7) (thickness 0.15)) (justify left bottom))
    )
    (fp_text value "R_0R_0402" (at -1.011843 1.772047 90) (layer "F.Fab")
        (effects (font (size 0.7 0.7) (thickness 0.15)) (justify left bottom))
    )
    (fp_text user "License: Apache-2.0" (at -0.95 5.169 90) (layer "F.Fab") hide
        (effects (font (size 0.7 0.7) (thickness 0.15)) (justify left bottom))
    )
    (fp_text user "Author: Antmicro" (at -0.95 4.169 90) (layer "F.Fab") hide
        (effects (font (size 0.7 0.7) (thickness 0.15)) (justify left bottom))
    )
    (fp_text user "${REFERENCE}" (at -0.95 3.168 90) (layer "F.Fab") hide
        (effects (font (size 0.7 0.7) (thickness 0.15)) (justify left bottom))
    )
    (fp_rect (start -0.925 -0.47) (end 0.925 0.47)
      (stroke (width 0.05) (type default)) (fill none) (layer "F.CrtYd"))
    (fp_rect (start -0.5 -0.25) (end 0.5 0.25)
      (stroke (width 0.15) (type solid)) (fill none) (layer "F.Fab"))
    (pad "1" smd roundrect (at -0.48 0 90) (size 0.59 0.64) (layers "F.Cu" "F.Paste" "F.Mask") (roundrect_rratio 0.25)
      (net 1 "VCC3V3") (pintype "passive"))
    (pad "2" smd roundrect (at 0.48 0 90) (size 0.59 0.64) (layers "F.Cu" "F.Paste" "F.Mask") (roundrect_rratio 0.25)
      (net 105 "Net-(U10-A0)") (pintype "passive"))
  )

  (footprint "antmicro-footprints:R_0402_1005Metric" (layer "F.Cu")
    (at 164.75 92.1 180)
    (descr "Resistor SMD 0402")
    (tags "resistor SMD 0402")
    (property "Author" "Antmicro")
    (property "License" "Apache-2.0")
    (property "MPN" "CR0402-FX-4701GLF")
    (property "Manufacturer" "Bourns")
    (property "Sheetfile" "power-switch.kicad_sch")
    (property "Sheetname" "Power switch 4")
    (property "Tolerance" "1%")
    (property "Val" "4k7")
    (property "ki_description" "SMD Chip Resistor, 4.7 kohm, ± 1%, 62.5 mW, 0402 [1005 Metric], Thick Film, General Purpose")
    (property "ki_keywords" "0402, SMT, RESISTOR, PASSIVE")
    (zone_connect 1)
    (attr smd)
    (fp_text reference "R28" (at 0.05 -1) (layer "F.SilkS")
        (effects (font (size 0.7 0.7) (thickness 0.15)))
    )
    (fp_text value "R_4k7_0402" (at 0 1.17) (layer "F.Fab") hide
        (effects (font (size 1 1) (thickness 0.15)))
    )
    (fp_text user "Author: Antmicro" (at -0.95 4.169) (layer "F.Fab") hide
        (effects (font (size 0.7 0.7) (thickness 0.15)) (justify right bottom))
    )
    (fp_text user "License: Apache-2.0" (at -0.95 5.169) (layer "F.Fab") hide
        (effects (font (size 0.7 0.7) (thickness 0.15)) (justify right bottom))
    )
    (fp_text user "${REFERENCE}" (at 0 0) (layer "F.Fab")
        (effects (font (size 0.7 0.7) (thickness 0.15)))
    )
    (fp_rect (start -0.925 -0.47) (end 0.925 0.47)
      (stroke (width 0.05) (type default)) (fill none) (layer "F.CrtYd"))
    (fp_rect (start -0.5 -0.25) (end 0.5 0.25)
      (stroke (width 0.15) (type solid)) (fill none) (layer "F.Fab"))
    (pad "1" smd roundrect (at -0.48 0 180) (size 0.59 0.64) (layers "F.Cu" "F.Paste" "F.Mask") (roundrect_rratio 0.25)
      (net 11 "VCC12V0") (pintype "passive"))
    (pad "2" smd roundrect (at 0.48 0 180) (size 0.59 0.64) (layers "F.Cu" "F.Paste" "F.Mask") (roundrect_rratio 0.25)
      (net 85 "Net-(D17-A)") (pintype "passive"))
  )

  (footprint "antmicro-footprints:C_0402_1005Metric" (layer "F.Cu")
    (at 176.85 85.6 180)
    (descr "Capacitor SMD 0402")
    (tags "capacitor SMD 0402")
    (property "Author" "Antmicro")
    (property "Dielectric" "X5R")
    (property "License" "Apache-2.0")
    (property "MPN" "GRM155R61H104KE14D")
    (property "Manufacturer" "Murata")
    (property "Sheetfile" "pow-cycl-curr-meas.kicad_sch")
    (property "Sheetname" "Power Cycling & Current Measurement")
    (property "Val" "100n")
    (property "Voltage" "50V")
    (property "ki_description" "SMD Multilayer Ceramic Capacitor, 0.1 µF, 50 V, 0402 [1005 Metric], ± 10%, X5R, GRM Series")
    (property "ki_keywords" "0402, SMT, CAPACITOR, PASSIVE, CERAMIC, MLCC")
    (attr smd)
    (fp_text reference "C29" (at 1.85 1.2) (layer "F.SilkS")
        (effects (font (size 0.7 0.7) (thickness 0.15)))
    )
    (fp_text value "C_100n_0402" (at 0 1.17) (layer "F.Fab") hide
        (effects (font (size 1 1) (thickness 0.15)))
    )
    (fp_text user "${REFERENCE}" (at 0 0) (layer "F.Fab")
        (effects (font (size 0.7 0.7) (thickness 0.15)))
    )
    (fp_text user "License: Apache-2.0" (at -0.939 5.799 180) (layer "F.Fab") hide
        (effects (font (size 0.7 0.7) (thickness 0.15)) (justify left bottom))
    )
    (fp_text user "Author: Antmicro" (at -0.939 3.399 180) (layer "F.Fab") hide
        (effects (font (size 0.7 0.7) (thickness 0.15)) (justify left bottom))
    )
    (fp_rect (start -0.925 -0.47) (end 0.925 0.47)
      (stroke (width 0.05) (type default)) (fill none) (layer "F.CrtYd"))
    (fp_line (start -0.494 -0.25) (end 0.504 -0.25)
      (stroke (width 0.15) (type solid)) (layer "F.Fab"))
    (fp_line (start -0.494 0.248) (end -0.494 -0.25)
      (stroke (width 0.15) (type solid)) (layer "F.Fab"))
    (fp_line (start 0.504 -0.25) (end 0.504 0.248)
      (stroke (width 0.15) (type solid)) (layer "F.Fab"))
    (fp_line (start 0.504 0.248) (end -0.494 0.248)
      (stroke (width 0.15) (type solid)) (layer "F.Fab"))
    (pad "1" smd roundrect (at -0.48 0 180) (size 0.59 0.64) (layers "F.Cu" "F.Paste" "F.Mask") (roundrect_rratio 0.25)
      (net 1 "VCC3V3") (pintype "passive"))
    (pad "2" smd roundrect (at 0.48 0 180) (size 0.59 0.64) (layers "F.Cu" "F.Paste" "F.Mask") (roundrect_rratio 0.25)
      (net 4 "GND") (pintype "passive"))
  )

  (footprint "antmicro-footprints:C_0402_1005Metric" (layer "F.Cu")
    (at 110.05 84.45 -90)
    (descr "Capacitor SMD 0402")
    (tags "capacitor SMD 0402")
    (property "Author" "Antmicro")
    (property "Dielectric" "X5R")
    (property "License" "Apache-2.0")
    (property "MPN" "GRM155R61H104KE14D")
    (property "Manufacturer" "Murata")
    (property "Sheetfile" "pow-cycl-curr-meas.kicad_sch")
    (property "Sheetname" "Power Cycling & Current Measurement")
    (property "Val" "100n")
    (property "Voltage" "50V")
    (property "ki_description" "SMD Multilayer Ceramic Capacitor, 0.1 µF, 50 V, 0402 [1005 Metric], ± 10%, X5R, GRM Series")
    (property "ki_keywords" "0402, SMT, CAPACITOR, PASSIVE, CERAMIC, MLCC")
    (attr smd)
    (fp_text reference "C28" (at 1.95 0.6 -90) (layer "F.SilkS")
        (effects (font (size 0.7 0.7) (thickness 0.15)) (justify left bottom))
    )
    (fp_text value "C_100n_0402" (at -1.022927 2.155213 -90) (layer "F.Fab")
        (effects (font (size 0.7 0.7) (thickness 0.15)) (justify left bottom))
    )
    (fp_text user "License: Apache-2.0" (at -0.939 5.799 -90) (layer "F.Fab") hide
        (effects (font (size 0.7 0.7) (thickness 0.15)) (justify left bottom))
    )
    (fp_text user "${REFERENCE}" (at -0.939 4.599 -90) (layer "F.Fab") hide
        (effects (font (size 0.7 0.7) (thickness 0.15)) (justify left bottom))
    )
    (fp_text user "Author: Antmicro" (at -0.939 3.399 -90) (layer "F.Fab") hide
        (effects (font (size 0.7 0.7) (thickness 0.15)) (justify left bottom))
    )
    (fp_rect (start -0.925 -0.47) (end 0.925 0.47)
      (stroke (width 0.05) (type default)) (fill none) (layer "F.CrtYd"))
    (fp_line (start -0.494 -0.25) (end 0.504 -0.25)
      (stroke (width 0.15) (type solid)) (layer "F.Fab"))
    (fp_line (start -0.494 0.248) (end -0.494 -0.25)
      (stroke (width 0.15) (type solid)) (layer "F.Fab"))
    (fp_line (start 0.504 -0.25) (end 0.504 0.248)
      (stroke (width 0.15) (type solid)) (layer "F.Fab"))
    (fp_line (start 0.504 0.248) (end -0.494 0.248)
      (stroke (width 0.15) (type solid)) (layer "F.Fab"))
    (pad "1" smd roundrect (at -0.48 0 270) (size 0.59 0.64) (layers "F.Cu" "F.Paste" "F.Mask") (roundrect_rratio 0.25)
      (net 1 "VCC3V3") (pintype "passive"))
    (pad "2" smd roundrect (at 0.48 0 270) (size 0.59 0.64) (layers "F.Cu" "F.Paste" "F.Mask") (roundrect_rratio 0.25)
      (net 4 "GND") (pintype "passive"))
  )

  (footprint "antmicro-footprints:TSOT23-6" (layer "F.Cu")
    (at 98.55 91)
    (property "Author" "Antmicro")
    (property "License" "Apache-2.0")
    (property "MPN" "AP62301WU-7")
    (property "Manufacturer" "Diodes Incorporated")
    (property "Sheetfile" "daughterboard-supply.kicad_sch")
    (property "Sheetname" "daughterboard-supply")
    (property "ki_description" "DC-DC Switching Synchronous Buck Regulator, Adjustable, 4.2V-18Vin, 0.8V-7V/3A out, TSOT-26-6")
    (property "ki_keywords" "SMT, PMIC, IC, VOLTAGE")
    (attr smd)
    (fp_text reference "U15" (at -1.15 3.75 90) (layer "F.SilkS")
        (effects (font (size 0.7 0.7) (thickness 0.15)) (justify left bottom))
    )
    (fp_text value "AP62301_TSOT" (at 0 2.6) (layer "F.Fab")
        (effects (font (size 0.7 0.7) (thickness 0.15)) (justify left bottom))
    )
    (fp_text user "Author: Antmicro" (at -1.93 5) (layer "F.Fab") hide
        (effects (font (size 0.7 0.7) (thickness 0.15)) (justify left bottom))
    )
    (fp_text user "${REFERENCE}" (at -1.93 3.8) (layer "F.Fab") hide
        (effects (font (size 0.7 0.7) (thickness 0.15)) (justify left bottom))
    )
    (fp_text user "License: Apache-2.0" (at -1.93 6.199) (layer "F.Fab") hide
        (effects (font (size 0.7 0.7) (thickness 0.15)) (justify left bottom))
    )
    (fp_line (start -1 -1.5) (end -1 -1.375)
      (stroke (width 0.15) (type solid)) (layer "F.SilkS"))
    (fp_line (start -1 1.55) (end -1 1.4)
      (stroke (width 0.15) (type solid)) (layer "F.SilkS"))
    (fp_line (start 1 -1.497) (end -1 -1.5)
      (stroke (width 0.15) (type solid)) (layer "F.SilkS"))
    (fp_line (start 1 -1.497) (end 1 -1.375)
      (stroke (width 0.15) (type solid)) (layer "F.SilkS"))
    (fp_line (start 1 1.55) (end -1 1.55)
      (stroke (width 0.15) (type solid)) (layer "F.SilkS"))
    (fp_line (start 1 1.55) (end 1 1.4)
      (stroke (width 0.15) (type solid)) (layer "F.SilkS"))
    (fp_circle (center -1.44 -1.5) (end -1.39 -1.5)
      (stroke (width 0.15) (type solid)) (fill solid) (layer "F.SilkS"))
    (fp_rect (start 1.93 -1.7) (end -1.93 1.7)
      (stroke (width 0.05) (type solid)) (fill none) (layer "F.CrtYd"))
    (fp_line (start -0.45 -1.521) (end -0.876 -1.096)
      (stroke (width 0.15) (type solid)) (layer "F.Fab"))
    (fp_rect (start 0.875 1.528) (end -0.875 -1.525)
      (stroke (width 0.15) (type solid)) (fill none) (layer "F.Fab"))
    (pad "1" smd rect (at -1.301 -0.947 270) (size 0.7 1.2) (layers "F.Cu" "F.Paste" "F.Mask")
      (net 4 "GND") (pinfunction "GND") (pintype "power_in"))
    (pad "2" smd rect (at -1.301 0.004 270) (size 0.7 1.2) (layers "F.Cu" "F.Paste" "F.Mask")
      (net 13 "Net-(U15-SW)") (pinfunction "SW") (pintype "power_out"))
    (pad "3" smd rect (at -1.301 0.954 270) (size 0.7 1.2) (layers "F.Cu" "F.Paste" "F.Mask")
      (net 11 "VCC12V0") (pinfunction "VIN") (pintype "power_in"))
    (pad "4" smd rect (at 1.299 0.954 270) (size 0.7 1.2) (layers "F.Cu" "F.Paste" "F.Mask")
      (net 111 "Net-(U15-FB)") (pinfunction "FB") (pintype "input"))
    (pad "5" smd rect (at 1.299 0.004 270) (size 0.7 1.2) (layers "F.Cu" "F.Paste" "F.Mask")
      (net 165 "unconnected-(U15-EN-Pad5)") (pinfunction "EN") (pintype "input+no_connect"))
    (pad "6" smd rect (at 1.299 -0.947 270) (size 0.7 1.2) (layers "F.Cu" "F.Paste" "F.Mask")
      (net 12 "Net-(U15-BST)") (pinfunction "BST") (pintype "output"))
  )

  (footprint "antmicro-footprints:R_0402_1005Metric" (layer "F.Cu")
    (at 109.6 86.8)
    (descr "Resistor SMD 0402")
    (tags "resistor SMD 0402")
    (property "Author" "Antmicro")
    (property "License" "Apache-2.0")
    (property "MPN" "CR0402-FX-1002GLF")
    (property "Manufacturer" "Bourns")
    (property "Sheetfile" "power-switch.kicad_sch")
    (property "Sheetname" "Power switch 1")
    (property "Tolerance" "1%")
    (property "Val" "10k")
    (property "ki_description" "SMD Chip Resistor, 10 kohm, ± 1%, 62.5 mW, 0402 [1005 Metric], Thick Film, General Purpose")
    (property "ki_keywords" "0402, SMT, RESISTOR, PASSIVE")
    (attr smd)
    (fp_text reference "R20" (at -3.05 0.45) (layer "F.SilkS")
        (effects (font (size 0.7 0.7) (thickness 0.15)) (justify left bottom))
    )
    (fp_text value "R_10k_0402" (at -1.011843 1.772047) (layer "F.Fab")
        (effects (font (size 0.7 0.7) (thickness 0.15)) (justify left bottom))
    )
    (fp_text user "License: Apache-2.0" (at -0.95 5.169) (layer "F.Fab") hide
        (effects (font (size 0.7 0.7) (thickness 0.15)) (justify left bottom))
    )
    (fp_text user "${REFERENCE}" (at -0.95 3.168) (layer "F.Fab") hide
        (effects (font (size 0.7 0.7) (thickness 0.15)) (justify left bottom))
    )
    (fp_text user "Author: Antmicro" (at -0.95 4.169) (layer "F.Fab") hide
        (effects (font (size 0.7 0.7) (thickness 0.15)) (justify left bottom))
    )
    (fp_rect (start -0.925 -0.47) (end 0.925 0.47)
      (stroke (width 0.05) (type default)) (fill none) (layer "F.CrtYd"))
    (fp_rect (start -0.5 -0.25) (end 0.5 0.25)
      (stroke (width 0.15) (type solid)) (fill none) (layer "F.Fab"))
    (pad "1" smd roundrect (at -0.48 0) (size 0.59 0.64) (layers "F.Cu" "F.Paste" "F.Mask") (roundrect_rratio 0.25)
      (net 1 "VCC3V3") (pintype "passive"))
    (pad "2" smd roundrect (at 0.48 0) (size 0.59 0.64) (layers "F.Cu" "F.Paste" "F.Mask") (roundrect_rratio 0.25)
      (net 23 "/Power Cycling & Current Measurement/PC_1") (pintype "passive"))
  )

  (footprint "antmicro-footprints:C_0402_1005Metric" (layer "F.Cu")
    (at 181.2 115.3)
    (descr "Capacitor SMD 0402")
    (tags "capacitor SMD 0402")
    (property "Author" "Antmicro")
    (property "Dielectric" "X5R")
    (property "License" "Apache-2.0")
    (property "MPN" "GRM155R61H104KE14D")
    (property "Manufacturer" "Murata")
    (property "Sheetfile" "ftdi-module.kicad_sch")
    (property "Sheetname" "FTDI")
    (property "Val" "100n")
    (property "Voltage" "50V")
    (property "ki_description" "SMD Multilayer Ceramic Capacitor, 0.1 µF, 50 V, 0402 [1005 Metric], ± 10%, X5R, GRM Series")
    (property "ki_keywords" "0402, SMT, CAPACITOR, PASSIVE, CERAMIC, MLCC")
    (attr smd)
    (fp_text reference "C17" (at -3 0.5) (layer "F.SilkS")
        (effects (font (size 0.7 0.7) (thickness 0.15)) (justify left bottom))
    )
    (fp_text value "C_100n_0402" (at -1.022927 2.155213) (layer "F.Fab")
        (effects (font (size 0.7 0.7) (thickness 0.15)) (justify left bottom))
    )
    (fp_text user "Author: Antmicro" (at -0.939 3.399) (layer "F.Fab") hide
        (effects (font (size 0.7 0.7) (thickness 0.15)) (justify left bottom))
    )
    (fp_text user "License: Apache-2.0" (at -0.939 5.799) (layer "F.Fab") hide
        (effects (font (size 0.7 0.7) (thickness 0.15)) (justify left bottom))
    )
    (fp_text user "${REFERENCE}" (at -0.939 4.599) (layer "F.Fab") hide
        (effects (font (size 0.7 0.7) (thickness 0.15)) (justify left bottom))
    )
    (fp_rect (start -0.925 -0.47) (end 0.925 0.47)
      (stroke (width 0.05) (type default)) (fill none) (layer "F.CrtYd"))
    (fp_line (start -0.494 -0.25) (end 0.504 -0.25)
      (stroke (width 0.15) (type solid)) (layer "F.Fab"))
    (fp_line (start -0.494 0.248) (end -0.494 -0.25)
      (stroke (width 0.15) (type solid)) (layer "F.Fab"))
    (fp_line (start 0.504 -0.25) (end 0.504 0.248)
      (stroke (width 0.15) (type solid)) (layer "F.Fab"))
    (fp_line (start 0.504 0.248) (end -0.494 0.248)
      (stroke (width 0.15) (type solid)) (layer "F.Fab"))
    (pad "1" smd roundrect (at -0.48 0) (size 0.59 0.64) (layers "F.Cu" "F.Paste" "F.Mask") (roundrect_rratio 0.25)
      (net 77 "GNDD") (pintype "passive"))
    (pad "2" smd roundrect (at 0.48 0) (size 0.59 0.64) (layers "F.Cu" "F.Paste" "F.Mask") (roundrect_rratio 0.25)
      (net 10 "VBUS") (pintype "passive"))
  )

  (footprint "antmicro-footprints:C_0402_1005Metric" (layer "F.Cu")
    (at 155.6 102.235 90)
    (descr "Capacitor SMD 0402")
    (tags "capacitor SMD 0402")
    (property "Author" "Antmicro")
    (property "Dielectric" "")
    (property "License" "Apache-2.0")
    (property "MPN" "C1005X6S1A105K050BC")
    (property "Manufacturer" "TDK")
    (property "Sheetfile" "pow-cycl-curr-meas.kicad_sch")
    (property "Sheetname" "Power Cycling & Current Measurement")
    (property "Val" "1u")
    (property "Voltage" "")
    (property "ki_description" "SMD Multilayer Ceramic Capacitor, 1 µF, 10 V, 0402 [1005 Metric], ± 10%, X6S, C")
    (property "ki_keywords" "0402, SMT, CAPACITOR, PASSIVE, CERAMIC, MLCC")
    (attr smd)
    (fp_text reference "C22" (at 0.035 1 90) (layer "F.SilkS")
        (effects (font (size 0.7 0.7) (thickness 0.15)))
    )
    (fp_text value "C_1u_0402" (at 0 1.17 90) (layer "F.Fab") hide
        (effects (font (size 1 1) (thickness 0.15)))
    )
    (fp_text user "${REFERENCE}" (at 0 0 90) (layer "F.Fab")
        (effects (font (size 0.7 0.7) (thickness 0.15)))
    )
    (fp_text user "Author: Antmicro" (at -0.939 3.399 90) (layer "F.Fab") hide
        (effects (font (size 0.7 0.7) (thickness 0.15)) (justify left bottom))
    )
    (fp_text user "License: Apache-2.0" (at -0.939 5.799 90) (layer "F.Fab") hide
        (effects (font (size 0.7 0.7) (thickness 0.15)) (justify left bottom))
    )
    (fp_rect (start -0.925 -0.47) (end 0.925 0.47)
      (stroke (width 0.05) (type default)) (fill none) (layer "F.CrtYd"))
    (fp_line (start -0.494 -0.25) (end 0.504 -0.25)
      (stroke (width 0.15) (type solid)) (layer "F.Fab"))
    (fp_line (start -0.494 0.248) (end -0.494 -0.25)
      (stroke (width 0.15) (type solid)) (layer "F.Fab"))
    (fp_line (start 0.504 -0.25) (end 0.504 0.248)
      (stroke (width 0.15) (type solid)) (layer "F.Fab"))
    (fp_line (start 0.504 0.248) (end -0.494 0.248)
      (stroke (width 0.15) (type solid)) (layer "F.Fab"))
    (pad "1" smd roundrect (at -0.48 0 90) (size 0.59 0.64) (layers "F.Cu" "F.Paste" "F.Mask") (roundrect_rratio 0.25)
      (net 4 "GND") (pintype "passive"))
    (pad "2" smd roundrect (at 0.48 0 90) (size 0.59 0.64) (layers "F.Cu" "F.Paste" "F.Mask") (roundrect_rratio 0.25)
      (net 1 "VCC3V3") (pintype "passive"))
  )

  (footprint "antmicro-footprints:TPD2E009DRTR" (layer "F.Cu")
    (at 181.3875 113.45 180)
    (property "Author" "Antmicro")
    (property "License" "Apache-2.0")
    (property "MPN" "PESD5V0S2BQA")
    (property "Manufacturer" "Nexperia")
    (property "Sheetfile" "ftdi-module.kicad_sch")
    (property "Sheetname" "FTDI")
    (property "ki_description" "TVS diode array, 30 kV, SOT-1215, 5V, 45 pF")
    (property "ki_keywords" "SMT, DIODE, SEMICONDUCTOR, TVS, ESD")
    (attr smd)
    (fp_text reference "D1" (at 2.6875 -0.6 180) (layer "F.SilkS")
        (effects (font (size 0.7 0.7) (thickness 0.15)) (justify left bottom))
    )
    (fp_text value "PESD5V0S2BQA" (at 5.608 1.306 180) (layer "F.Fab")
        (effects (font (size 0.7 0.7) (thickness 0.15)) (justify left bottom))
    )
    (fp_text user "License: Apache-2.0" (at -0.949 5.706 180) (layer "F.Fab") hide
        (effects (font (size 0.7 0.7) (thickness 0.15)) (justify left bottom))
    )
    (fp_text user "${REFERENCE}" (at -0.949 4.506 180) (layer "F.Fab") hide
        (effects (font (size 0.7 0.7) (thickness 0.15)) (justify left bottom))
    )
    (fp_text user "Author: Antmicro" (at -0.949 3.306 180) (layer "F.Fab") hide
        (effects (font (size 0.7 0.7) (thickness 0.15)) (justify left bottom))
    )
    (fp_line (start 0.03 -0.499) (end 0.4 -0.499)
      (stroke (width 0.15) (type solid)) (layer "F.SilkS"))
    (fp_line (start 0.03 0.499) (end 0.4 0.499)
      (stroke (width 0.15) (type solid)) (layer "F.SilkS"))
    (fp_line (start 0.4 -0.419) (end 0.4 -0.499)
      (stroke (width 0.15) (type solid)) (layer "F.SilkS"))
    (fp_line (start 0.4 0.42) (end 0.4 0.499)
      (stroke (width 0.15) (type solid)) (layer "F.SilkS"))
    (fp_circle (center -0.5 -0.6) (end -0.45 -0.6)
      (stroke (width 0.15) (type solid)) (fill solid) (layer "F.SilkS"))
    (fp_rect (start -0.8 -0.59) (end 0.8 0.59)
      (stroke (width 0.05) (type solid)) (fill none) (layer "F.CrtYd"))
    (fp_line (start -0.4 -0.499) (end 0.4 -0.499)
      (stroke (width 0.15) (type solid)) (layer "F.Fab"))
    (fp_line (start -0.4 0.499) (end -0.4 -0.499)
      (stroke (width 0.15) (type solid)) (layer "F.Fab"))
    (fp_line (start 0.4 -0.499) (end 0.4 0.499)
      (stroke (width 0.15) (type solid)) (layer "F.Fab"))
    (fp_line (start 0.4 0.499) (end -0.4 0.499)
      (stroke (width 0.15) (type solid)) (layer "F.Fab"))
    (pad "1" smd rect (at -0.52 -0.349 180) (size 0.46 0.2) (layers "F.Cu" "F.Paste" "F.Mask")
      (net 15 "/FTDI/USB_D-") (pinfunction "IO1") (pintype "passive"))
    (pad "2" smd rect (at -0.52 0.348 180) (size 0.46 0.2) (layers "F.Cu" "F.Paste" "F.Mask")
      (net 14 "/FTDI/USB_D+") (pinfunction "IO2") (pintype "passive"))
    (pad "3" smd rect (at 0.52 0 180) (size 0.46 0.2) (layers "F.Cu" "F.Paste" "F.Mask")
      (net 77 "GNDD") (pinfunction "GND") (pintype "passive"))
  )

  (footprint "antmicro-footprints:LED_0603_1608Metric_G" (layer "F.Cu")
    (at 181.75 108.45 -90)
    (descr "LED SMD 0603 Green")
    (tags "LED SMD 0603 Green")
    (property "Author" "Antmicro")
    (property "Color" "Green")
    (property "License" "Apache-2.0")
    (property "MPN" "LG L29K-G2J1-24-Z")
    (property "Manufacturer" "OSRAM")
    (property "Sheetfile" "ftdi-module.kicad_sch")
    (property "Sheetname" "FTDI")
    (property "ki_description" "LED, Green, SMD, 0603, 20 mA, 1.7 V, 570 nm")
    (property "ki_keywords" "SMT, DIODE, SEMICONDUCTOR, LED")
    (attr smd)
    (fp_text reference "D2" (at -1.35 0.75) (layer "F.SilkS")
        (effects (font (size 0.7 0.7) (thickness 0.15)) (justify left bottom))
    )
    (fp_text value "LED_G_0603_LG_L29K-G2J1-24-Z" (at -0.001 1.599 -90) (layer "F.Fab")
        (effects (font (size 0.7 0.7) (thickness 0.15)) (justify left bottom))
    )
    (fp_text user "Author: Antmicro" (at -1.4224 4.799 -90) (layer "F.Fab") hide
        (effects (font (size 0.7 0.7) (thickness 0.15)) (justify left bottom))
    )
    (fp_text user "${REFERENCE}" (at -1.4224 5.999 -90) (layer "F.Fab") hide
        (effects (font (size 0.7 0.7) (thickness 0.15)) (justify left bottom))
    )
    (fp_text user "License: Apache-2.0" (at -1.4224 3.599 -90) (layer "F.Fab") hide
        (effects (font (size 0.7 0.7) (thickness 0.15)) (justify left bottom))
    )
    (fp_line (start -1.18 -0.319) (end -1.18 0.321)
      (stroke (width 0.15) (type solid)) (layer "F.SilkS"))
    (fp_line (start -0.094672 0.001008) (end -0.24 0.001008)
      (stroke (width 0.1) (type solid)) (layer "F.SilkS"))
    (fp_line (start -0.094672 0.001008) (end 0.105328 -0.198992)
      (stroke (width 0.1) (type solid)) (layer "F.SilkS"))
    (fp_line (start -0.094672 0.201008) (end -0.094672 -0.198992)
      (stroke (width 0.1) (type solid)) (layer "F.SilkS"))
    (fp_line (start 0.105328 0.001008) (end 0.24 0.001)
      (stroke (width 0.1) (type solid)) (layer "F.SilkS"))
    (fp_line (start 0.105328 0.201008) (end -0.094672 0.001008)
      (stroke (width 0.1) (type solid)) (layer "F.SilkS"))
    (fp_line (start 0.105328 0.201008) (end 0.105328 -0.198992)
      (stroke (width 0.1) (type solid)) (layer "F.SilkS"))
    (fp_line (start 0.22 -0.35) (end -0.22 -0.35)
      (stroke (width 0.15) (type solid)) (layer "F.SilkS"))
    (fp_line (start 0.22 0.35) (end -0.22 0.35)
      (stroke (width 0.15) (type solid)) (layer "F.SilkS"))
    (fp_rect (start 1.25 0.65) (end -1.25 -0.65)
      (stroke (width 0.05) (type solid)) (fill none) (layer "F.CrtYd"))
    (fp_line (start -0.199 -0.202) (end -0.199 0.1)
      (stroke (width 0.15) (type solid)) (layer "F.Fab"))
    (fp_line (start -0.199 0) (end -0.597 0)
      (stroke (width 0.15) (type solid)) (layer "F.Fab"))
    (fp_line (start -0.199 0.2) (end -0.199 0.1)
      (stroke (width 0.15) (type solid)) (layer "F.Fab"))
    (fp_line (start -0.101 0) (end 0.201 0.2)
      (stroke (width 0.15) (type solid)) (layer "F.Fab"))
    (fp_line (start 0.201 -0.202) (end -0.101 0)
      (stroke (width 0.15) (type solid)) (layer "F.Fab"))
    (fp_line (start 0.201 0) (end 0.201 -0.202)
      (stroke (width 0.15) (type solid)) (layer "F.Fab"))
    (fp_line (start 0.201 0.2) (end 0.201 0)
      (stroke (width 0.15) (type solid)) (layer "F.Fab"))
    (fp_line (start 0.599 0) (end 0.201 0)
      (stroke (width 0.15) (type solid)) (layer "F.Fab"))
    (fp_rect (start 0.848 0.4) (end -0.85 -0.402)
      (stroke (width 0.15) (type solid)) (fill none) (layer "F.Fab"))
    (pad "1" smd roundrect (at -0.7 0 90) (size 0.8 1) (layers "F.Cu" "F.Paste" "F.Mask") (roundrect_rratio 0.2)
      (net 77 "GNDD") (pinfunction "C") (pintype "passive"))
    (pad "2" smd roundrect (at 0.7 0 90) (size 0.8 1) (layers "F.Cu" "F.Paste" "F.Mask") (roundrect_rratio 0.2)
      (net 35 "Net-(D2-A)") (pinfunction "A") (pintype "passive"))
  )

  (footprint "antmicro-footprints:FB_0603_1608Metric" (layer "F.Cu")
    (at 183.2 108.45 90)
    (property "Author" "Antmicro")
    (property "Current" "")
    (property "License" "Apache-2.0")
    (property "MPN" "BLM18AG601SN1D")
    (property "Manufacturer" "Murata")
    (property "Sheetfile" "ftdi-module.kicad_sch")
    (property "Sheetname" "FTDI")
    (property "Val" "600Z/0.5A")
    (property "ki_description" "Ferrite Bead, 0603 [1608 Metric], 600 ohm, 500 mA, BLM18A, 0.38 ohm, ± 25%, General use")
    (property "ki_keywords" "0603, SMT, FERRITE BEAD, PASSIVE")
    (attr smd)
    (fp_text reference "FB3" (at 1.25 0.45 90) (layer "F.SilkS")
        (effects (font (size 0.7 0.7) (thickness 0.15)) (justify left bottom))
    )
    (fp_text value "FB_600Z_0.5A_Murata-BLM18AG_0603" (at 0 1.5 90) (layer "F.Fab")
        (effects (font (size 0.7 0.7) (thickness 0.15)) (justify left bottom))
    )
    (fp_text user "${REFERENCE}" (at -1.653 4.6 90) (layer "F.Fab") hide
        (effects (font (size 0.7 0.7) (thickness 0.15)) (justify left bottom))
    )
    (fp_text user "Author: Antmicro" (at -1.653 3.162 90) (layer "F.Fab") hide
        (effects (font (size 0.7 0.7) (thickness 0.15)) (justify left bottom))
    )
    (fp_text user "License: Apache-2.0" (at -1.653 5.9 90) (layer "F.Fab") hide
        (effects (font (size 0.7 0.7) (thickness 0.15)) (justify left bottom))
    )
    (fp_line (start -0.15 -0.4) (end 0.15 -0.4)
      (stroke (width 0.15) (type solid)) (layer "F.SilkS"))
    (fp_line (start -0.15 0.4) (end 0.15 0.4)
      (stroke (width 0.15) (type solid)) (layer "F.SilkS"))
    (fp_rect (start -1.25 -0.65) (end 1.25 0.65)
      (stroke (width 0.05) (type solid)) (fill none) (layer "F.CrtYd"))
    (fp_line (start -0.803 0.406) (end -0.803 -0.408)
      (stroke (width 0.15) (type solid)) (layer "F.Fab"))
    (fp_line (start 0.8 -0.408) (end -0.803 -0.408)
      (stroke (width 0.15) (type solid)) (layer "F.Fab"))
    (fp_line (start 0.8 -0.408) (end 0.8 0.406)
      (stroke (width 0.15) (type solid)) (layer "F.Fab"))
    (fp_line (start 0.8 0.406) (end -0.803 0.406)
      (stroke (width 0.15) (type solid)) (layer "F.Fab"))
    (pad "1" smd roundrect (at -0.7 0 90) (size 0.8 1) (layers "F.Cu" "F.Paste" "F.Mask") (roundrect_rratio 0.2)
      (net 136 "Net-(FB3-Pad1)") (pintype "passive"))
    (pad "2" smd roundrect (at 0.7 0 90) (size 0.8 1) (layers "F.Cu" "F.Paste" "F.Mask") (roundrect_rratio 0.2)
      (net 77 "GNDD") (pintype "passive"))
  )

  (footprint "antmicro-footprints:Conn_JST_SH_1x4_BM04B-SRSS-TB-LF-SN" (layer "F.Cu")
    (at 185.625 102.75)
    (property "Author" "Antmicro")
    (property "License" "Apache-2.0")
    (property "MPN" "BM04B-SRSS-TB(LF)(SN) ")
    (property "Manufacturer" "JST Automotive Connectors")
    (property "Sheetfile" "d1600e-psu-breakout-board.kicad_sch")
    (property "Sheetname" "")
    (property "ki_description" "Pin Header, Top Entry, Wire-to-Board, 1 mm, 1 Rows, 4 Contacts, Surface Mount, SR")
    (property "ki_keywords" "VERTICAL, SMT, WIRE-BOARD, CONNECTOR")
    (attr smd)
    (fp_text reference "J3" (at 2.925 0.55 90) (layer "F.SilkS")
        (effects (font (size 0.7 0.7) (thickness 0.15)) (justify left bottom))
    )
    (fp_text value "JST_SH_1x4_BM04B-SRSS-TB-LF-SN" (at -3.25 5) (layer "F.Fab")
        (effects (font (size 0.7 0.7) (thickness 0.15)) (justify left bottom))
    )
    (fp_text user "Author: Antmicro" (at -3.25 7) (layer "F.Fab") hide
        (effects (font (size 0.7 0.7) (thickness 0.15)) (justify left bottom))
    )
    (fp_text user "License: Apache-2.0" (at -3.25 9.4) (layer "F.Fab") hide
        (effects (font (size 0.7 0.7) (thickness 0.15)) (justify left bottom))
    )
    (fp_text user "${REFERENCE}" (at -3.25 8.2) (layer "F.Fab") hide
        (effects (font (size 0.7 0.7) (thickness 0.15)) (justify left bottom))
    )
    (fp_line (start -1.125 -2.999) (end -1.125 -2.201)
      (stroke (width 0.15) (type solid)) (layer "F.SilkS"))
    (fp_line (start -1.125 2.999) (end -1.125 2.201)
      (stroke (width 0.15) (type solid)) (layer "F.SilkS"))
    (fp_line (start -0.251 -2.999) (end -1.125 -2.999)
      (stroke (width 0.15) (type solid)) (layer "F.SilkS"))
    (fp_line (start -0.251 2.999) (end -1.125 2.999)
      (stroke (width 0.15) (type solid)) (layer "F.SilkS"))
    (fp_line (start 1.774 -1.7) (end 1.774 1.702)
      (stroke (width 0.15) (type solid)) (layer "F.SilkS"))
    (fp_circle (center -1.6 -2.1) (end -1.55 -2.1)
      (stroke (width 0.15) (type solid)) (fill solid) (layer "F.SilkS"))
    (fp_rect (start -2.05 -3.95) (end 2.05 3.95)
      (stroke (width 0.05) (type solid)) (fill none) (layer "F.CrtYd"))
    (fp_rect (start -1.8 -3) (end 1.8 3)
      (stroke (width 0.15) (type solid)) (fill none) (layer "F.Fab"))
    (pad "1" smd roundrect (at -1.45 -1.5 270) (size 0.6 1.55) (layers "F.Cu" "F.Paste" "F.Mask") (roundrect_rratio 0.25)
      (net 20 "Net-(J3-Pad1)") (pintype "passive"))
    (pad "2" smd roundrect (at -1.45 -0.5 270) (size 0.6 1.55) (layers "F.Cu" "F.Paste" "F.Mask") (roundrect_rratio 0.25)
      (net 99 "SDA_CON") (pintype "passive"))
    (pad "3" smd roundrect (at -1.45 0.5 270) (size 0.6 1.55) (layers "F.Cu" "F.Paste" "F.Mask") (roundrect_rratio 0.25)
      (net 17 "SCL") (pintype "passive"))
    (pad "4" smd roundrect (at -1.45 1.5 270) (size 0.6 1.55) (layers "F.Cu" "F.Paste" "F.Mask") (roundrect_rratio 0.25)
      (net 4 "GND") (pintype "passive"))
    (pad "MP" smd roundrect (at 1.075 -2.8 270) (size 1.2 1.8) (layers "F.Cu" "F.Paste" "F.Mask") (roundrect_rratio 0.25)
      (net 91 "unconnected-(J3-PadMP)") (pintype "passive+no_connect"))
    (pad "MP" smd roundrect (at 1.075 2.8 270) (size 1.2 1.8) (layers "F.Cu" "F.Paste" "F.Mask") (roundrect_rratio 0.25)
      (net 91 "unconnected-(J3-PadMP)") (pintype "passive+no_connect"))
  )

  (footprint "antmicro-footprints:R_0402_1005Metric" (layer "F.Cu")
    (at 180.3 109.65 -90)
    (descr "Resistor SMD 0402")
    (tags "resistor SMD 0402")
    (property "Author" "Antmicro")
    (property "License" "Apache-2.0")
    (property "MPN" "CR0402-FX-3300GLF")
    (property "Manufacturer" "Bourns")
    (property "Sheetfile" "ftdi-module.kicad_sch")
    (property "Sheetname" "FTDI")
    (property "Tolerance" "1%")
    (property "Val" "330R")
    (property "ki_description" "SMD Chip Resistor, 330 ohm, ± 1%, 62.5 mW, 0402 [1005 Metric], Thick Film, General Purpose")
    (property "ki_keywords" "0402, SMT, RESISTOR, PASSIVE")
    (attr smd)
    (fp_text reference "R7" (at 1.9 0.45 -90) (layer "F.SilkS")
        (effects (font (size 0.7 0.7) (thickness 0.15)) (justify left bottom))
    )
    (fp_text value "R_330R_0402" (at -1.011843 1.772047 -90) (layer "F.Fab")
        (effects (font (size 0.7 0.7) (thickness 0.15)) (justify left bottom))
    )
    (fp_text user "License: Apache-2.0" (at -0.95 5.169 -90) (layer "F.Fab") hide
        (effects (font (size 0.7 0.7) (thickness 0.15)) (justify left bottom))
    )
    (fp_text user "Author: Antmicro" (at -0.95 4.169 -90) (layer "F.Fab") hide
        (effects (font (size 0.7 0.7) (thickness 0.15)) (justify left bottom))
    )
    (fp_text user "${REFERENCE}" (at -0.95 3.168 -90) (layer "F.Fab") hide
        (effects (font (size 0.7 0.7) (thickness 0.15)) (justify left bottom))
    )
    (fp_rect (start -0.925 -0.47) (end 0.925 0.47)
      (stroke (width 0.05) (type default)) (fill none) (layer "F.CrtYd"))
    (fp_rect (start -0.5 -0.25) (end 0.5 0.25)
      (stroke (width 0.15) (type solid)) (fill none) (layer "F.Fab"))
    (pad "1" smd roundrect (at -0.48 0 270) (size 0.59 0.64) (layers "F.Cu" "F.Paste" "F.Mask") (roundrect_rratio 0.25)
      (net 76 "VCC3V3_USB") (pintype "passive"))
    (pad "2" smd roundrect (at 0.48 0 270) (size 0.59 0.64) (layers "F.Cu" "F.Paste" "F.Mask") (roundrect_rratio 0.25)
      (net 35 "Net-(D2-A)") (pintype "passive"))
  )

  (footprint "antmicro-footprints:R_0603_1608Metric" (layer "F.Cu")
    (at 183.2 116.05 -90)
    (descr "Resistor SMD 0603")
    (tags "resistor SMD 0603")
    (property "Author" "Antmicro")
    (property "Current" "1A")
    (property "License" "Apache-2.0")
    (property "MPN" "CR0603-J/-000ELF")
    (property "Manufacturer" "Bourns")
    (property "Sheetfile" "ftdi-module.kicad_sch")
    (property "Sheetname" "FTDI")
    (property "Tolerance" "")
    (property "Val" "0R")
    (property "ki_description" "Zero Ohm Resistor, Jumper, 0603 [1608 Metric], Thick Film, 100 mW, 1 A, Surface Mount Device, CR")
    (property "ki_keywords" "0603, SMT, RESISTOR, PASSIVE")
    (attr smd)
    (fp_text reference "R8" (at -1.25 -1 -90) (layer "F.SilkS")
        (effects (font (size 0.7 0.7) (thickness 0.15)) (justify left bottom))
    )
    (fp_text value "R_0R_0603" (at 0 1.6 -90) (layer "F.Fab")
        (effects (font (size 0.7 0.7) (thickness 0.15)) (justify left bottom))
    )
    (fp_text user "${REFERENCE}" (at -1.25 3.898 -90) (layer "F.Fab") hide
        (effects (font (size 0.7 0.7) (thickness 0.15)) (justify left bottom))
    )
    (fp_text user "License: Apache-2.0" (at -1.25 5.9 -90) (layer "F.Fab") hide
        (effects (font (size 0.7 0.7) (thickness 0.15)) (justify left bottom))
    )
    (fp_text user "Author: Antmicro" (at -1.25 4.9 -90) (layer "F.Fab") hide
        (effects (font (size 0.7 0.7) (thickness 0.15)) (justify left bottom))
    )
    (fp_line (start -0.15 -0.4) (end 0.15 -0.4)
      (stroke (width 0.15) (type solid)) (layer "F.SilkS"))
    (fp_line (start -0.15 0.4) (end 0.15 0.4)
      (stroke (width 0.15) (type solid)) (layer "F.SilkS"))
    (fp_rect (start -1.25 -0.65) (end 1.25 0.65)
      (stroke (width 0.05) (type solid)) (fill none) (layer "F.CrtYd"))
    (fp_rect (start -0.8 -0.4) (end 0.8 0.4)
      (stroke (width 0.15) (type solid)) (fill none) (layer "F.Fab"))
    (pad "1" smd roundrect (at -0.7 0 270) (size 0.8 1) (layers "F.Cu" "F.Paste" "F.Mask") (roundrect_rratio 0.2)
      (net 10 "VBUS") (pintype "passive"))
    (pad "2" smd roundrect (at 0.7 0 270) (size 0.8 1) (layers "F.Cu" "F.Paste" "F.Mask") (roundrect_rratio 0.2)
      (net 3 "VCC5V0_USB") (pintype "passive"))
  )

  (footprint "antmicro-footprints:R_0402_1005Metric" (layer "F.Cu")
    (at 182.25 99.515 -90)
    (descr "Resistor SMD 0402")
    (tags "resistor SMD 0402")
    (property "Author" "Antmicro")
    (property "Current" "1A")
    (property "DNP" "DNP")
    (property "License" "Apache-2.0")
    (property "MPN" "ERJ2GE0R00X")
    (property "Manufacturer" "Panasonic")
    (property "Sheetfile" "d1600e-psu-breakout-board.kicad_sch")
    (property "Sheetname" "")
    (property "Tolerance" "")
    (property "Val" "0R")
    (property "dnp" "")
    (property "exclude_from_bom" "")
    (property "ki_description" "SMD Chip Resistor, Jumper, 0 ohm, 100 mW, 0402 [1005 Metric], Thick Film, General Purpose")
    (property "ki_keywords" "0402, SMT, RESISTOR, PASSIVE")
    (attr smd exclude_from_bom)
    (fp_text reference "R10" (at -0.025 0.93 90) (layer "F.SilkS")
        (effects (font (size 0.7 0.7) (thickness 0.15)))
    )
    (fp_text value "R_0R_0402" (at 0 1.17 90) (layer "F.Fab") hide
        (effects (font (size 1 1) (thickness 0.15)))
    )
    (fp_text user "Author: Antmicro" (at -0.95 4.169 -90) (layer "F.Fab") hide
        (effects (font (size 0.7 0.7) (thickness 0.15)) (justify left bottom))
    )
    (fp_text user "${REFERENCE}" (at 0 0 90) (layer "F.Fab")
        (effects (font (size 0.7 0.7) (thickness 0.15)))
    )
    (fp_text user "License: Apache-2.0" (at -0.95 5.169 -90) (layer "F.Fab") hide
        (effects (font (size 0.7 0.7) (thickness 0.15)) (justify left bottom))
    )
    (fp_rect (start -0.925 -0.47) (end 0.925 0.47)
      (stroke (width 0.05) (type default)) (fill none) (layer "F.CrtYd"))
    (fp_rect (start -0.5 -0.25) (end 0.5 0.25)
      (stroke (width 0.15) (type solid)) (fill none) (layer "F.Fab"))
    (pad "1" smd roundrect (at -0.48 0 270) (size 0.59 0.64) (layers "F.Cu" "F.Paste" "F.Mask") (roundrect_rratio 0.25)
      (net 1 "VCC3V3") (pintype "passive"))
    (pad "2" smd roundrect (at 0.48 0 270) (size 0.59 0.64) (layers "F.Cu" "F.Paste" "F.Mask") (roundrect_rratio 0.25)
      (net 20 "Net-(J3-Pad1)") (pintype "passive"))
  )

  (footprint "antmicro-footprints:TSSOP-16_4.4x5mm_P0.65mm" (layer "F.Cu")
    (at 160 99.25 -90)
    (property "Author" "Antmicro")
    (property "License" "Apache-2.0")
    (property "MPN" "TCA9534PWR")
    (property "Manufacturer" "Texas Instruments")
    (property "Sheetfile" "pow-cycl-curr-meas.kicad_sch")
    (property "Sheetname" "Power Cycling & Current Measurement")
    (property "ki_description" "Low Voltage 8-Bit I2C and SMBUS Low-Power I/O Expander with Interrupt Output and Configuration Registers")
    (property "ki_keywords" "SMT, INTERFACE, IC, I2C")
    (attr smd)
    (fp_text reference "U10" (at 0.6 2.9 -90) (layer "F.SilkS")
        (effects (font (size 0.7 0.7) (thickness 0.15)) (justify left bottom))
    )
    (fp_text value "TCA9534PWR_TSSOP" (at 0.001 3.749 -90) (layer "F.Fab")
        (effects (font (size 0.7 0.7) (thickness 0.15)) (justify left bottom))
    )
    (fp_text user "Author: Antmicro" (at -3.81 6.949 -90) (layer "F.Fab") hide
        (effects (font (size 0.7 0.7) (thickness 0.15)) (justify left bottom))
    )
    (fp_text user "License: Apache-2.0" (at -3.81 5.749 -90) (layer "F.Fab") hide
        (effects (font (size 0.7 0.7) (thickness 0.15)) (justify left bottom))
    )
    (fp_text user "${REFERENCE}" (at -3.81 8.149 -90) (layer "F.Fab") hide
        (effects (font (size 0.7 0.7) (thickness 0.15)) (justify left bottom))
    )
    (fp_line (start -2.149 -2.735) (end 2.25 -2.735)
      (stroke (width 0.15) (type solid)) (layer "F.SilkS"))
    (fp_line (start 0.051 2.733) (end -2.149 2.733)
      (stroke (width 0.15) (type solid)) (layer "F.SilkS"))
    (fp_line (start 0.051 2.733) (end 2.25 2.733)
      (stroke (width 0.15) (type solid)) (layer "F.SilkS"))
    (fp_circle (center -2.815 -3.05) (end -2.765 -3.05)
      (stroke (width 0.15) (type solid)) (fill solid) (layer "F.SilkS"))
    (fp_line (start -3.81 -2.75) (end -3.81 2.74)
      (stroke (width 0.05) (type solid)) (layer "F.CrtYd"))
    (fp_line (start -3.81 2.74) (end 3.89 2.74)
      (stroke (width 0.05) (type solid)) (layer "F.CrtYd"))
    (fp_line (start 3.89 -2.75) (end -3.81 -2.75)
      (stroke (width 0.05) (type solid)) (layer "F.CrtYd"))
    (fp_line (start 3.89 2.74) (end 3.89 -2.75)
      (stroke (width 0.05) (type solid)) (layer "F.CrtYd"))
    (fp_line (start -2.149 -1.5) (end -1.15 -2.5)
      (stroke (width 0.15) (type solid)) (layer "F.Fab"))
    (fp_line (start -2.149 2.499) (end -2.149 -1.5)
      (stroke (width 0.15) (type solid)) (layer "F.Fab"))
    (fp_line (start -1.15 -2.5) (end 2.25 -2.5)
      (stroke (width 0.15) (type solid)) (layer "F.Fab"))
    (fp_line (start 2.25 -2.5) (end 2.25 2.499)
      (stroke (width 0.15) (type solid)) (layer "F.Fab"))
    (fp_line (start 2.25 2.499) (end -2.149 2.499)
      (stroke (width 0.15) (type solid)) (layer "F.Fab"))
    (pad "1" smd rect (at -2.815 -2.275 270) (size 1.475 0.4) (layers "F.Cu" "F.Paste" "F.Mask")
      (net 105 "Net-(U10-A0)") (pinfunction "A0") (pintype "input"))
    (pad "2" smd rect (at -2.815 -1.625 270) (size 1.475 0.4) (layers "F.Cu" "F.Paste" "F.Mask")
      (net 106 "Net-(U10-A1)") (pinfunction "A1") (pintype "input"))
    (pad "3" smd rect (at -2.815 -0.975 270) (size 1.475 0.4) (layers "F.Cu" "F.Paste" "F.Mask")
      (net 107 "Net-(U10-A2)") (pinfunction "A2") (pintype "input"))
    (pad "4" smd rect (at -2.815 -0.325 270) (size 1.475 0.4) (layers "F.Cu" "F.Paste" "F.Mask")
      (net 26 "/Power Cycling & Current Measurement/PC_5") (pinfunction "P0") (pintype "bidirectional"))
    (pad "5" smd rect (at -2.815 0.325 270) (size 1.475 0.4) (layers "F.Cu" "F.Paste" "F.Mask")
      (net 29 "/Power Cycling & Current Measurement/PC_4") (pinfunction "P1") (pintype "bidirectional"))
    (pad "6" smd rect (at -2.815 0.975 270) (size 1.475 0.4) (layers "F.Cu" "F.Paste" "F.Mask")
      (net 30 "/Power Cycling & Current Measurement/PC_3") (pinfunction "P2") (pintype "bidirectional"))
    (pad "7" smd rect (at -2.815 1.625 270) (size 1.475 0.4) (layers "F.Cu" "F.Paste" "F.Mask")
      (net 24 "/Power Cycling & Current Measurement/PC_2") (pinfunction "P3") (pintype "bidirectional"))
    (pad "8" smd rect (at -2.815 2.275 270) (size 1.475 0.4) (layers "F.Cu" "F.Paste" "F.Mask")
      (net 4 "GND") (pinfunction "GND") (pintype "power_in"))
    (pad "9" smd rect (at 2.91 2.275 270) (size 1.475 0.4) (layers "F.Cu" "F.Paste" "F.Mask")
      (net 23 "/Power Cycling & Current Measurement/PC_1") (pinfunction "P4") (pintype "bidirectional"))
    (pad "10" smd rect (at 2.91 1.625 270) (size 1.475 0.4) (layers "F.Cu" "F.Paste" "F.Mask")
      (net 160 "unconnected-(U10-P5-Pad10)") (pinfunction "P5") (pintype "bidirectional+no_connect"))
    (pad "11" smd rect (at 2.91 0.975 270) (size 1.475 0.4) (layers "F.Cu" "F.Paste" "F.Mask")
      (net 161 "unconnected-(U10-P6-Pad11)") (pinfunction "P6") (pintype "bidirectional+no_connect"))
    (pad "12" smd rect (at 2.91 0.325 270) (size 1.475 0.4) (layers "F.Cu" "F.Paste" "F.Mask")
      (net 162 "unconnected-(U10-P7-Pad12)") (pinfunction "P7") (pintype "bidirectional+no_connect"))
    (pad "13" smd rect (at 2.91 -0.325 270) (size 1.475 0.4) (layers "F.Cu" "F.Paste" "F.Mask")
      (net 108 "Net-(U10-~{INT})") (pinfunction "~{INT}") (pintype "open_collector"))
    (pad "14" smd rect (at 2.91 -0.975 270) (size 1.475 0.4) (layers "F.Cu" "F.Paste" "F.Mask")
      (net 17 "SCL") (pinfunction "SCL") (pintype "input"))
    (pad "15" smd rect (at 2.91 -1.625 270) (size 1.475 0.4) (layers "F.Cu" "F.Paste" "F.Mask")
      (net 18 "SDA") (pinfunction "SDA") (pintype "bidirectional"))
    (pad "16" smd rect (at 2.91 -2.275 270) (size 1.475 0.4) (layers "F.Cu" "F.Paste" "F.Mask")
      (net 1 "VCC3V3") (pinfunction "VCC") (pintype "power_in"))
  )

  (footprint "antmicro-footprints:TSSOP-16_4.4x5mm_P0.65mm" (layer "F.Cu")
    (at 152.1 99.25 -90)
    (property "Author" "Antmicro")
    (property "License" "Apache-2.0")
    (property "MPN" "ADS7828E/250")
    (property "Manufacturer" "Texas Instruments")
    (property "Sheetfile" "pow-cycl-curr-meas.kicad_sch")
    (property "Sheetname" "Power Cycling & Current Measurement")
    (property "ki_description" "8 channel12-bit ADC with I2C, 2V7-5V")
    (property "ki_keywords" "SMT, CONVERTER, IC, ADC, I2C")
    (attr smd)
    (fp_text reference "U14" (at 1.55 -3.75 -90) (layer "F.SilkS")
        (effects (font (size 0.7 0.7) (thickness 0.15)) (justify left bottom))
    )
    (fp_text value "ADS7828" (at 0.001 3.749 -90) (layer "F.Fab")
        (effects (font (size 0.7 0.7) (thickness 0.15)) (justify left bottom))
    )
    (fp_text user "${REFERENCE}" (at -3.81 8.149 -90) (layer "F.Fab") hide
        (effects (font (size 0.7 0.7) (thickness 0.15)) (justify left bottom))
    )
    (fp_text user "Author: Antmicro" (at -3.81 6.949 -90) (layer "F.Fab") hide
        (effects (font (size 0.7 0.7) (thickness 0.15)) (justify left bottom))
    )
    (fp_text user "License: Apache-2.0" (at -3.81 5.749 -90) (layer "F.Fab") hide
        (effects (font (size 0.7 0.7) (thickness 0.15)) (justify left bottom))
    )
    (fp_line (start -2.149 -2.735) (end 2.25 -2.735)
      (stroke (width 0.15) (type solid)) (layer "F.SilkS"))
    (fp_line (start 0.051 2.733) (end -2.149 2.733)
      (stroke (width 0.15) (type solid)) (layer "F.SilkS"))
    (fp_line (start 0.051 2.733) (end 2.25 2.733)
      (stroke (width 0.15) (type solid)) (layer "F.SilkS"))
    (fp_circle (center -2.815 -3.05) (end -2.765 -3.05)
      (stroke (width 0.15) (type solid)) (fill solid) (layer "F.SilkS"))
    (fp_line (start -3.81 -2.75) (end -3.81 2.74)
      (stroke (width 0.05) (type solid)) (layer "F.CrtYd"))
    (fp_line (start -3.81 2.74) (end 3.89 2.74)
      (stroke (width 0.05) (type solid)) (layer "F.CrtYd"))
    (fp_line (start 3.89 -2.75) (end -3.81 -2.75)
      (stroke (width 0.05) (type solid)) (layer "F.CrtYd"))
    (fp_line (start 3.89 2.74) (end 3.89 -2.75)
      (stroke (width 0.05) (type solid)) (layer "F.CrtYd"))
    (fp_line (start -2.149 -1.5) (end -1.15 -2.5)
      (stroke (width 0.15) (type solid)) (layer "F.Fab"))
    (fp_line (start -2.149 2.499) (end -2.149 -1.5)
      (stroke (width 0.15) (type solid)) (layer "F.Fab"))
    (fp_line (start -1.15 -2.5) (end 2.25 -2.5)
      (stroke (width 0.15) (type solid)) (layer "F.Fab"))
    (fp_line (start 2.25 -2.5) (end 2.25 2.499)
      (stroke (width 0.15) (type solid)) (layer "F.Fab"))
    (fp_line (start 2.25 2.499) (end -2.149 2.499)
      (stroke (width 0.15) (type solid)) (layer "F.Fab"))
    (pad "1" smd rect (at -2.815 -2.275 270) (size 1.475 0.4) (layers "F.Cu" "F.Paste" "F.Mask")
      (net 50 "/Power Cycling & Current Measurement/C_ADC5") (pinfunction "CH0") (pintype "input"))
    (pad "2" smd rect (at -2.815 -1.625 270) (size 1.475 0.4) (layers "F.Cu" "F.Paste" "F.Mask")
      (net 49 "/Power Cycling & Current Measurement/C_ADC4") (pinfunction "CH1") (pintype "input"))
    (pad "3" smd rect (at -2.815 -0.975 270) (size 1.475 0.4) (layers "F.Cu" "F.Paste" "F.Mask")
      (net 48 "/Power Cycling & Current Measurement/C_ADC3") (pinfunction "CH2") (pintype "input"))
    (pad "4" smd rect (at -2.815 -0.325 270) (size 1.475 0.4) (layers "F.Cu" "F.Paste" "F.Mask")
      (net 47 "/Power Cycling & Current Measurement/C_ADC2") (pinfunction "CH3") (pintype "input"))
    (pad "5" smd rect (at -2.815 0.325 270) (size 1.475 0.4) (layers "F.Cu" "F.Paste" "F.Mask")
      (net 46 "/Power Cycling & Current Measurement/C_ADC1") (pinfunction "CH4") (pintype "input"))
    (pad "6" smd rect (at -2.815 0.975 270) (size 1.475 0.4) (layers "F.Cu" "F.Paste" "F.Mask")
      (net 163 "unconnected-(U14-CH5-Pad6)") (pinfunction "CH5") (pintype "input+no_connect"))
    (pad "7" smd rect (at -2.815 1.625 270) (size 1.475 0.4) (layers "F.Cu" "F.Paste" "F.Mask")
      (net 164 "unconnected-(U14-CH6-Pad7)") (pinfunction "CH6") (pintype "input+no_connect"))
    (pad "8" smd rect (at -2.815 2.275 270) (size 1.475 0.4) (layers "F.Cu" "F.Paste" "F.Mask")
      (net 90 "/Power Cycling & Current Measurement/V_ADC1") (pinfunction "CH7") (pintype "input"))
    (pad "9" smd rect (at 2.91 2.275 270) (size 1.475 0.4) (layers "F.Cu" "F.Paste" "F.Mask")
      (net 4 "GND") (pinfunction "GND") (pintype "power_in"))
    (pad "10" smd rect (at 2.91 1.625 270) (size 1.475 0.4) (layers "F.Cu" "F.Paste" "F.Mask")
      (net 34 "Net-(U14-REF)") (pinfunction "REF") (pintype "bidirectional"))
    (pad "11" smd rect (at 2.91 0.975 270) (size 1.475 0.4) (layers "F.Cu" "F.Paste" "F.Mask")
      (net 4 "GND") (pinfunction "COM") (pintype "input"))
    (pad "12" smd rect (at 2.91 0.325 270) (size 1.475 0.4) (layers "F.Cu" "F.Paste" "F.Mask")
      (net 110 "Net-(U14-A0)") (pinfunction "A0") (pintype "input"))
    (pad "13" smd rect (at 2.91 -0.325 270) (size 1.475 0.4) (layers "F.Cu" "F.Paste" "F.Mask")
      (net 109 "Net-(U14-A1)") (pinfunction "A1") (pintype "input"))
    (pad "14" smd rect (at 2.91 -0.975 270) (size 1.475 0.4) (layers "F.Cu" "F.Paste" "F.Mask")
      (net 17 "SCL") (pinfunction "SCL") (pintype "input"))
    (pad "15" smd rect (at 2.91 -1.625 270) (size 1.475 0.4) (layers "F.Cu" "F.Paste" "F.Mask")
      (net 18 "SDA") (pinfunction "SDA") (pintype "bidirectional"))
    (pad "16" smd rect (at 2.91 -2.275 270) (size 1.475 0.4) (layers "F.Cu" "F.Paste" "F.Mask")
      (net 1 "VCC3V3") (pinfunction "VDD") (pintype "power_in"))
  )

  (footprint "antmicro-footprints:R_0402_1005Metric" (layer "F.Cu")
    (at 159.8 103.8)
    (descr "Resistor SMD 0402")
    (tags "resistor SMD 0402")
    (property "Author" "Antmicro")
    (property "License" "Apache-2.0")
    (property "MPN" "CR0402-FX-4701GLF")
    (property "Manufacturer" "Bourns")
    (property "Sheetfile" "pow-cycl-curr-meas.kicad_sch")
    (property "Sheetname" "Power Cycling & Current Measurement")
    (property "Tolerance" "1%")
    (property "Val" "4k7")
    (property "ki_description" "SMD Chip Resistor, 4.7 kohm, ± 1%, 62.5 mW, 0402 [1005 Metric], Thick Film, General Purpose")
    (property "ki_keywords" "0402, SMT, RESISTOR, PASSIVE")
    (attr smd)
    (fp_text reference "R19" (at -1.1 1.45) (layer "F.SilkS")
        (effects (font (size 0.7 0.7) (thickness 0.15)) (justify left bottom))
    )
    (fp_text value "R_4k7_0402" (at -1.011843 1.772047) (layer "F.Fab")
        (effects (font (size 0.7 0.7) (thickness 0.15)) (justify left bottom))
    )
    (fp_text user "License: Apache-2.0" (at -0.95 5.169) (layer "F.Fab") hide
        (effects (font (size 0.7 0.7) (thickness 0.15)) (justify left bottom))
    )
    (fp_text user "${REFERENCE}" (at -0.95 3.168) (layer "F.Fab") hide
        (effects (font (size 0.7 0.7) (thickness 0.15)) (justify left bottom))
    )
    (fp_text user "Author: Antmicro" (at -0.95 4.169) (layer "F.Fab") hide
        (effects (font (size 0.7 0.7) (thickness 0.15)) (justify left bottom))
    )
    (fp_rect (start -0.925 -0.47) (end 0.925 0.47)
      (stroke (width 0.05) (type default)) (fill none) (layer "F.CrtYd"))
    (fp_rect (start -0.5 -0.25) (end 0.5 0.25)
      (stroke (width 0.15) (type solid)) (fill none) (layer "F.Fab"))
    (pad "1" smd roundrect (at -0.48 0) (size 0.59 0.64) (layers "F.Cu" "F.Paste" "F.Mask") (roundrect_rratio 0.25)
      (net 1 "VCC3V3") (pintype "passive"))
    (pad "2" smd roundrect (at 0.48 0) (size 0.59 0.64) (layers "F.Cu" "F.Paste" "F.Mask") (roundrect_rratio 0.25)
      (net 108 "Net-(U10-~{INT})") (pintype "passive"))
  )

  (footprint "antmicro-footprints:TP_SMD_1mm" (layer "F.Cu")
    (at 126.4 82.0008)
    (property "Author" "Antmicro")
    (property "License" "Apache-2.0")
    (property "MPN" "")
    (property "Manufacturer" "")
    (property "Sheetfile" "pow-cycl-curr-meas.kicad_sch")
    (property "Sheetname" "Power Cycling & Current Measurement")
    (property "exclude_from_bom" "")
    (property "ki_description" "Test point 1mm SMD")
    (property "ki_keywords" "TESTPOINT")
    (attr exclude_from_pos_files exclude_from_bom)
    (fp_text reference "TP_ADC2" (at 0 -0.731898) (layer "F.SilkS") hide
        (effects (font (size 0.7 0.7) (thickness 0.15)) (justify left bottom))
    )
    (fp_text value "TP_1mm_SMD" (at 0 1.4) (layer "F.Fab")
        (effects (font (size 0.7 0.7) (thickness 0.15)) (justify left bottom))
    )
    (fp_text user "License: Apache-2.0" (at -0.5 5.2) (layer "F.Fab") hide
        (effects (font (size 0.7 0.7) (thickness 0.15)) (justify left bottom))
    )
    (fp_text user "${REFERENCE}" (at -0.5 2.8) (layer "F.Fab") hide
        (effects (font (size 0.7 0.7) (thickness 0.15)) (justify left bottom))
    )
    (fp_text user "Author: Antmicro" (at -0.5 4) (layer "F.Fab") hide
        (effects (font (size 0.7 0.7) (thickness 0.15)) (justify left bottom))
    )
    (fp_circle (center 0 0) (end 0.6 0)
      (stroke (width 0.05) (type default)) (fill none) (layer "F.CrtYd"))
    (pad "1" smd circle (at 0 0) (size 1 1) (layers "F.Cu" "F.Mask")
      (net 47 "/Power Cycling & Current Measurement/C_ADC2") (pinfunction "1") (pintype "passive"))
  )

  (footprint "antmicro-footprints:TP_SMD_1mm" (layer "F.Cu")
    (at 142.35 82.2008)
    (property "Author" "Antmicro")
    (property "License" "Apache-2.0")
    (property "MPN" "")
    (property "Manufacturer" "")
    (property "Sheetfile" "pow-cycl-curr-meas.kicad_sch")
    (property "Sheetname" "Power Cycling & Current Measurement")
    (property "exclude_from_bom" "")
    (property "ki_description" "Test point 1mm SMD")
    (property "ki_keywords" "TESTPOINT")
    (attr exclude_from_pos_files exclude_from_bom)
    (fp_text reference "TP_ADC3" (at 0 -0.731898) (layer "F.SilkS") hide
        (effects (font (size 0.7 0.7) (thickness 0.15)) (justify left bottom))
    )
    (fp_text value "TP_1mm_SMD" (at 0 1.4) (layer "F.Fab")
        (effects (font (size 0.7 0.7) (thickness 0.15)) (justify left bottom))
    )
    (fp_text user "Author: Antmicro" (at -0.5 4) (layer "F.Fab") hide
        (effects (font (size 0.7 0.7) (thickness 0.15)) (justify left bottom))
    )
    (fp_text user "License: Apache-2.0" (at -0.5 5.2) (layer "F.Fab") hide
        (effects (font (size 0.7 0.7) (thickness 0.15)) (justify left bottom))
    )
    (fp_text user "${REFERENCE}" (at -0.5 2.8) (layer "F.Fab") hide
        (effects (font (size 0.7 0.7) (thickness 0.15)) (justify left bottom))
    )
    (fp_circle (center 0 0) (end 0.6 0)
      (stroke (width 0.05) (type default)) (fill none) (layer "F.CrtYd"))
    (pad "1" smd circle (at 0 0) (size 1 1) (layers "F.Cu" "F.Mask")
      (net 48 "/Power Cycling & Current Measurement/C_ADC3") (pinfunction "1") (pintype "passive"))
  )

  (footprint "antmicro-footprints:TP_SMD_1mm" (layer "F.Cu")
    (at 159.35 82.0508)
    (property "Author" "Antmicro")
    (property "License" "Apache-2.0")
    (property "MPN" "")
    (property "Manufacturer" "")
    (property "Sheetfile" "pow-cycl-curr-meas.kicad_sch")
    (property "Sheetname" "Power Cycling & Current Measurement")
    (property "exclude_from_bom" "")
    (property "ki_description" "Test point 1mm SMD")
    (property "ki_keywords" "TESTPOINT")
    (attr exclude_from_pos_files exclude_from_bom)
    (fp_text reference "TP_ADC4" (at 0 -0.731898) (layer "F.SilkS") hide
        (effects (font (size 0.7 0.7) (thickness 0.15)) (justify left bottom))
    )
    (fp_text value "TP_1mm_SMD" (at 0 1.4) (layer "F.Fab")
        (effects (font (size 0.7 0.7) (thickness 0.15)) (justify left bottom))
    )
    (fp_text user "License: Apache-2.0" (at -0.5 5.2) (layer "F.Fab") hide
        (effects (font (size 0.7 0.7) (thickness 0.15)) (justify left bottom))
    )
    (fp_text user "${REFERENCE}" (at -0.5 2.8) (layer "F.Fab") hide
        (effects (font (size 0.7 0.7) (thickness 0.15)) (justify left bottom))
    )
    (fp_text user "Author: Antmicro" (at -0.5 4) (layer "F.Fab") hide
        (effects (font (size 0.7 0.7) (thickness 0.15)) (justify left bottom))
    )
    (fp_circle (center 0 0) (end 0.6 0)
      (stroke (width 0.05) (type default)) (fill none) (layer "F.CrtYd"))
    (pad "1" smd circle (at 0 0) (size 1 1) (layers "F.Cu" "F.Mask")
      (net 49 "/Power Cycling & Current Measurement/C_ADC4") (pinfunction "1") (pintype "passive"))
  )

  (footprint "antmicro-footprints:TP_SMD_1mm" (layer "F.Cu")
    (at 175.55 82.2508)
    (property "Author" "Antmicro")
    (property "License" "Apache-2.0")
    (property "MPN" "")
    (property "Manufacturer" "")
    (property "Sheetfile" "pow-cycl-curr-meas.kicad_sch")
    (property "Sheetname" "Power Cycling & Current Measurement")
    (property "exclude_from_bom" "")
    (property "ki_description" "Test point 1mm SMD")
    (property "ki_keywords" "TESTPOINT")
    (attr exclude_from_pos_files exclude_from_bom)
    (fp_text reference "TP_ADC5" (at 0 -0.731898) (layer "F.SilkS") hide
        (effects (font (size 0.7 0.7) (thickness 0.15)) (justify left bottom))
    )
    (fp_text value "TP_1mm_SMD" (at 0 1.4) (layer "F.Fab")
        (effects (font (size 0.7 0.7) (thickness 0.15)) (justify left bottom))
    )
    (fp_text user "${REFERENCE}" (at -0.5 2.8) (layer "F.Fab") hide
        (effects (font (size 0.7 0.7) (thickness 0.15)) (justify left bottom))
    )
    (fp_text user "License: Apache-2.0" (at -0.5 5.2) (layer "F.Fab") hide
        (effects (font (size 0.7 0.7) (thickness 0.15)) (justify left bottom))
    )
    (fp_text user "Author: Antmicro" (at -0.5 4) (layer "F.Fab") hide
        (effects (font (size 0.7 0.7) (thickness 0.15)) (justify left bottom))
    )
    (fp_circle (center 0 0) (end 0.6 0)
      (stroke (width 0.05) (type default)) (fill none) (layer "F.CrtYd"))
    (pad "1" smd circle (at 0 0) (size 1 1) (layers "F.Cu" "F.Mask")
      (net 50 "/Power Cycling & Current Measurement/C_ADC5") (pinfunction "1") (pintype "passive"))
  )

  (footprint "antmicro-footprints:TP_SMD_1mm" (layer "F.Cu")
    (at 159.8 91.45)
    (property "Author" "Antmicro")
    (property "License" "Apache-2.0")
    (property "MPN" "")
    (property "Manufacturer" "")
    (property "Sheetfile" "pow-cycl-curr-meas.kicad_sch")
    (property "Sheetname" "Power Cycling & Current Measurement")
    (property "exclude_from_bom" "")
    (property "ki_description" "Test point 1mm SMD")
    (property "ki_keywords" "TESTPOINT")
    (attr exclude_from_pos_files exclude_from_bom)
    (fp_text reference "TP_PC3" (at -2.65 -0.0008) (layer "F.SilkS") hide
        (effects (font (size 0.7 0.7) (thickness 0.15)))
    )
    (fp_text value "TP_1mm_SMD" (at 0 -0.5) (layer "F.Fab") hide
        (effects (font (size 1 1) (thickness 0.15)))
    )
    (fp_text user "Author: Antmicro" (at -0.5 4) (layer "F.Fab") hide
        (effects (font (size 0.7 0.7) (thickness 0.15)) (justify left bottom))
    )
    (fp_text user "License: Apache-2.0" (at -0.5 5.2) (layer "F.Fab") hide
        (effects (font (size 0.7 0.7) (thickness 0.15)) (justify left bottom))
    )
    (fp_text user "${REFERENCE}" (at -0.5 2.8) (layer "F.Fab") hide
        (effects (font (size 0.7 0.7) (thickness 0.15)) (justify left bottom))
    )
    (fp_circle (center 0 0) (end 0.6 0)
      (stroke (width 0.05) (type default)) (fill none) (layer "F.CrtYd"))
    (pad "1" smd circle (at 0 0) (size 1 1) (layers "F.Cu" "F.Mask")
      (net 30 "/Power Cycling & Current Measurement/PC_3") (pinfunction "1") (pintype "passive"))
  )

  (footprint "antmicro-footprints:TP_SMD_1mm" (layer "F.Cu")
    (at 160.87 93.57)
    (property "Author" "Antmicro")
    (property "License" "Apache-2.0")
    (property "MPN" "")
    (property "Manufacturer" "")
    (property "Sheetfile" "pow-cycl-curr-meas.kicad_sch")
    (property "Sheetname" "Power Cycling & Current Measurement")
    (property "exclude_from_bom" "")
    (property "ki_description" "Test point 1mm SMD")
    (property "ki_keywords" "TESTPOINT")
    (attr exclude_from_pos_files exclude_from_bom)
    (fp_text reference "TP_PC4" (at -1.4 -1.2) (layer "F.SilkS") hide
        (effects (font (size 0.7 0.7) (thickness 0.15)))
    )
    (fp_text value "TP_1mm_SMD" (at 0 -0.5) (layer "F.Fab") hide
        (effects (font (size 1 1) (thickness 0.15)))
    )
    (fp_text user "${REFERENCE}" (at -0.5 2.8) (layer "F.Fab") hide
        (effects (font (size 0.7 0.7) (thickness 0.15)) (justify left bottom))
    )
    (fp_text user "Author: Antmicro" (at -0.5 4) (layer "F.Fab") hide
        (effects (font (size 0.7 0.7) (thickness 0.15)) (justify left bottom))
    )
    (fp_text user "License: Apache-2.0" (at -0.5 5.2) (layer "F.Fab") hide
        (effects (font (size 0.7 0.7) (thickness 0.15)) (justify left bottom))
    )
    (fp_circle (center 0 0) (end 0.6 0)
      (stroke (width 0.05) (type default)) (fill none) (layer "F.CrtYd"))
    (pad "1" smd circle (at 0 0) (size 1 1) (layers "F.Cu" "F.Mask")
      (net 29 "/Power Cycling & Current Measurement/PC_4") (pinfunction "1") (pintype "passive"))
  )

  (footprint "antmicro-footprints:TP_SMD_1mm" (layer "F.Cu")
    (at 161.4 92.3508)
    (property "Author" "Antmicro")
    (property "License" "Apache-2.0")
    (property "MPN" "")
    (property "Manufacturer" "")
    (property "Sheetfile" "pow-cycl-curr-meas.kicad_sch")
    (property "Sheetname" "Power Cycling & Current Measurement")
    (property "exclude_from_bom" "")
    (property "ki_description" "Test point 1mm SMD")
    (property "ki_keywords" "TESTPOINT")
    (attr exclude_from_pos_files exclude_from_bom)
    (fp_text reference "TP_PC5" (at 2.6 0.05) (layer "F.SilkS") hide
        (effects (font (size 0.7 0.7) (thickness 0.15)))
    )
    (fp_text value "TP_1mm_SMD" (at 0 -0.5) (layer "F.Fab") hide
        (effects (font (size 1 1) (thickness 0.15)))
    )
    (fp_text user "License: Apache-2.0" (at -0.5 5.2) (layer "F.Fab") hide
        (effects (font (size 0.7 0.7) (thickness 0.15)) (justify left bottom))
    )
    (fp_text user "${REFERENCE}" (at -0.5 2.8) (layer "F.Fab") hide
        (effects (font (size 0.7 0.7) (thickness 0.15)) (justify left bottom))
    )
    (fp_text user "Author: Antmicro" (at -0.5 4) (layer "F.Fab") hide
        (effects (font (size 0.7 0.7) (thickness 0.15)) (justify left bottom))
    )
    (fp_circle (center 0 0) (end 0.6 0)
      (stroke (width 0.05) (type default)) (fill none) (layer "F.CrtYd"))
    (pad "1" smd circle (at 0 0) (size 1 1) (layers "F.Cu" "F.Mask")
      (net 26 "/Power Cycling & Current Measurement/PC_5") (pinfunction "1") (pintype "passive"))
  )

  (footprint "antmicro-footprints:TP_SMD_1mm" (layer "F.Cu")
    (at 108.85 82.0508)
    (property "Author" "Antmicro")
    (property "License" "Apache-2.0")
    (property "MPN" "")
    (property "Manufacturer" "")
    (property "Sheetfile" "pow-cycl-curr-meas.kicad_sch")
    (property "Sheetname" "Power Cycling & Current Measurement")
    (property "exclude_from_bom" "")
    (property "ki_description" "Test point 1mm SMD")
    (property "ki_keywords" "TESTPOINT")
    (attr exclude_from_pos_files exclude_from_bom)
    (fp_text reference "TP_ADC1" (at 0 -0.731898) (layer "F.SilkS") hide
        (effects (font (size 0.7 0.7) (thickness 0.15)) (justify left bottom))
    )
    (fp_text value "TP_1mm_SMD" (at 0 1.4) (layer "F.Fab")
        (effects (font (size 0.7 0.7) (thickness 0.15)) (justify left bottom))
    )
    (fp_text user "Author: Antmicro" (at -0.5 4) (layer "F.Fab") hide
        (effects (font (size 0.7 0.7) (thickness 0.15)) (justify left bottom))
    )
    (fp_text user "${REFERENCE}" (at -0.5 2.8) (layer "F.Fab") hide
        (effects (font (size 0.7 0.7) (thickness 0.15)) (justify left bottom))
    )
    (fp_text user "License: Apache-2.0" (at -0.5 5.2) (layer "F.Fab") hide
        (effects (font (size 0.7 0.7) (thickness 0.15)) (justify left bottom))
    )
    (fp_circle (center 0 0) (end 0.6 0)
      (stroke (width 0.05) (type default)) (fill none) (layer "F.CrtYd"))
    (pad "1" smd circle (at 0 0) (size 1 1) (layers "F.Cu" "F.Mask")
      (net 46 "/Power Cycling & Current Measurement/C_ADC1") (pinfunction "1") (pintype "passive"))
  )

  (footprint "antmicro-footprints:TP_SMD_1mm" (layer "F.Cu")
    (at 158.55 93.0508)
    (property "Author" "Antmicro")
    (property "License" "Apache-2.0")
    (property "MPN" "")
    (property "Manufacturer" "")
    (property "Sheetfile" "pow-cycl-curr-meas.kicad_sch")
    (property "Sheetname" "Power Cycling & Current Measurement")
    (property "exclude_from_bom" "")
    (property "ki_description" "Test point 1mm SMD")
    (property "ki_keywords" "TESTPOINT")
    (attr exclude_from_pos_files exclude_from_bom)
    (fp_text reference "TP_PC2" (at -2.5 0.3992) (layer "F.SilkS") hide
        (effects (font (size 0.7 0.7) (thickness 0.15)))
    )
    (fp_text value "TP_1mm_SMD" (at 0 -0.5) (layer "F.Fab") hide
        (effects (font (size 1 1) (thickness 0.15)))
    )
    (fp_text user "License: Apache-2.0" (at -0.5 5.2) (layer "F.Fab") hide
        (effects (font (size 0.7 0.7) (thickness 0.15)) (justify left bottom))
    )
    (fp_text user "Author: Antmicro" (at -0.5 4) (layer "F.Fab") hide
        (effects (font (size 0.7 0.7) (thickness 0.15)) (justify left bottom))
    )
    (fp_text user "${REFERENCE}" (at -0.5 2.8) (layer "F.Fab") hide
        (effects (font (size 0.7 0.7) (thickness 0.15)) (justify left bottom))
    )
    (fp_circle (center 0 0) (end 0.6 0)
      (stroke (width 0.05) (type default)) (fill none) (layer "F.CrtYd"))
    (pad "1" smd circle (at 0 0) (size 1 1) (layers "F.Cu" "F.Mask")
      (net 24 "/Power Cycling & Current Measurement/PC_2") (pinfunction "1") (pintype "passive"))
  )

  (footprint "antmicro-footprints:TP_SMD_1mm" (layer "F.Cu")
    (at 157.2 94.3008)
    (property "Author" "Antmicro")
    (property "License" "Apache-2.0")
    (property "MPN" "")
    (property "Manufacturer" "")
    (property "Sheetfile" "pow-cycl-curr-meas.kicad_sch")
    (property "Sheetname" "Power Cycling & Current Measurement")
    (property "exclude_from_bom" "")
    (property "ki_description" "Test point 1mm SMD")
    (property "ki_keywords" "TESTPOINT")
    (attr exclude_from_pos_files exclude_from_bom)
    (fp_text reference "TP_PC1" (at 2.45 -0.0508) (layer "F.SilkS") hide
        (effects (font (size 0.7 0.7) (thickness 0.15)))
    )
    (fp_text value "TP_1mm_SMD" (at 0 -0.5) (layer "F.Fab") hide
        (effects (font (size 1 1) (thickness 0.15)))
    )
    (fp_text user "${REFERENCE}" (at -0.5 2.8) (layer "F.Fab") hide
        (effects (font (size 0.7 0.7) (thickness 0.15)) (justify left bottom))
    )
    (fp_text user "Author: Antmicro" (at -0.5 4) (layer "F.Fab") hide
        (effects (font (size 0.7 0.7) (thickness 0.15)) (justify left bottom))
    )
    (fp_text user "License: Apache-2.0" (at -0.5 5.2) (layer "F.Fab") hide
        (effects (font (size 0.7 0.7) (thickness 0.15)) (justify left bottom))
    )
    (fp_circle (center 0 0) (end 0.6 0)
      (stroke (width 0.05) (type default)) (fill none) (layer "F.CrtYd"))
    (pad "1" smd circle (at 0 0) (size 1 1) (layers "F.Cu" "F.Mask")
      (net 23 "/Power Cycling & Current Measurement/PC_1") (pinfunction "1") (pintype "passive"))
  )

  (footprint "antmicro-footprints:R_0402_1005Metric" (layer "F.Cu")
    (at 103.8 136 -90)
    (descr "Resistor SMD 0402")
    (tags "resistor SMD 0402")
    (property "Author" "Antmicro")
    (property "License" "Apache-2.0")
    (property "MPN" "CR0402-FX-1002GLF")
    (property "Manufacturer" "Bourns")
    (property "Sheetfile" "d1600e-psu-breakout-board.kicad_sch")
    (property "Sheetname" "")
    (property "Tolerance" "1%")
    (property "Val" "10k")
    (property "ki_description" "SMD Chip Resistor, 10 kohm, ± 1%, 62.5 mW, 0402 [1005 Metric], Thick Film, General Purpose")
    (property "ki_keywords" "0402, SMT, RESISTOR, PASSIVE")
    (attr smd)
    (fp_text reference "R40" (at 1.1 -1.6 -90) (layer "F.SilkS")
        (effects (font (size 0.7 0.7) (thickness 0.15)) (justify left bottom))
    )
    (fp_text value "R_10k_0402" (at -1.011843 1.772047 -90) (layer "F.Fab")
        (effects (font (size 0.7 0.7) (thickness 0.15)) (justify left bottom))
    )
    (fp_text user "Author: Antmicro" (at -0.95 4.169 -90) (layer "F.Fab") hide
        (effects (font (size 0.7 0.7) (thickness 0.15)) (justify left bottom))
    )
    (fp_text user "${REFERENCE}" (at -0.95 3.168 -90) (layer "F.Fab") hide
        (effects (font (size 0.7 0.7) (thickness 0.15)) (justify left bottom))
    )
    (fp_text user "License: Apache-2.0" (at -0.95 5.169 -90) (layer "F.Fab") hide
        (effects (font (size 0.7 0.7) (thickness 0.15)) (justify left bottom))
    )
    (fp_rect (start -0.925 -0.47) (end 0.925 0.47)
      (stroke (width 0.05) (type default)) (fill none) (layer "F.CrtYd"))
    (fp_rect (start -0.5 -0.25) (end 0.5 0.25)
      (stroke (width 0.15) (type solid)) (fill none) (layer "F.Fab"))
    (pad "1" smd roundrect (at -0.48 0 270) (size 0.59 0.64) (layers "F.Cu" "F.Paste" "F.Mask") (roundrect_rratio 0.25)
      (net 54 "Net-(Q11-Pad1)") (pintype "passive"))
    (pad "2" smd roundrect (at 0.48 0 270) (size 0.59 0.64) (layers "F.Cu" "F.Paste" "F.Mask") (roundrect_rratio 0.25)
      (net 51 "PSU_ON") (pintype "passive"))
  )

  (footprint "antmicro-footprints:LED_0603_1608Metric_G" (layer "F.Cu")
    (at 98 133.8 -90)
    (descr "LED SMD 0603 Green")
    (tags "LED SMD 0603 Green")
    (property "Author" "Antmicro")
    (property "Color" "Green")
    (property "License" "Apache-2.0")
    (property "MPN" "LG L29K-G2J1-24-Z")
    (property "Manufacturer" "OSRAM")
    (property "Sheetfile" "d1600e-psu-breakout-board.kicad_sch")
    (property "Sheetname" "")
    (property "ki_description" "LED, Green, SMD, 0603, 20 mA, 1.7 V, 570 nm")
    (property "ki_keywords" "SMT, DIODE, SEMICONDUCTOR, LED")
    (attr smd)
    (fp_text reference "D5" (at -1.65 -0.45 -90) (layer "F.SilkS")
        (effects (font (size 0.7 0.7) (thickness 0.15)) (justify left bottom))
    )
    (fp_text value "LED_G_0603_LG_L29K-G2J1-24-Z" (at -0.001 1.599 -90) (layer "F.Fab")
        (effects (font (size 0.7 0.7) (thickness 0.15)) (justify left bottom))
    )
    (fp_text user "${REFERENCE}" (at -1.4224 5.999 -90) (layer "F.Fab") hide
        (effects (font (size 0.7 0.7) (thickness 0.15)) (justify left bottom))
    )
    (fp_text user "License: Apache-2.0" (at -1.4224 3.599 -90) (layer "F.Fab") hide
        (effects (font (size 0.7 0.7) (thickness 0.15)) (justify left bottom))
    )
    (fp_text user "Author: Antmicro" (at -1.4224 4.799 -90) (layer "F.Fab") hide
        (effects (font (size 0.7 0.7) (thickness 0.15)) (justify left bottom))
    )
    (fp_line (start -1.18 -0.319) (end -1.18 0.321)
      (stroke (width 0.15) (type solid)) (layer "F.SilkS"))
    (fp_line (start -0.094672 0.001008) (end -0.24 0.001008)
      (stroke (width 0.1) (type solid)) (layer "F.SilkS"))
    (fp_line (start -0.094672 0.001008) (end 0.105328 -0.198992)
      (stroke (width 0.1) (type solid)) (layer "F.SilkS"))
    (fp_line (start -0.094672 0.201008) (end -0.094672 -0.198992)
      (stroke (width 0.1) (type solid)) (layer "F.SilkS"))
    (fp_line (start 0.105328 0.001008) (end 0.24 0.001)
      (stroke (width 0.1) (type solid)) (layer "F.SilkS"))
    (fp_line (start 0.105328 0.201008) (end -0.094672 0.001008)
      (stroke (width 0.1) (type solid)) (layer "F.SilkS"))
    (fp_line (start 0.105328 0.201008) (end 0.105328 -0.198992)
      (stroke (width 0.1) (type solid)) (layer "F.SilkS"))
    (fp_line (start 0.22 -0.35) (end -0.22 -0.35)
      (stroke (width 0.15) (type solid)) (layer "F.SilkS"))
    (fp_line (start 0.22 0.35) (end -0.22 0.35)
      (stroke (width 0.15) (type solid)) (layer "F.SilkS"))
    (fp_rect (start 1.25 0.65) (end -1.25 -0.65)
      (stroke (width 0.05) (type solid)) (fill none) (layer "F.CrtYd"))
    (fp_line (start -0.199 -0.202) (end -0.199 0.1)
      (stroke (width 0.15) (type solid)) (layer "F.Fab"))
    (fp_line (start -0.199 0) (end -0.597 0)
      (stroke (width 0.15) (type solid)) (layer "F.Fab"))
    (fp_line (start -0.199 0.2) (end -0.199 0.1)
      (stroke (width 0.15) (type solid)) (layer "F.Fab"))
    (fp_line (start -0.101 0) (end 0.201 0.2)
      (stroke (width 0.15) (type solid)) (layer "F.Fab"))
    (fp_line (start 0.201 -0.202) (end -0.101 0)
      (stroke (width 0.15) (type solid)) (layer "F.Fab"))
    (fp_line (start 0.201 0) (end 0.201 -0.202)
      (stroke (width 0.15) (type solid)) (layer "F.Fab"))
    (fp_line (start 0.201 0.2) (end 0.201 0)
      (stroke (width 0.15) (type solid)) (layer "F.Fab"))
    (fp_line (start 0.599 0) (end 0.201 0)
      (stroke (width 0.15) (type solid)) (layer "F.Fab"))
    (fp_rect (start 0.848 0.4) (end -0.85 -0.402)
      (stroke (width 0.15) (type solid)) (fill none) (layer "F.Fab"))
    (pad "1" smd roundrect (at -0.7 0 90) (size 0.8 1) (layers "F.Cu" "F.Paste" "F.Mask") (roundrect_rratio 0.2)
      (net 38 "Net-(D5-C)") (pinfunction "C") (pintype "passive"))
    (pad "2" smd roundrect (at 0.7 0 90) (size 0.8 1) (layers "F.Cu" "F.Paste" "F.Mask") (roundrect_rratio 0.2)
      (net 39 "Net-(D5-A)") (pinfunction "A") (pintype "passive"))
  )

  (footprint "antmicro-footprints:R_0402_1005Metric" (layer "F.Cu")
    (at 96.4 133.8 -90)
    (descr "Resistor SMD 0402")
    (tags "resistor SMD 0402")
    (property "Author" "Antmicro")
    (property "License" "Apache-2.0")
    (property "MPN" "CR0402-FX-6800GLF")
    (property "Manufacturer" "Bourns")
    (property "Sheetfile" "d1600e-psu-breakout-board.kicad_sch")
    (property "Sheetname" "")
    (property "Tolerance" "1%")
    (property "Val" "680R")
    (property "ki_description" "SMD Chip Resistor, 680 ohm, ± 1%, 63 mW, 0402 [1005 Metric], Thick Film, General Purpose")
    (property "ki_keywords" "0402, SMT, RESISTOR, PASSIVE")
    (attr smd)
    (fp_text reference "R41" (at -0.9 -0.4 -90) (layer "F.SilkS")
        (effects (font (size 0.7 0.7) (thickness 0.15)) (justify left bottom))
    )
    (fp_text value "R_680R_0402" (at -1.011843 1.772047 -90) (layer "F.Fab")
        (effects (font (size 0.7 0.7) (thickness 0.15)) (justify left bottom))
    )
    (fp_text user "License: Apache-2.0" (at -0.95 5.169 -90) (layer "F.Fab") hide
        (effects (font (size 0.7 0.7) (thickness 0.15)) (justify left bottom))
    )
    (fp_text user "Author: Antmicro" (at -0.95 4.169 -90) (layer "F.Fab") hide
        (effects (font (size 0.7 0.7) (thickness 0.15)) (justify left bottom))
    )
    (fp_text user "${REFERENCE}" (at -0.95 3.168 -90) (layer "F.Fab") hide
        (effects (font (size 0.7 0.7) (thickness 0.15)) (justify left bottom))
    )
    (fp_rect (start -0.925 -0.47) (end 0.925 0.47)
      (stroke (width 0.05) (type default)) (fill none) (layer "F.CrtYd"))
    (fp_rect (start -0.5 -0.25) (end 0.5 0.25)
      (stroke (width 0.15) (type solid)) (fill none) (layer "F.Fab"))
    (pad "1" smd roundrect (at -0.48 0 270) (size 0.59 0.64) (layers "F.Cu" "F.Paste" "F.Mask") (roundrect_rratio 0.25)
      (net 38 "Net-(D5-C)") (pintype "passive"))
    (pad "2" smd roundrect (at 0.48 0 270) (size 0.59 0.64) (layers "F.Cu" "F.Paste" "F.Mask") (roundrect_rratio 0.25)
      (net 4 "GND") (pintype "passive"))
  )

  (footprint "antmicro-footprints:SOT-23-3" (layer "F.Cu")
    (at 101 134.6 180)
    (property "Author" "Antmicro")
    (property "License" "Apache-2.0")
    (property "MPN" "BC856,215")
    (property "Manufacturer" "Nexperia")
    (property "Sheetfile" "d1600e-psu-breakout-board.kicad_sch")
    (property "Sheetname" "")
    (property "ki_description" "Bipolar (BJT) Single Transistor, PNP, 65 V, 100 mA, 250 mW, SOT-23-3, Surface Mount")
    (property "ki_keywords" "SMT, TRANSISTOR, SEMICONDUCTOR, PNP")
    (attr smd)
    (fp_text reference "Q11" (at 1.05 2.15 180) (layer "F.SilkS")
        (effects (font (size 0.7 0.7) (thickness 0.15)) (justify left bottom))
    )
    (fp_text value "BC856,215" (at -1.9 2.7 180) (layer "F.Fab")
        (effects (font (size 0.7 0.7) (thickness 0.15)) (justify left bottom))
    )
    (fp_text user "License: Apache-2.0" (at -1.8 6.8 180) (layer "F.Fab") hide
        (effects (font (size 0.7 0.7) (thickness 0.15)) (justify left bottom))
    )
    (fp_text user "Author: Antmicro" (at -1.837 5.3 180) (layer "F.Fab") hide
        (effects (font (size 0.7 0.7) (thickness 0.15)) (justify left bottom))
    )
    (fp_text user "${REFERENCE}" (at -1.837 4 180) (layer "F.Fab") hide
        (effects (font (size 0.7 0.7) (thickness 0.15)) (justify left bottom))
    )
    (fp_line (start -1.45 -1.35) (end -0.85 -1.35)
      (stroke (width 0.15) (type solid)) (layer "F.SilkS"))
    (fp_line (start -0.85 -1.35) (end -0.7 -1.5)
      (stroke (width 0.15) (type solid)) (layer "F.SilkS"))
    (fp_line (start -0.7 1.5) (end -0.7 1.35)
      (stroke (width 0.15) (type solid)) (layer "F.SilkS"))
    (fp_line (start 0.7 -1.5) (end -0.7 -1.5)
      (stroke (width 0.15) (type solid)) (layer "F.SilkS"))
    (fp_line (start 0.7 -0.4) (end 0.7 -1.5)
      (stroke (width 0.15) (type solid)) (layer "F.SilkS"))
    (fp_line (start 0.7 0.4) (end 0.7 1.5)
      (stroke (width 0.15) (type solid)) (layer "F.SilkS"))
    (fp_line (start 0.7 1.5) (end -0.7 1.5)
      (stroke (width 0.15) (type solid)) (layer "F.SilkS"))
    (fp_line (start -1.75 -0.5) (end -1.75 -1.4)
      (stroke (width 0.05) (type solid)) (layer "F.CrtYd"))
    (fp_line (start -1.75 0.5) (end -0.85 0.5)
      (stroke (width 0.05) (type solid)) (layer "F.CrtYd"))
    (fp_line (start -1.75 1.4) (end -1.75 0.5)
      (stroke (width 0.05) (type solid)) (layer "F.CrtYd"))
    (fp_line (start -0.9 -1.6) (end -0.9 -1.4)
      (stroke (width 0.05) (type solid)) (layer "F.CrtYd"))
    (fp_line (start -0.9 -1.6) (end 0.825 -1.6)
      (stroke (width 0.05) (type solid)) (layer "F.CrtYd"))
    (fp_line (start -0.9 -1.4) (end -1.75 -1.4)
      (stroke (width 0.05) (type solid)) (layer "F.CrtYd"))
    (fp_line (start -0.85 -0.5) (end -1.75 -0.5)
      (stroke (width 0.05) (type solid)) (layer "F.CrtYd"))
    (fp_line (start -0.85 0.5) (end -0.85 -0.5)
      (stroke (width 0.05) (type solid)) (layer "F.CrtYd"))
    (fp_line (start -0.85 1.4) (end -1.75 1.4)
      (stroke (width 0.05) (type solid)) (layer "F.CrtYd"))
    (fp_line (start -0.85 1.65) (end -0.85 1.4)
      (stroke (width 0.05) (type solid)) (layer "F.CrtYd"))
    (fp_line (start 0.825 -1.6) (end 0.825 -0.45)
      (stroke (width 0.05) (type solid)) (layer "F.CrtYd"))
    (fp_line (start 0.825 -0.45) (end 1.75 -0.45)
      (stroke (width 0.05) (type solid)) (layer "F.CrtYd"))
    (fp_line (start 0.85 0.45) (end 0.85 1.65)
      (stroke (width 0.05) (type solid)) (layer "F.CrtYd"))
    (fp_line (start 0.85 1.65) (end -0.85 1.65)
      (stroke (width 0.05) (type solid)) (layer "F.CrtYd"))
    (fp_line (start 1.75 -0.45) (end 1.75 0.45)
      (stroke (width 0.05) (type solid)) (layer "F.CrtYd"))
    (fp_line (start 1.75 0.45) (end 0.85 0.45)
      (stroke (width 0.05) (type solid)) (layer "F.CrtYd"))
    (fp_line (start -0.712 -1.325) (end -0.712 1.523)
      (stroke (width 0.15) (type solid)) (layer "F.Fab"))
    (fp_line (start -0.712 1.519) (end 0.688 1.519)
      (stroke (width 0.15) (type solid)) (layer "F.Fab"))
    (fp_line (start -0.437 -1.526) (end -0.712 -1.325)
      (stroke (width 0.15) (type solid)) (layer "F.Fab"))
    (fp_line (start -0.437 -1.526) (end 0.688 -1.526)
      (stroke (width 0.15) (type solid)) (layer "F.Fab"))
    (fp_line (start 0.688 1.519) (end 0.688 -1.52)
      (stroke (width 0.15) (type solid)) (layer "F.Fab"))
    (pad "1" smd roundrect (at -1.1 -0.951 180) (size 1 0.6) (layers "F.Cu" "F.Paste" "F.Mask") (roundrect_rratio 0.15)
      (net 54 "Net-(Q11-Pad1)") (pintype "input"))
    (pad "2" smd roundrect (at -1.1 0.949 180) (size 1 0.6) (layers "F.Cu" "F.Paste" "F.Mask") (roundrect_rratio 0.15)
      (net 1 "VCC3V3") (pintype "passive"))
    (pad "3" smd roundrect (at 1.1 -0.0005 180) (size 1 0.6) (layers "F.Cu" "F.Paste" "F.Mask") (roundrect_rratio 0.15)
      (net 39 "Net-(D5-A)") (pintype "passive"))
  )

  (footprint "antmicro-footprints:MP_Pad6mm_Drill3.2mm" (layer "F.Cu")
    (at 94 145)
    (property "Author" "Antmicro")
    (property "License" "Apache-2.0")
    (property "Sheetfile" "d1600e-psu-breakout-board.kicad_sch")
    (property "Sheetname" "")
    (property "exclude_from_bom" "")
    (property "ki_description" "Mechanical part")
    (property "ki_keywords" "MECHANICAL")
    (attr exclude_from_pos_files exclude_from_bom)
    (fp_text reference "MP2" (at 0 -3.2) (layer "F.SilkS") hide
        (effects (font (size 0.7 0.7) (thickness 0.15)) (justify left bottom))
    )
    (fp_text value "MP_Pad6mm_Drill3.2mm" (at 0 3.9) (layer "F.Fab")
        (effects (font (size 0.7 0.7) (thickness 0.15)) (justify left bottom))
    )
    (fp_text user "Author: Antmicro" (at -0.178 7.225) (layer "F.Fab") hide
        (effects (font (size 0.7 0.7) (thickness 0.15)) (justify left bottom))
    )
    (fp_text user "License: Apache-2.0" (at -0.178 8.425) (layer "F.Fab") hide
        (effects (font (size 0.7 0.7) (thickness 0.15)) (justify left bottom))
    )
    (fp_text user "${REFERENCE}" (at -0.178 6.025) (layer "F.Fab") hide
        (effects (font (size 0.7 0.7) (thickness 0.15)) (justify left bottom))
    )
    (fp_circle (center 0 0) (end 3.25 0)
      (stroke (width 0.05) (type default)) (fill none) (layer "F.CrtYd"))
    (pad "1" thru_hole circle (at 0 0) (size 6 6) (drill 3.2) (layers "*.Cu" "*.Mask")
      (net 4 "GND") (pintype "passive"))
  )

  (footprint "antmicro-footprints:MP_Pad6mm_Drill3.2mm" (layer "F.Cu")
    (at 186.55 53.9)
    (property "Author" "Antmicro")
    (property "License" "Apache-2.0")
    (property "Sheetfile" "d1600e-psu-breakout-board.kicad_sch")
    (property "Sheetname" "")
    (property "exclude_from_bom" "")
    (property "ki_description" "Mechanical part")
    (property "ki_keywords" "MECHANICAL")
    (attr exclude_from_pos_files exclude_from_bom)
    (fp_text reference "MP3" (at 0 -3.2) (layer "F.SilkS") hide
        (effects (font (size 0.7 0.7) (thickness 0.15)) (justify left bottom))
    )
    (fp_text value "MP_Pad6mm_Drill3.2mm" (at 0 3.9) (layer "F.Fab")
        (effects (font (size 0.7 0.7) (thickness 0.15)) (justify left bottom))
    )
    (fp_text user "${REFERENCE}" (at -0.178 6.025) (layer "F.Fab") hide
        (effects (font (size 0.7 0.7) (thickness 0.15)) (justify left bottom))
    )
    (fp_text user "Author: Antmicro" (at -0.178 7.225) (layer "F.Fab") hide
        (effects (font (size 0.7 0.7) (thickness 0.15)) (justify left bottom))
    )
    (fp_text user "License: Apache-2.0" (at -0.178 8.425) (layer "F.Fab") hide
        (effects (font (size 0.7 0.7) (thickness 0.15)) (justify left bottom))
    )
    (fp_circle (center 0 0) (end 3.25 0)
      (stroke (width 0.05) (type default)) (fill none) (layer "F.CrtYd"))
    (pad "1" thru_hole circle (at 0 0) (size 6 6) (drill 3.2) (layers "*.Cu" "*.Mask")
      (net 4 "GND") (pintype "passive"))
  )

  (footprint "antmicro-footprints:MP_Pad6mm_Drill3.2mm" (layer "F.Cu")
    (at 185 145)
    (property "Author" "Antmicro")
    (property "License" "Apache-2.0")
    (property "Sheetfile" "d1600e-psu-breakout-board.kicad_sch")
    (property "Sheetname" "")
    (property "exclude_from_bom" "")
    (property "ki_description" "Mechanical part")
    (property "ki_keywords" "MECHANICAL")
    (attr exclude_from_pos_files exclude_from_bom)
    (fp_text reference "MP4" (at 0 -3.2) (layer "F.SilkS") hide
        (effects (font (size 0.7 0.7) (thickness 0.15)) (justify left bottom))
    )
    (fp_text value "MP_Pad6mm_Drill3.2mm" (at 0 3.9) (layer "F.Fab")
        (effects (font (size 0.7 0.7) (thickness 0.15)) (justify left bottom))
    )
    (fp_text user "${REFERENCE}" (at -0.178 6.025) (layer "F.Fab") hide
        (effects (font (size 0.7 0.7) (thickness 0.15)) (justify left bottom))
    )
    (fp_text user "License: Apache-2.0" (at -0.178 8.425) (layer "F.Fab") hide
        (effects (font (size 0.7 0.7) (thickness 0.15)) (justify left bottom))
    )
    (fp_text user "Author: Antmicro" (at -0.178 7.225) (layer "F.Fab") hide
        (effects (font (size 0.7 0.7) (thickness 0.15)) (justify left bottom))
    )
    (fp_circle (center 0 0) (end 3.25 0)
      (stroke (width 0.05) (type default)) (fill none) (layer "F.CrtYd"))
    (pad "1" thru_hole circle (at 0 0) (size 6 6) (drill 3.2) (layers "*.Cu" "*.Mask")
      (net 4 "GND") (pintype "passive"))
  )

  (footprint "antmicro-footprints:MOLEX_39288080" (layer "F.Cu")
    (at 111.25 74.7 90)
    (property "Author" "Antmicro")
    (property "License" "Apache-2.0")
    (property "MPN" "39-28-8080")
    (property "Manufacturer" "Molex")
    (property "Sheetfile" "d1600e-psu-breakout-board.kicad_sch")
    (property "Sheetname" "")
    (property "ki_description" "Pin Header, THT, Vertical, UL94V-2, Power, Wire-to-Board, 4.2 mm, 2 Rows, 8 Contacts, Mini-fit Jr, 5566 series")
    (property "ki_keywords" "VERTICAL, THT, HEADER, CONNECTOR, MALE, WIRE-BOARD, POWER")
    (attr through_hole)
    (fp_text reference "J4" (at -2.5 -2.65 90) (layer "F.SilkS")
        (effects (font (size 0.7 0.7) (thickness 0.15)) (justify left bottom))
    )
    (fp_text value "Molex_Mini-Fit-Jr_2x4_39-28-8080" (at 4.49 11.365 90) (layer "F.Fab")
        (effects (font (size 0.7 0.7) (thickness 0.15)) (justify left bottom))
    )
    (fp_text user "Author: Antmicro" (at -3.5 16.965 90) (layer "F.Fab") hide
        (effects (font (size 0.7 0.7) (thickness 0.15)) (justify left bottom))
    )
    (fp_text user "License: Apache-2.0" (at -3.5 14.565 90) (layer "F.Fab") hide
        (effects (font (size 0.7 0.7) (thickness 0.15)) (justify left bottom))
    )
    (fp_text user "${REFERENCE}" (at -3.5 15.765 90) (layer "F.Fab") hide
        (effects (font (size 0.7 0.7) (thickness 0.15)) (justify left bottom))
    )
    (fp_text user "PTH D1.40 +/- 0.05" (at -3.5 13.365 90) (layer "F.Fab") hide
        (effects (font (size 0.7 0.7) (thickness 0.15)) (justify left bottom))
    )
    (fp_line (start -3.1 8.75) (end -3.1 -0.98)
      (stroke (width 0.15) (type solid)) (layer "F.SilkS"))
    (fp_line (start -1.83 -2.25) (end -3.1 -0.98)
      (stroke (width 0.15) (type solid)) (layer "F.SilkS"))
    (fp_line (start -1.83 -2.25) (end 15.7 -2.25)
      (stroke (width 0.15) (type solid)) (layer "F.SilkS"))
    (fp_line (start -0.4 -3.327) (end 0 -2.627)
      (stroke (width 0.15) (type solid)) (layer "F.SilkS"))
    (fp_line (start 0 -2.627) (end 0.4 -3.327)
      (stroke (width 0.15) (type solid)) (layer "F.SilkS"))
    (fp_line (start 0.4 -3.327) (end -0.4 -3.327)
      (stroke (width 0.15) (type solid)) (layer "F.SilkS"))
    (fp_line (start 15.7 -2.25) (end 15.7 8.75)
      (stroke (width 0.15) (type solid)) (layer "F.SilkS"))
    (fp_line (start 15.7 8.75) (end -3.1 8.75)
      (stroke (width 0.15) (type solid)) (layer "F.SilkS"))
    (fp_circle (center 0 -3) (end 0.05 -3)
      (stroke (width 0.15) (type solid)) (fill solid) (layer "F.SilkS"))
    (fp_circle (center 0 5.5) (end 0.513 5.5)
      (stroke (width 1.0262) (type solid)) (fill none) (layer "B.Mask"))
    (fp_circle (center 4.2 0) (end 4.713 0)
      (stroke (width 1.0262) (type solid)) (fill none) (layer "B.Mask"))
    (fp_circle (center 4.2 5.5) (end 4.713 5.5)
      (stroke (width 1.0262) (type solid)) (fill none) (layer "B.Mask"))
    (fp_circle (center 8.4 0) (end 8.913 0)
      (stroke (width 1.0262) (type solid)) (fill none) (layer "B.Mask"))
    (fp_circle (center 8.4 5.5) (end 8.913 5.5)
      (stroke (width 1.0262) (type solid)) (fill none) (layer "B.Mask"))
    (fp_circle (center 12.6 0) (end 13.113 0)
      (stroke (width 1.0262) (type solid)) (fill none) (layer "B.Mask"))
    (fp_circle (center 12.6 5.5) (end 13.113 5.5)
      (stroke (width 1.0262) (type solid)) (fill none) (layer "B.Mask"))
    (fp_poly
      (pts
        (xy -1.026 -1.026)
        (xy 1.026 -1.026)
        (xy 1.026 1.026)
        (xy -1.026 1.026)
      )

      (stroke (width 0.01) (type solid)) (fill solid) (layer "B.Mask"))
    (fp_circle (center 0 5.5) (end 0.513 5.5)
      (stroke (width 1.0262) (type solid)) (fill none) (layer "F.Mask"))
    (fp_circle (center 4.2 0) (end 4.713 0)
      (stroke (width 1.0262) (type solid)) (fill none) (layer "F.Mask"))
    (fp_circle (center 4.2 5.5) (end 4.713 5.5)
      (stroke (width 1.0262) (type solid)) (fill none) (layer "F.Mask"))
    (fp_circle (center 8.4 0) (end 8.913 0)
      (stroke (width 1.0262) (type solid)) (fill none) (layer "F.Mask"))
    (fp_circle (center 8.4 5.5) (end 8.913 5.5)
      (stroke (width 1.0262) (type solid)) (fill none) (layer "F.Mask"))
    (fp_circle (center 12.6 0) (end 13.113 0)
      (stroke (width 1.0262) (type solid)) (fill none) (layer "F.Mask"))
    (fp_circle (center 12.6 5.5) (end 13.113 5.5)
      (stroke (width 1.0262) (type solid)) (fill none) (layer "F.Mask"))
    (fp_poly
      (pts
        (xy -1.026 -1.026)
        (xy 1.026 -1.026)
        (xy 1.026 1.026)
        (xy -1.026 1.026)
      )

      (stroke (width 0.01) (type solid)) (fill solid) (layer "F.Mask"))
    (fp_rect (start -3.5 -2.7) (end 16.1 9.1)
      (stroke (width 0.05) (type solid)) (fill none) (layer "F.CrtYd"))
    (fp_line (start -3.1 8.75) (end -3.1 -0.98)
      (stroke (width 0.15) (type solid)) (layer "F.Fab"))
    (fp_line (start -1.83 -2.25) (end -3.1 -0.98)
      (stroke (width 0.15) (type solid)) (layer "F.Fab"))
    (fp_line (start -1.83 -2.25) (end 15.7 -2.25)
      (stroke (width 0.15) (type solid)) (layer "F.Fab"))
    (fp_line (start -0.4 -3.327) (end 0 -2.627)
      (stroke (width 0.15) (type solid)) (layer "F.Fab"))
    (fp_line (start 0 -2.627) (end 0.4 -3.327)
      (stroke (width 0.15) (type solid)) (layer "F.Fab"))
    (fp_line (start 0.4 -3.327) (end -0.4 -3.327)
      (stroke (width 0.15) (type solid)) (layer "F.Fab"))
    (fp_line (start 15.7 -2.25) (end 15.7 8.75)
      (stroke (width 0.15) (type solid)) (layer "F.Fab"))
    (fp_line (start 15.7 8.75) (end -3.1 8.75)
      (stroke (width 0.15) (type solid)) (layer "F.Fab"))
    (pad "1" thru_hole rect (at 0 0 90) (size 1.9 1.9) (drill 1.4) (layers "*.Cu")
      (net 4 "GND") (pinfunction "1") (pintype "bidirectional"))
    (pad "2" thru_hole circle (at 4.2 0 90) (size 1.9 1.9) (drill 1.4) (layers "*.Cu")
      (net 4 "GND") (pinfunction "2") (pintype "bidirectional"))
    (pad "3" thru_hole circle (at 8.4 0 90) (size 1.9 1.9) (drill 1.4) (layers "*.Cu")
      (net 4 "GND") (pinfunction "3") (pintype "bidirectional"))
    (pad "4" thru_hole circle (at 12.6 0 90) (size 1.9 1.9) (drill 1.4) (layers "*.Cu")
      (net 4 "GND") (pinfunction "4") (pintype "bidirectional"))
    (pad "5" thru_hole circle (at 0 5.5 90) (size 1.9 1.9) (drill 1.4) (layers "*.Cu")
      (net 41 "LOAD_1") (pinfunction "5") (pintype "bidirectional"))
    (pad "6" thru_hole circle (at 4.2 5.5 90) (size 1.9 1.9) (drill 1.4) (layers "*.Cu")
      (net 41 "LOAD_1") (pinfunction "6") (pintype "bidirectional"))
    (pad "7" thru_hole circle (at 8.4 5.5 90) (size 1.9 1.9) (drill 1.4) (layers "*.Cu")
      (net 41 "LOAD_1") (pinfunction "7") (pintype "bidirectional"))
    (pad "8" thru_hole circle (at 12.6 5.5 90) (size 1.9 1.9) (drill 1.4) (layers "*.Cu")
      (net 41 "LOAD_1") (pinfunction "8") (pintype "bidirectional"))
  )

  (footprint "antmicro-footprints:MP_Pad6mm_Drill3.2mm" (layer "F.Cu")
    (at 94 53.9)
    (property "Author" "Antmicro")
    (property "License" "Apache-2.0")
    (property "Sheetfile" "d1600e-psu-breakout-board.kicad_sch")
    (property "Sheetname" "")
    (property "exclude_from_bom" "")
    (property "ki_description" "Mechanical part")
    (property "ki_keywords" "MECHANICAL")
    (attr exclude_from_pos_files exclude_from_bom)
    (fp_text reference "MP1" (at 0 -3.2) (layer "F.SilkS") hide
        (effects (font (size 0.7 0.7) (thickness 0.15)) (justify left bottom))
    )
    (fp_text value "MP_Pad6mm_Drill3.2mm" (at 0 3.9) (layer "F.Fab")
        (effects (font (size 0.7 0.7) (thickness 0.15)) (justify left bottom))
    )
    (fp_text user "${REFERENCE}" (at -0.178 6.025) (layer "F.Fab") hide
        (effects (font (size 0.7 0.7) (thickness 0.15)) (justify left bottom))
    )
    (fp_text user "Author: Antmicro" (at -0.178 7.225) (layer "F.Fab") hide
        (effects (font (size 0.7 0.7) (thickness 0.15)) (justify left bottom))
    )
    (fp_text user "License: Apache-2.0" (at -0.178 8.425) (layer "F.Fab") hide
        (effects (font (size 0.7 0.7) (thickness 0.15)) (justify left bottom))
    )
    (fp_circle (center 0 0) (end 3.25 0)
      (stroke (width 0.05) (type default)) (fill none) (layer "F.CrtYd"))
    (pad "1" thru_hole circle (at 0 0) (size 6 6) (drill 3.2) (layers "*.Cu" "*.Mask")
      (net 4 "GND") (pintype "passive"))
  )

  (footprint "antmicro-footprints:TP_SMD_1mm" (layer "F.Cu")
    (at 115.6 131.4 -90)
    (property "Author" "Antmicro")
    (property "License" "Apache-2.0")
    (property "MPN" "")
    (property "Manufacturer" "")
    (property "Sheetfile" "d1600e-psu-breakout-board.kicad_sch")
    (property "Sheetname" "")
    (property "exclude_from_bom" "")
    (property "ki_description" "Test point 1mm SMD")
    (property "ki_keywords" "TESTPOINT")
    (attr exclude_from_pos_files exclude_from_bom)
    (fp_text reference "TP_S18" (at -0.7 -0.45 -90) (layer "F.SilkS")
        (effects (font (size 0.7 0.7) (thickness 0.15)) (justify left bottom))
    )
    (fp_text value "TP_1mm_SMD" (at 0 1.4 -90) (layer "F.Fab")
        (effects (font (size 0.7 0.7) (thickness 0.15)) (justify left bottom))
    )
    (fp_text user "Author: Antmicro" (at -0.5 4 -90) (layer "F.Fab") hide
        (effects (font (size 0.7 0.7) (thickness 0.15)) (justify left bottom))
    )
    (fp_text user "${REFERENCE}" (at -0.5 2.8 -90) (layer "F.Fab") hide
        (effects (font (size 0.7 0.7) (thickness 0.15)) (justify left bottom))
    )
    (fp_text user "License: Apache-2.0" (at -0.5 5.2 -90) (layer "F.Fab") hide
        (effects (font (size 0.7 0.7) (thickness 0.15)) (justify left bottom))
    )
    (fp_circle (center 0 0) (end 0.6 0)
      (stroke (width 0.05) (type default)) (fill none) (layer "F.CrtYd"))
    (pad "1" smd circle (at 0 0 270) (size 1 1) (layers "F.Cu" "F.Mask")
      (net 73 "Net-(J10-PadS18)") (pinfunction "1") (pintype "passive"))
  )

  (footprint "antmicro-footprints:TP_SMD_1mm" (layer "F.Cu")
    (at 116.9 131.4 -90)
    (property "Author" "Antmicro")
    (property "License" "Apache-2.0")
    (property "MPN" "")
    (property "Manufacturer" "")
    (property "Sheetfile" "d1600e-psu-breakout-board.kicad_sch")
    (property "Sheetname" "")
    (property "exclude_from_bom" "")
    (property "ki_description" "Test point 1mm SMD")
    (property "ki_keywords" "TESTPOINT")
    (attr exclude_from_pos_files exclude_from_bom)
    (fp_text reference "TP_S19" (at -0.7 -0.45 -90) (layer "F.SilkS")
        (effects (font (size 0.7 0.7) (thickness 0.15)) (justify left bottom))
    )
    (fp_text value "TP_1mm_SMD" (at 0 1.4 -90) (layer "F.Fab")
        (effects (font (size 0.7 0.7) (thickness 0.15)) (justify left bottom))
    )
    (fp_text user "License: Apache-2.0" (at -0.5 5.2 -90) (layer "F.Fab") hide
        (effects (font (size 0.7 0.7) (thickness 0.15)) (justify left bottom))
    )
    (fp_text user "Author: Antmicro" (at -0.5 4 -90) (layer "F.Fab") hide
        (effects (font (size 0.7 0.7) (thickness 0.15)) (justify left bottom))
    )
    (fp_text user "${REFERENCE}" (at -0.5 2.8 -90) (layer "F.Fab") hide
        (effects (font (size 0.7 0.7) (thickness 0.15)) (justify left bottom))
    )
    (fp_circle (center 0 0) (end 0.6 0)
      (stroke (width 0.05) (type default)) (fill none) (layer "F.CrtYd"))
    (pad "1" smd circle (at 0 0 270) (size 1 1) (layers "F.Cu" "F.Mask")
      (net 71 "Net-(J10-PadS19)") (pinfunction "1") (pintype "passive"))
  )

  (footprint "antmicro-footprints:TP_SMD_1mm" (layer "F.Cu")
    (at 118.2 131.4 -90)
    (property "Author" "Antmicro")
    (property "License" "Apache-2.0")
    (property "MPN" "")
    (property "Manufacturer" "")
    (property "Sheetfile" "d1600e-psu-breakout-board.kicad_sch")
    (property "Sheetname" "")
    (property "exclude_from_bom" "")
    (property "ki_description" "Test point 1mm SMD")
    (property "ki_keywords" "TESTPOINT")
    (attr exclude_from_pos_files exclude_from_bom)
    (fp_text reference "TP_S20" (at -0.7 -0.45 -90) (layer "F.SilkS")
        (effects (font (size 0.7 0.7) (thickness 0.15)) (justify left bottom))
    )
    (fp_text value "TP_1mm_SMD" (at 0 1.4 -90) (layer "F.Fab")
        (effects (font (size 0.7 0.7) (thickness 0.15)) (justify left bottom))
    )
    (fp_text user "Author: Antmicro" (at -0.5 4 -90) (layer "F.Fab") hide
        (effects (font (size 0.7 0.7) (thickness 0.15)) (justify left bottom))
    )
    (fp_text user "${REFERENCE}" (at -0.5 2.8 -90) (layer "F.Fab") hide
        (effects (font (size 0.7 0.7) (thickness 0.15)) (justify left bottom))
    )
    (fp_text user "License: Apache-2.0" (at -0.5 5.2 -90) (layer "F.Fab") hide
        (effects (font (size 0.7 0.7) (thickness 0.15)) (justify left bottom))
    )
    (fp_circle (center 0 0) (end 0.6 0)
      (stroke (width 0.05) (type default)) (fill none) (layer "F.CrtYd"))
    (pad "1" smd circle (at 0 0 270) (size 1 1) (layers "F.Cu" "F.Mask")
      (net 74 "Net-(J10-PadS20)") (pinfunction "1") (pintype "passive"))
  )

  (footprint "antmicro-footprints:TP_SMD_1mm" (layer "F.Cu")
    (at 119.5 131.4 -90)
    (property "Author" "Antmicro")
    (property "License" "Apache-2.0")
    (property "MPN" "")
    (property "Manufacturer" "")
    (property "Sheetfile" "d1600e-psu-breakout-board.kicad_sch")
    (property "Sheetname" "")
    (property "exclude_from_bom" "")
    (property "ki_description" "Test point 1mm SMD")
    (property "ki_keywords" "TESTPOINT")
    (attr exclude_from_pos_files exclude_from_bom)
    (fp_text reference "TP_S21" (at -0.7 -0.45 -90) (layer "F.SilkS")
        (effects (font (size 0.7 0.7) (thickness 0.15)) (justify left bottom))
    )
    (fp_text value "TP_1mm_SMD" (at 0 1.4 -90) (layer "F.Fab")
        (effects (font (size 0.7 0.7) (thickness 0.15)) (justify left bottom))
    )
    (fp_text user "Author: Antmicro" (at -0.5 4 -90) (layer "F.Fab") hide
        (effects (font (size 0.7 0.7) (thickness 0.15)) (justify left bottom))
    )
    (fp_text user "${REFERENCE}" (at -0.5 2.8 -90) (layer "F.Fab") hide
        (effects (font (size 0.7 0.7) (thickness 0.15)) (justify left bottom))
    )
    (fp_text user "License: Apache-2.0" (at -0.5 5.2 -90) (layer "F.Fab") hide
        (effects (font (size 0.7 0.7) (thickness 0.15)) (justify left bottom))
    )
    (fp_circle (center 0 0) (end 0.6 0)
      (stroke (width 0.05) (type default)) (fill none) (layer "F.CrtYd"))
    (pad "1" smd circle (at 0 0 270) (size 1 1) (layers "F.Cu" "F.Mask")
      (net 69 "Net-(J10-PadS21)") (pinfunction "1") (pintype "passive"))
  )

  (footprint "antmicro-footprints:TP_SMD_1mm" (layer "F.Cu")
    (at 123.4508 131.4 -90)
    (property "Author" "Antmicro")
    (property "License" "Apache-2.0")
    (property "MPN" "")
    (property "Manufacturer" "")
    (property "Sheetfile" "d1600e-psu-breakout-board.kicad_sch")
    (property "Sheetname" "")
    (property "exclude_from_bom" "")
    (property "ki_description" "Test point 1mm SMD")
    (property "ki_keywords" "TESTPOINT")
    (attr exclude_from_pos_files exclude_from_bom)
    (fp_text reference "TP_S24" (at -0.7 -0.45 -90) (layer "F.SilkS")
        (effects (font (size 0.7 0.7) (thickness 0.15)) (justify left bottom))
    )
    (fp_text value "TP_1mm_SMD" (at 0 1.4 -90) (layer "F.Fab")
        (effects (font (size 0.7 0.7) (thickness 0.15)) (justify left bottom))
    )
    (fp_text user "License: Apache-2.0" (at -0.5 5.2 -90) (layer "F.Fab") hide
        (effects (font (size 0.7 0.7) (thickness 0.15)) (justify left bottom))
    )
    (fp_text user "${REFERENCE}" (at -0.5 2.8 -90) (layer "F.Fab") hide
        (effects (font (size 0.7 0.7) (thickness 0.15)) (justify left bottom))
    )
    (fp_text user "Author: Antmicro" (at -0.5 4 -90) (layer "F.Fab") hide
        (effects (font (size 0.7 0.7) (thickness 0.15)) (justify left bottom))
    )
    (fp_circle (center 0 0) (end 0.6 0)
      (stroke (width 0.05) (type default)) (fill none) (layer "F.CrtYd"))
    (pad "1" smd circle (at 0 0 270) (size 1 1) (layers "F.Cu" "F.Mask")
      (net 55 "Net-(J10-PadS24)") (pinfunction "1") (pintype "passive"))
  )

  (footprint "antmicro-footprints:TP_SMD_1mm" (layer "F.Cu")
    (at 110.25 137.4)
    (property "Author" "Antmicro")
    (property "License" "Apache-2.0")
    (property "MPN" "")
    (property "Manufacturer" "")
    (property "Sheetfile" "d1600e-psu-breakout-board.kicad_sch")
    (property "Sheetname" "")
    (property "exclude_from_bom" "")
    (property "ki_description" "Test point 1mm SMD")
    (property "ki_keywords" "TESTPOINT")
    (attr exclude_from_pos_files exclude_from_bom)
    (fp_text reference "TP_S11" (at 0.311136 -0.412467 90) (layer "F.SilkS")
        (effects (font (size 0.7 0.7) (thickness 0.15)) (justify left bottom))
    )
    (fp_text value "TP_1mm_SMD" (at 0 1.4) (layer "F.Fab")
        (effects (font (size 0.7 0.7) (thickness 0.15)) (justify left bottom))
    )
    (fp_text user "License: Apache-2.0" (at -0.5 5.2) (layer "F.Fab") hide
        (effects (font (size 0.7 0.7) (thickness 0.15)) (justify left bottom))
    )
    (fp_text user "Author: Antmicro" (at -0.5 4) (layer "F.Fab") hide
        (effects (font (size 0.7 0.7) (thickness 0.15)) (justify left bottom))
    )
    (fp_text user "${REFERENCE}" (at -0.5 2.8) (layer "F.Fab") hide
        (effects (font (size 0.7 0.7) (thickness 0.15)) (justify left bottom))
    )
    (fp_circle (center 0 0) (end 0.6 0)
      (stroke (width 0.05) (type default)) (fill none) (layer "F.CrtYd"))
    (pad "1" smd circle (at 0 0) (size 1 1) (layers "F.Cu" "F.Mask")
      (net 57 "Net-(J10-PadS11)") (pinfunction "1") (pintype "passive"))
  )

  (footprint "antmicro-footprints:TP_SMD_1mm" (layer "F.Cu")
    (at 108.9 137.4508)
    (property "Author" "Antmicro")
    (property "License" "Apache-2.0")
    (property "MPN" "")
    (property "Manufacturer" "")
    (property "Sheetfile" "d1600e-psu-breakout-board.kicad_sch")
    (property "Sheetname" "")
    (property "exclude_from_bom" "")
    (property "ki_description" "Test point 1mm SMD")
    (property "ki_keywords" "TESTPOINT")
    (attr exclude_from_pos_files exclude_from_bom)
    (fp_text reference "TP_S12" (at -0.15 -2.5016 90) (layer "F.SilkS")
        (effects (font (size 0.7 0.7) (thickness 0.15)))
    )
    (fp_text value "TP_1mm_SMD" (at 0 1.4) (layer "F.Fab")
        (effects (font (size 0.7 0.7) (thickness 0.15)) (justify left bottom))
    )
    (fp_text user "${REFERENCE}" (at -0.5 2.8) (layer "F.Fab") hide
        (effects (font (size 0.7 0.7) (thickness 0.15)) (justify left bottom))
    )
    (fp_text user "License: Apache-2.0" (at -0.5 5.2) (layer "F.Fab") hide
        (effects (font (size 0.7 0.7) (thickness 0.15)) (justify left bottom))
    )
    (fp_text user "Author: Antmicro" (at -0.5 4) (layer "F.Fab") hide
        (effects (font (size 0.7 0.7) (thickness 0.15)) (justify left bottom))
    )
    (fp_circle (center 0 0) (end 0.6 0)
      (stroke (width 0.05) (type default)) (fill none) (layer "F.CrtYd"))
    (pad "1" smd circle (at 0 0) (size 1 1) (layers "F.Cu" "F.Mask")
      (net 56 "Net-(J10-PadS12)") (pinfunction "1") (pintype "passive"))
  )

  (footprint "antmicro-footprints:TP_SMD_1mm" (layer "F.Cu")
    (at 122.1508 131.4 -90)
    (property "Author" "Antmicro")
    (property "License" "Apache-2.0")
    (property "MPN" "")
    (property "Manufacturer" "")
    (property "Sheetfile" "d1600e-psu-breakout-board.kicad_sch")
    (property "Sheetname" "")
    (property "exclude_from_bom" "")
    (property "ki_description" "Test point 1mm SMD")
    (property "ki_keywords" "TESTPOINT")
    (attr exclude_from_pos_files exclude_from_bom)
    (fp_text reference "TP_S23" (at -0.7 -0.45 -90) (layer "F.SilkS")
        (effects (font (size 0.7 0.7) (thickness 0.15)) (justify left bottom))
    )
    (fp_text value "TP_1mm_SMD" (at 0 1.4 -90) (layer "F.Fab")
        (effects (font (size 0.7 0.7) (thickness 0.15)) (justify left bottom))
    )
    (fp_text user "${REFERENCE}" (at -0.5 2.8 -90) (layer "F.Fab") hide
        (effects (font (size 0.7 0.7) (thickness 0.15)) (justify left bottom))
    )
    (fp_text user "Author: Antmicro" (at -0.5 4 -90) (layer "F.Fab") hide
        (effects (font (size 0.7 0.7) (thickness 0.15)) (justify left bottom))
    )
    (fp_text user "License: Apache-2.0" (at -0.5 5.2 -90) (layer "F.Fab") hide
        (effects (font (size 0.7 0.7) (thickness 0.15)) (justify left bottom))
    )
    (fp_circle (center 0 0) (end 0.6 0)
      (stroke (width 0.05) (type default)) (fill none) (layer "F.CrtYd"))
    (pad "1" smd circle (at 0 0 270) (size 1 1) (layers "F.Cu" "F.Mask")
      (net 68 "Net-(J10-PadS23)") (pinfunction "1") (pintype "passive"))
  )

  (footprint "antmicro-footprints:Socket_Amphenol_HPCE_2x17_10107844-002LF" (layer "F.Cu")
    (at 140.009 150.519)
    (property "Author" "Antmicro")
    (property "License" "Apache-2.0")
    (property "MPN" "10107844-002LF")
    (property "Manufacturer" "Amphenol")
    (property "Sheetfile" "d1600e-psu-breakout-board.kicad_sch")
    (property "Sheetname" "")
    (property "ki_description" "60 (24 + 36 Power) Position Edge Card Connector")
    (property "ki_keywords" "HORIZONTAL, EDGE, CONNECTOR, SOCKET")
    (fp_text reference "J10" (at -37.159 -9.269) (layer "F.SilkS")
        (effects (font (size 0.7 0.7) (thickness 0.15)) (justify left bottom))
    )
    (fp_text value "Socket_Amphenol_HPCE_2x17_10107844-002LF" (at 0 13) (layer "F.Fab")
        (effects (font (size 0.7 0.7) (thickness 0.15)) (justify left bottom))
    )
    (fp_text user "Author: Antmicro" (at -40.07 14.12) (layer "F.Fab") hide
        (effects (font (size 0.7 0.7) (thickness 0.15)) (justify left bottom))
    )
    (fp_text user "License: Apache-2.0" (at -40.07 16.52) (layer "F.Fab") hide
        (effects (font (size 0.7 0.7) (thickness 0.15)) (justify left bottom))
    )
    (fp_text user "${REFERENCE}" (at -40.07 15.32) (layer "F.Fab") hide
        (effects (font (size 0.7 0.7) (thickness 0.15)) (justify left bottom))
    )
    (fp_poly
      (pts
        (xy -9.859 -4.72)
        (xy -14.058 -4.72)
        (xy -14.058 -11.719)
        (xy -9.859 -11.719)
      )

      (stroke (width 0.1) (type solid)) (fill solid) (layer "B.Paste"))
    (fp_poly
      (pts
        (xy -4.754 -4.715)
        (xy -8.949 -4.72)
        (xy -8.956 -11.821)
        (xy -4.761 -11.817)
      )

      (stroke (width 0.1) (type solid)) (fill solid) (layer "B.Paste"))
    (fp_poly
      (pts
        (xy 0.235 -4.715)
        (xy -3.959 -4.72)
        (xy -3.966 -11.821)
        (xy 0.227 -11.817)
      )

      (stroke (width 0.1) (type solid)) (fill solid) (layer "B.Paste"))
    (fp_poly
      (pts
        (xy 5.436 -4.715)
        (xy 1.241 -4.72)
        (xy 1.233 -11.821)
        (xy 5.428 -11.817)
      )

      (stroke (width 0.1) (type solid)) (fill solid) (layer "B.Paste"))
    (fp_poly
      (pts
        (xy 10.435 -4.715)
        (xy 6.24 -4.72)
        (xy 6.232 -11.821)
        (xy 10.428 -11.817)
      )

      (stroke (width 0.1) (type solid)) (fill solid) (layer "B.Paste"))
    (fp_poly
      (pts
        (xy 15.586 -4.715)
        (xy 11.39 -4.72)
        (xy 11.383 -11.821)
        (xy 15.578 -11.817)
      )

      (stroke (width 0.1) (type solid)) (fill solid) (layer "B.Paste"))
    (fp_poly
      (pts
        (xy 20.535 -4.765)
        (xy 16.34 -4.769)
        (xy 16.332 -11.872)
        (xy 20.528 -11.866)
      )

      (stroke (width 0.1) (type solid)) (fill solid) (layer "B.Paste"))
    (fp_poly
      (pts
        (xy 25.736 -4.715)
        (xy 21.541 -4.72)
        (xy 21.532 -11.821)
        (xy 25.727 -11.817)
      )

      (stroke (width 0.1) (type solid)) (fill solid) (layer "B.Paste"))
    (fp_poly
      (pts
        (xy 30.686 -4.765)
        (xy 26.491 -4.769)
        (xy 26.483 -11.872)
        (xy 30.677 -11.866)
      )

      (stroke (width 0.1) (type solid)) (fill solid) (layer "B.Paste"))
    (fp_poly
      (pts
        (xy -9.959 -4.619)
        (xy -14.058 -4.619)
        (xy -14.058 -11.82)
        (xy -9.959 -11.82)
      )

      (stroke (width 0.1) (type solid)) (fill solid) (layer "F.Paste"))
    (fp_poly
      (pts
        (xy -4.759 -4.72)
        (xy -8.959 -4.72)
        (xy -8.959 -11.82)
        (xy -4.759 -11.82)
      )

      (stroke (width 0.1) (type solid)) (fill solid) (layer "F.Paste"))
    (fp_poly
      (pts
        (xy 0.19 -4.72)
        (xy -4.009 -4.72)
        (xy -4.009 -11.82)
        (xy 0.19 -11.82)
      )

      (stroke (width 0.1) (type solid)) (fill solid) (layer "F.Paste"))
    (fp_poly
      (pts
        (xy 5.441 -4.72)
        (xy 1.241 -4.72)
        (xy 1.241 -11.82)
        (xy 5.441 -11.82)
      )

      (stroke (width 0.1) (type solid)) (fill solid) (layer "F.Paste"))
    (fp_poly
      (pts
        (xy 10.441 -4.72)
        (xy 6.24 -4.72)
        (xy 6.24 -11.82)
        (xy 10.441 -11.82)
      )

      (stroke (width 0.1) (type solid)) (fill solid) (layer "F.Paste"))
    (fp_poly
      (pts
        (xy 15.64 -4.72)
        (xy 11.441 -4.72)
        (xy 11.441 -11.82)
        (xy 15.64 -11.82)
      )

      (stroke (width 0.1) (type solid)) (fill solid) (layer "F.Paste"))
    (fp_poly
      (pts
        (xy 20.59 -4.72)
        (xy 16.39 -4.72)
        (xy 16.39 -11.82)
        (xy 20.59 -11.82)
      )

      (stroke (width 0.1) (type solid)) (fill solid) (layer "F.Paste"))
    (fp_poly
      (pts
        (xy 25.791 -4.72)
        (xy 21.59 -4.72)
        (xy 21.59 -11.82)
        (xy 25.791 -11.82)
      )

      (stroke (width 0.1) (type solid)) (fill solid) (layer "F.Paste"))
    (fp_poly
      (pts
        (xy 30.741 -4.72)
        (xy 26.541 -4.72)
        (xy 26.541 -11.82)
        (xy 30.741 -11.82)
      )

      (stroke (width 0.1) (type solid)) (fill solid) (layer "F.Paste"))
    (fp_line (start -39.458 -8.17) (end -39.458 -0.27)
      (stroke (width 0.15) (type solid)) (layer "F.SilkS"))
    (fp_line (start -39.458 -8.17) (end -32.009 -8.17)
      (stroke (width 0.15) (type solid)) (layer "F.SilkS"))
    (fp_line (start -32.009 -8.17) (end -32.009 -10.869)
      (stroke (width 0.15) (type solid)) (layer "F.SilkS"))
    (fp_line (start 31.84 -8.17) (end 31.84 -12.02)
      (stroke (width 0.15) (type solid)) (layer "F.SilkS"))
    (fp_line (start 32.191 -8.17) (end 31.84 -8.17)
      (stroke (width 0.15) (type solid)) (layer "F.SilkS"))
    (fp_line (start 39.191 -8.17) (end 32.191 -8.17)
      (stroke (width 0.15) (type solid)) (layer "F.SilkS"))
    (fp_line (start 39.191 -8.17) (end 39.191 -0.27)
      (stroke (width 0.15) (type solid)) (layer "F.SilkS"))
    (fp_poly
      (pts
        (xy -9.789 -4.6)
        (xy -14.168 -4.6)
        (xy -14.168 -11.91)
        (xy -9.789 -11.91)
      )

      (stroke (width 0.1) (type solid)) (fill solid) (layer "B.Mask"))
    (fp_poly
      (pts
        (xy -4.608 -4.6)
        (xy -9.088 -4.6)
        (xy -9.088 -11.91)
        (xy -4.608 -11.91)
      )

      (stroke (width 0.1) (type solid)) (fill solid) (layer "B.Mask"))
    (fp_poly
      (pts
        (xy 0.366 -4.595)
        (xy -4.114 -4.595)
        (xy -4.114 -11.905)
        (xy 0.366 -11.905)
      )

      (stroke (width 0.1) (type solid)) (fill solid) (layer "B.Mask"))
    (fp_poly
      (pts
        (xy 5.596 -4.619)
        (xy 1.116 -4.619)
        (xy 1.116 -11.93)
        (xy 5.596 -11.93)
      )

      (stroke (width 0.1) (type solid)) (fill solid) (layer "B.Mask"))
    (fp_poly
      (pts
        (xy 10.571 -4.619)
        (xy 6.091 -4.619)
        (xy 6.091 -11.93)
        (xy 10.571 -11.93)
      )

      (stroke (width 0.1) (type solid)) (fill solid) (layer "B.Mask"))
    (fp_poly
      (pts
        (xy 15.77 -4.619)
        (xy 11.265 -4.614)
        (xy 11.265 -11.924)
        (xy 15.77 -11.93)
      )

      (stroke (width 0.1) (type solid)) (fill solid) (layer "B.Mask"))
    (fp_poly
      (pts
        (xy 20.695 -4.619)
        (xy 16.215 -4.619)
        (xy 16.215 -11.93)
        (xy 20.695 -11.93)
      )

      (stroke (width 0.1) (type solid)) (fill solid) (layer "B.Mask"))
    (fp_poly
      (pts
        (xy 25.921 -4.644)
        (xy 21.441 -4.644)
        (xy 21.441 -11.955)
        (xy 25.921 -11.955)
      )

      (stroke (width 0.1) (type solid)) (fill solid) (layer "B.Mask"))
    (fp_poly
      (pts
        (xy 30.87 -4.644)
        (xy 26.39 -4.644)
        (xy 26.39 -11.955)
        (xy 30.87 -11.955)
      )

      (stroke (width 0.1) (type solid)) (fill solid) (layer "B.Mask"))
    (fp_poly
      (pts
        (xy -9.789 -4.6)
        (xy -14.168 -4.6)
        (xy -14.168 -11.91)
        (xy -9.789 -11.91)
      )

      (stroke (width 0.1) (type solid)) (fill solid) (layer "F.Mask"))
    (fp_poly
      (pts
        (xy -4.608 -4.6)
        (xy -9.088 -4.6)
        (xy -9.088 -11.91)
        (xy -4.608 -11.91)
      )

      (stroke (width 0.1) (type solid)) (fill solid) (layer "F.Mask"))
    (fp_poly
      (pts
        (xy 5.601 -4.609)
        (xy 1.1 -4.609)
        (xy 1.1 -11.959)
        (xy 5.601 -11.959)
      )

      (stroke (width 0.1) (type solid)) (fill solid) (layer "F.Mask"))
    (fp_poly
      (pts
        (xy 10.571 -4.609)
        (xy 6.071 -4.609)
        (xy 6.071 -11.959)
        (xy 10.571 -11.959)
      )

      (stroke (width 0.1) (type solid)) (fill solid) (layer "F.Mask"))
    (fp_poly
      (pts
        (xy 15.761 -4.609)
        (xy 11.261 -4.609)
        (xy 11.261 -11.959)
        (xy 15.761 -11.959)
      )

      (stroke (width 0.1) (type solid)) (fill solid) (layer "F.Mask"))
    (fp_poly
      (pts
        (xy 20.73 -4.619)
        (xy 16.23 -4.619)
        (xy 16.23 -11.969)
        (xy 20.73 -11.969)
      )

      (stroke (width 0.1) (type solid)) (fill solid) (layer "F.Mask"))
    (fp_poly
      (pts
        (xy 25.921 -4.63)
        (xy 21.421 -4.63)
        (xy 21.421 -11.98)
        (xy 25.921 -11.98)
      )

      (stroke (width 0.1) (type solid)) (fill solid) (layer "F.Mask"))
    (fp_poly
      (pts
        (xy 30.89 -4.63)
        (xy 26.39 -4.63)
        (xy 26.39 -11.98)
        (xy 30.89 -11.98)
      )

      (stroke (width 0.1) (type solid)) (fill solid) (layer "F.Mask"))
    (fp_poly
      (pts
        (xy 0.371 -4.6)
        (xy -4.128 -4.6)
        (xy -4.128 -11.808)
        (xy -4.128 -11.94)
        (xy 0.371 -11.94)
      )

      (stroke (width 0.1) (type solid)) (fill solid) (layer "F.Mask"))
    (fp_line (start -37.75 -6.52) (end -32.15 -6.52)
      (stroke (width 0.05) (type solid)) (layer "B.CrtYd"))
    (fp_line (start -37.75 -6.47) (end -37.75 -6.52)
      (stroke (width 0.05) (type solid)) (layer "B.CrtYd"))
    (fp_line (start -37.75 -6.42) (end -37.75 -6.47)
      (stroke (width 0.05) (type solid)) (layer "B.CrtYd"))
    (fp_line (start -37.75 -1.72) (end -37.75 -6.42)
      (stroke (width 0.05) (type solid)) (layer "B.CrtYd"))
    (fp_line (start -37.65 -1.72) (end -37.75 -1.72)
      (stroke (width 0.05) (type solid)) (layer "B.CrtYd"))
    (fp_line (start -34.9 -1.72) (end -37.65 -1.72)
      (stroke (width 0.05) (type solid)) (layer "B.CrtYd"))
    (fp_line (start -34.9 11.83) (end -34.9 -1.72)
      (stroke (width 0.05) (type solid)) (layer "B.CrtYd"))
    (fp_line (start -34.84 11.83) (end -34.9 11.83)
      (stroke (width 0.05) (type solid)) (layer "B.CrtYd"))
    (fp_line (start -34.8 11.83) (end -34.84 11.83)
      (stroke (width 0.05) (type solid)) (layer "B.CrtYd"))
    (fp_line (start -32.15 -6.52) (end -32 -6.52)
      (stroke (width 0.05) (type solid)) (layer "B.CrtYd"))
    (fp_line (start -32 -11.21) (end -16.14 -11.21)
      (stroke (width 0.05) (type solid)) (layer "B.CrtYd"))
    (fp_line (start -32 -11.17) (end -32 -11.21)
      (stroke (width 0.05) (type solid)) (layer "B.CrtYd"))
    (fp_line (start -32 -6.52) (end -32 -11.17)
      (stroke (width 0.05) (type solid)) (layer "B.CrtYd"))
    (fp_line (start -16.14 -14.92) (end -16.14 -11.21)
      (stroke (width 0.05) (type solid)) (layer "B.CrtYd"))
    (fp_line (start -16.14 -14.92) (end 31.14 -14.92)
      (stroke (width 0.05) (type solid)) (layer "B.CrtYd"))
    (fp_line (start 31.14 -6.52) (end 31.14 -14.92)
      (stroke (width 0.05) (type solid)) (layer "B.CrtYd"))
    (fp_line (start 31.14 -6.52) (end 37.64 -6.52)
      (stroke (width 0.05) (type solid)) (layer "B.CrtYd"))
    (fp_line (start 33.79 -1.72) (end 33.79 11.78)
      (stroke (width 0.05) (type solid)) (layer "B.CrtYd"))
    (fp_line (start 33.79 11.78) (end 33.79 11.83)
      (stroke (width 0.05) (type solid)) (layer "B.CrtYd"))
    (fp_line (start 33.79 11.83) (end -34.8 11.83)
      (stroke (width 0.05) (type solid)) (layer "B.CrtYd"))
    (fp_line (start 36.89 -1.72) (end 33.79 -1.72)
      (stroke (width 0.05) (type solid)) (layer "B.CrtYd"))
    (fp_line (start 37.64 -6.52) (end 37.73 -6.52)
      (stroke (width 0.05) (type solid)) (layer "B.CrtYd"))
    (fp_line (start 37.73 -6.52) (end 37.73 -5.22)
      (stroke (width 0.05) (type solid)) (layer "B.CrtYd"))
    (fp_line (start 37.73 -5.22) (end 37.73 -1.82)
      (stroke (width 0.05) (type solid)) (layer "B.CrtYd"))
    (fp_line (start 37.73 -1.82) (end 37.73 -1.72)
      (stroke (width 0.05) (type solid)) (layer "B.CrtYd"))
    (fp_line (start 37.73 -1.72) (end 36.89 -1.72)
      (stroke (width 0.05) (type solid)) (layer "B.CrtYd"))
    (fp_line (start -39.8 -8.51) (end -32.29 -8.51)
      (stroke (width 0.05) (type solid)) (layer "F.CrtYd"))
    (fp_line (start -39.8 0.22) (end -39.8 -8.51)
      (stroke (width 0.05) (type solid)) (layer "F.CrtYd"))
    (fp_line (start -35.05 0.22) (end -39.8 0.22)
      (stroke (width 0.05) (type solid)) (layer "F.CrtYd"))
    (fp_line (start -35.05 11.98) (end -35.05 0.22)
      (stroke (width 0.05) (type solid)) (layer "F.CrtYd"))
    (fp_line (start -32.29 -11.27) (end -16.14 -11.27)
      (stroke (width 0.05) (type solid)) (layer "F.CrtYd"))
    (fp_line (start -32.29 -8.51) (end -32.29 -11.27)
      (stroke (width 0.05) (type solid)) (layer "F.CrtYd"))
    (fp_line (start -16.14 -14.92) (end 32.18 -14.92)
      (stroke (width 0.05) (type solid)) (layer "F.CrtYd"))
    (fp_line (start -16.14 -11.27) (end -16.14 -14.92)
      (stroke (width 0.05) (type solid)) (layer "F.CrtYd"))
    (fp_line (start 32.18 -8.51) (end 32.18 -14.92)
      (stroke (width 0.05) (type solid)) (layer "F.CrtYd"))
    (fp_line (start 32.18 -8.51) (end 39.68 -8.51)
      (stroke (width 0.05) (type solid)) (layer "F.CrtYd"))
    (fp_line (start 33.93 0.22) (end 33.93 11.98)
      (stroke (width 0.05) (type solid)) (layer "F.CrtYd"))
    (fp_line (start 33.93 11.98) (end -35.05 11.98)
      (stroke (width 0.05) (type solid)) (layer "F.CrtYd"))
    (fp_line (start 39.68 -8.51) (end 39.68 0.22)
      (stroke (width 0.05) (type solid)) (layer "F.CrtYd"))
    (fp_line (start 39.68 0.22) (end 33.93 0.22)
      (stroke (width 0.05) (type solid)) (layer "F.CrtYd"))
    (fp_line (start -37.409 -6.17) (end -31.659 -6.17)
      (stroke (width 0.15) (type solid)) (layer "B.Fab"))
    (fp_line (start -37.409 -2.07) (end -37.409 -6.17)
      (stroke (width 0.15) (type solid)) (layer "B.Fab"))
    (fp_line (start -34.559 -2.07) (end -37.409 -2.07)
      (stroke (width 0.15) (type solid)) (layer "B.Fab"))
    (fp_line (start -34.559 -2.07) (end -34.559 11.48)
      (stroke (width 0.15) (type solid)) (layer "B.Fab"))
    (fp_line (start -34.559 11.48) (end 33.441 11.48)
      (stroke (width 0.15) (type solid)) (layer "B.Fab"))
    (fp_line (start -31.659 -10.92) (end -16.158 -10.92)
      (stroke (width 0.15) (type solid)) (layer "B.Fab"))
    (fp_line (start -31.659 -6.17) (end -31.659 -10.92)
      (stroke (width 0.15) (type solid)) (layer "B.Fab"))
    (fp_line (start -16.158 -12.369) (end 30.941 -12.369)
      (stroke (width 0.15) (type solid)) (layer "B.Fab"))
    (fp_line (start -16.158 -11.219) (end -16.158 -12.369)
      (stroke (width 0.15) (type solid)) (layer "B.Fab"))
    (fp_line (start 30.941 -6.17) (end 30.941 -12.369)
      (stroke (width 0.15) (type solid)) (layer "B.Fab"))
    (fp_line (start 33.441 -2.07) (end 33.441 11.48)
      (stroke (width 0.15) (type solid)) (layer "B.Fab"))
    (fp_line (start 37.391 -6.17) (end 30.941 -6.17)
      (stroke (width 0.15) (type solid)) (layer "B.Fab"))
    (fp_line (start 37.391 -2.07) (end 33.441 -2.07)
      (stroke (width 0.15) (type solid)) (layer "B.Fab"))
    (fp_line (start 37.391 -2.07) (end 37.391 -6.17)
      (stroke (width 0.15) (type solid)) (layer "B.Fab"))
    (fp_line (start -39.458 -8.17) (end -39.458 -0.27)
      (stroke (width 0.15) (type solid)) (layer "F.Fab"))
    (fp_line (start -39.458 -8.17) (end -32.009 -8.17)
      (stroke (width 0.15) (type solid)) (layer "F.Fab"))
    (fp_line (start -34.559 -0.27) (end -39.458 -0.27)
      (stroke (width 0.15) (type solid)) (layer "F.Fab"))
    (fp_line (start -34.559 -0.27) (end -34.559 11.48)
      (stroke (width 0.15) (type solid)) (layer "F.Fab"))
    (fp_line (start -34.559 11.48) (end 33.441 11.48)
      (stroke (width 0.15) (type solid)) (layer "F.Fab"))
    (fp_line (start -32.009 -8.17) (end -32.009 -10.869)
      (stroke (width 0.15) (type solid)) (layer "F.Fab"))
    (fp_line (start -16.158 -12.369) (end 31.84 -12.369)
      (stroke (width 0.15) (type solid)) (layer "F.Fab"))
    (fp_line (start -16.158 -10.92) (end -31.958 -10.92)
      (stroke (width 0.15) (type solid)) (layer "F.Fab"))
    (fp_line (start -16.158 -10.92) (end -16.158 -12.369)
      (stroke (width 0.15) (type solid)) (layer "F.Fab"))
    (fp_line (start 31.84 -8.17) (end 31.84 -12.369)
      (stroke (width 0.15) (type solid)) (layer "F.Fab"))
    (fp_line (start 33.441 -0.27) (end 33.441 11.48)
      (stroke (width 0.15) (type solid)) (layer "F.Fab"))
    (fp_line (start 39.191 -8.17) (end 31.84 -8.17)
      (stroke (width 0.15) (type solid)) (layer "F.Fab"))
    (fp_line (start 39.191 -8.17) (end 39.191 -0.27)
      (stroke (width 0.15) (type solid)) (layer "F.Fab"))
    (fp_line (start 39.191 -0.27) (end 33.441 -0.27)
      (stroke (width 0.15) (type solid)) (layer "F.Fab"))
    (pad "" np_thru_hole circle (at -35.329 -4.12) (size 3.7 3.7) (drill 3.7) (layers "F&B.Cu" "*.Mask"))
    (pad "" np_thru_hole circle (at 35.331 -4.12) (size 3.7 3.7) (drill 3.7) (layers "F&B.Cu" "*.Mask"))
    (pad "P1/2" smd rect (at 28.602 -9.6 90) (size 10 4.495) (layers "F.Cu")
      (net 11 "VCC12V0") (pinfunction "P1") (pintype "power_in"))
    (pad "P3/4" smd rect (at 23.637 -9.6 90) (size 10 4.495) (layers "F.Cu")
      (net 11 "VCC12V0") (pinfunction "P3") (pintype "power_in"))
    (pad "P5/6" smd rect (at 18.442 -9.6 90) (size 10 4.495) (layers "F.Cu")
      (net 11 "VCC12V0") (pinfunction "P5") (pintype "power_in"))
    (pad "P7/8" smd rect (at 13.478 -9.6 90) (size 10 4.495) (layers "F.Cu")
      (net 11 "VCC12V0") (pinfunction "P7") (pintype "power_in"))
    (pad "P9/10" smd rect (at 8.283 -9.6 90) (size 10 4.495) (layers "F.Cu")
      (net 4 "GND") (pinfunction "P9") (pintype "power_in"))
    (pad "P11/12" smd rect (at 3.317 -9.6 90) (size 10 4.495) (layers "F.Cu")
      (net 4 "GND") (pinfunction "P11") (pintype "power_in"))
    (pad "P13/14" smd rect (at -1.875 -9.6 90) (size 10 4.495) (layers "F.Cu")
      (net 4 "GND") (pinfunction "P13") (pintype "power_in"))
    (pad "P15/16" smd rect (at -6.841 -9.6 90) (size 10 4.495) (layers "F.Cu")
      (net 4 "GND") (pinfunction "P15") (pintype "power_in"))
    (pad "P17/18" smd rect (at -11.978 -9.6 90) (size 10 4.381) (layers "F.Cu")
      (net 4 "GND") (pinfunction "P17") (pintype "power_in"))
    (pad "P19/20" smd rect (at -11.978 -9.6 90) (size 10 4.381) (layers "B.Cu")
      (net 92 "unconnected-(J10-P19-PadP19{slash}20)") (pinfunction "P19") (pintype "power_in+no_connect"))
    (pad "P21/22" smd rect (at -6.841 -9.6 90) (size 10 4.495) (layers "B.Cu")
      (net 4 "GND") (pinfunction "P21") (pintype "power_in"))
    (pad "P23/24" smd rect (at -1.875 -9.6 90) (size 10 4.495) (layers "B.Cu")
      (net 4 "GND") (pinfunction "P23") (pintype "power_in"))
    (pad "P25/26" smd rect (at 3.317 -9.6 90) (size 10 4.495) (layers "B.Cu")
      (net 4 "GND") (pinfunction "P25") (pintype "power_in"))
    (pad "P27/28" smd rect (at 8.283 -9.6 90) (size 10 4.495) (layers "B.Cu")
      (net 4 "GND") (pinfunction "P27") (pintype "power_in"))
    (pad "P29/30" smd rect (at 13.478 -9.6 90) (size 10 4.495) (layers "B.Cu")
      (net 11 "VCC12V0") (pinfunction "P29") (pintype "power_in"))
    (pad "P31/32" smd rect (at 18.442 -9.6 90) (size 10 4.495) (layers "B.Cu")
      (net 11 "VCC12V0") (pinfunction "P31") (pintype "power_in"))
    (pad "P33/34" smd rect (at 23.637 -9.6 90) (size 10 4.495) (layers "B.Cu")
      (net 11 "VCC12V0") (pinfunction "P33") (pintype "power_in"))
    (pad "P35/36" smd rect (at 28.602 -9.6 90) (size 10 4.495) (layers "B.Cu")
      (net 11 "VCC12V0") (pinfunction "P35") (pintype "power_in"))
    (pad "S1" smd rect (at -16.758 -7.744) (size 0.81 6.3) (layers "F.Cu" "F.Paste" "F.Mask")
      (net 64 "Net-(J10-PadS1)") (pinfunction "S1") (pintype "passive"))
    (pad "S2" smd rect (at -18.029 -7.744) (size 0.81 6.3) (layers "F.Cu" "F.Paste" "F.Mask")
      (net 65 "Net-(J10-PadS2)") (pinfunction "S2") (pintype "passive"))
    (pad "S3" smd rect (at -19.298 -7.744) (size 0.81 6.3) (layers "F.Cu" "F.Paste" "F.Mask")
      (net 66 "Net-(J10-PadS3)") (pinfunction "S3") (pintype "passive"))
    (pad "S4" smd rect (at -20.569 -7.744) (size 0.81 6.3) (layers "F.Cu" "F.Paste" "F.Mask")
      (net 67 "Net-(J10-PadS4)") (pinfunction "S4") (pintype "passive"))
    (pad "S5" smd rect (at -21.839 -7.744) (size 0.81 6.3) (layers "F.Cu" "F.Paste" "F.Mask")
      (net 60 "Net-(J10-PadS5)") (pinfunction "S5") (pintype "passive"))
    (pad "S6" smd rect (at -23.109 -7.744) (size 0.81 6.3) (layers "F.Cu" "F.Paste" "F.Mask")
      (net 61 "Net-(J10-PadS6)") (pinfunction "S6") (pintype "passive"))
    (pad "S7" smd rect (at -24.379 -7.744) (size 0.81 6.3) (layers "F.Cu" "F.Paste" "F.Mask")
      (net 62 "Net-(J10-PadS7)") (pinfunction "S7") (pintype "passive"))
    (pad "S8" smd rect (at -25.649 -7.744) (size 0.81 6.3) (layers "F.Cu" "F.Paste" "F.Mask")
      (net 63 "Net-(J10-PadS8)") (pinfunction "S8") (pintype "passive"))
    (pad "S9" smd rect (at -26.919 -7.744) (size 0.81 6.3) (layers "F.Cu" "F.Paste" "F.Mask")
      (net 59 "Net-(J10-PadS9)") (pinfunction "S9") (pintype "passive"))
    (pad "S10" smd rect (at -28.189 -7.744) (size 0.81 6.3) (layers "F.Cu" "F.Paste" "F.Mask")
      (net 58 "Net-(J10-PadS10)") (pinfunction "S10") (pintype "passive"))
    (pad "S11" smd rect (at -29.458 -7.744) (size 0.81 6.3) (layers "F.Cu" "F.Paste" "F.Mask")
      (net 57 "Net-(J10-PadS11)") (pinfunction "S11") (pintype "passive"))
    (pad "S12" smd rect (at -30.729 -7.744) (size 0.81 6.3) (layers "F.Cu" "F.Paste" "F.Mask")
      (net 56 "Net-(J10-PadS12)") (pinfunction "S12") (pintype "passive"))
    (pad "S13" smd rect (at -30.729 -7.744) (size 0.81 6.3) (layers "B.Cu" "B.Paste" "B.Mask")
      (net 51 "PSU_ON") (pinfunction "S13") (pintype "passive"))
    (pad "S14" smd rect (at -29.458 -7.744) (size 0.81 6.3) (layers "B.Cu" "B.Paste" "B.Mask")
      (net 51 "PSU_ON") (pinfunction "S14") (pintype "passive"))
    (pad "S15" smd rect (at -28.189 -7.744) (size 0.81 6.3) (layers "B.Cu" "B.Paste" "B.Mask")
      (net 51 "PSU_ON") (pinfunction "S15") (pintype "passive"))
    (pad "S16" smd rect (at -26.919 -7.744) (size 0.81 6.3) (layers "B.Cu" "B.Paste" "B.Mask")
      (net 75 "Net-(J10-PadS16)") (pinfunction "S16") (pintype "passive"))
    (pad "S17" smd rect (at -25.649 -7.744) (size 0.81 6.3) (layers "B.Cu" "B.Paste" "B.Mask")
      (net 72 "Net-(J10-PadS17)") (pinfunction "S17") (pintype "passive"))
    (pad "S18" smd rect (at -24.379 -7.744) (size 0.81 6.3) (layers "B.Cu" "B.Paste" "B.Mask")
      (net 73 "Net-(J10-PadS18)") (pinfunction "S18") (pintype "passive"))
    (pad "S19" smd rect (at -23.109 -7.744) (size 0.81 6.3) (layers "B.Cu" "B.Paste" "B.Mask")
      (net 71 "Net-(J10-PadS19)") (pinfunction "S19") (pintype "passive"))
    (pad "S20" smd rect (at -21.839 -7.744) (size 0.81 6.3) (layers "B.Cu" "B.Paste" "B.Mask")
      (net 74 "Net-(J10-PadS20)") (pinfunction "S20") (pintype "passive"))
    (pad "S21" smd rect (at -20.569 -7.744) (size 0.81 6.3) (layers "B.Cu" "B.Paste" "B.Mask")
      (net 69 "Net-(J10-PadS21)") (pinfunction "S21") (pintype "passive"))
    (pad "S22" smd rect (at -19.298 -7.744) (size 0.81 6.3) (layers "B.Cu" "B.Paste" "B.Mask")
      (net 70 "Net-(J10-PadS22)") (pinfunction "S22") (pintype "passive"))
    (pad "S23" smd rect (at -18.029 -7.744) (size 0.81 6.3) (layers "B.Cu" "B.Paste" "B.Mask")
      (net 68 "Net-(J10-PadS23)") (pinfunction "S23") (pintype "passive"))
    (pad "S24" smd rect (at -16.758 -7.744) (size 0.81 6.3) (layers "B.Cu" "B.Paste" "B.Mask")
      (net 55 "Net-(J10-PadS24)") (pinfunction "S24") (pintype "passive"))
  )

  (footprint "antmicro-footprints:TP_SMD_1mm" (layer "F.Cu")
    (at 114.3 131.4 -90)
    (property "Author" "Antmicro")
    (property "License" "Apache-2.0")
    (property "MPN" "")
    (property "Manufacturer" "")
    (property "Sheetfile" "d1600e-psu-breakout-board.kicad_sch")
    (property "Sheetname" "")
    (property "exclude_from_bom" "")
    (property "ki_description" "Test point 1mm SMD")
    (property "ki_keywords" "TESTPOINT")
    (attr exclude_from_pos_files exclude_from_bom)
    (fp_text reference "TP_S17" (at -0.7 -0.45 -90) (layer "F.SilkS")
        (effects (font (size 0.7 0.7) (thickness 0.15)) (justify left bottom))
    )
    (fp_text value "TP_1mm_SMD" (at 0 1.4 -90) (layer "F.Fab")
        (effects (font (size 0.7 0.7) (thickness 0.15)) (justify left bottom))
    )
    (fp_text user "Author: Antmicro" (at -0.5 4 -90) (layer "F.Fab") hide
        (effects (font (size 0.7 0.7) (thickness 0.15)) (justify left bottom))
    )
    (fp_text user "${REFERENCE}" (at -0.5 2.8 -90) (layer "F.Fab") hide
        (effects (font (size 0.7 0.7) (thickness 0.15)) (justify left bottom))
    )
    (fp_text user "License: Apache-2.0" (at -0.5 5.2 -90) (layer "F.Fab") hide
        (effects (font (size 0.7 0.7) (thickness 0.15)) (justify left bottom))
    )
    (fp_circle (center 0 0) (end 0.6 0)
      (stroke (width 0.05) (type default)) (fill none) (layer "F.CrtYd"))
    (pad "1" smd circle (at 0 0 270) (size 1 1) (layers "F.Cu" "F.Mask")
      (net 72 "Net-(J10-PadS17)") (pinfunction "1") (pintype "passive"))
  )

  (footprint "antmicro-footprints:TP_SMD_1mm" (layer "F.Cu")
    (at 113 131.4 -90)
    (property "Author" "Antmicro")
    (property "License" "Apache-2.0")
    (property "MPN" "")
    (property "Manufacturer" "")
    (property "Sheetfile" "d1600e-psu-breakout-board.kicad_sch")
    (property "Sheetname" "")
    (property "exclude_from_bom" "")
    (property "ki_description" "Test point 1mm SMD")
    (property "ki_keywords" "TESTPOINT")
    (attr exclude_from_pos_files exclude_from_bom)
    (fp_text reference "TP_S16" (at -0.7 -0.45 -90) (layer "F.SilkS")
        (effects (font (size 0.7 0.7) (thickness 0.15)) (justify left bottom))
    )
    (fp_text value "TP_1mm_SMD" (at 0 1.4 -90) (layer "F.Fab")
        (effects (font (size 0.7 0.7) (thickness 0.15)) (justify left bottom))
    )
    (fp_text user "Author: Antmicro" (at -0.5 4 -90) (layer "F.Fab") hide
        (effects (font (size 0.7 0.7) (thickness 0.15)) (justify left bottom))
    )
    (fp_text user "${REFERENCE}" (at -0.5 2.8 -90) (layer "F.Fab") hide
        (effects (font (size 0.7 0.7) (thickness 0.15)) (justify left bottom))
    )
    (fp_text user "License: Apache-2.0" (at -0.5 5.2 -90) (layer "F.Fab") hide
        (effects (font (size 0.7 0.7) (thickness 0.15)) (justify left bottom))
    )
    (fp_circle (center 0 0) (end 0.6 0)
      (stroke (width 0.05) (type default)) (fill none) (layer "F.CrtYd"))
    (pad "1" smd circle (at 0 0 270) (size 1 1) (layers "F.Cu" "F.Mask")
      (net 75 "Net-(J10-PadS16)") (pinfunction "1") (pintype "passive"))
  )

  (footprint "antmicro-footprints:R_0402_1005Metric" (layer "F.Cu")
    (at 131.4 92.05 180)
    (descr "Resistor SMD 0402")
    (tags "resistor SMD 0402")
    (property "Author" "Antmicro")
    (property "License" "Apache-2.0")
    (property "MPN" "CR0402-FX-4701GLF")
    (property "Manufacturer" "Bourns")
    (property "Sheetfile" "power-switch.kicad_sch")
    (property "Sheetname" "Power switch 2")
    (property "Tolerance" "1%")
    (property "Val" "4k7")
    (property "ki_description" "SMD Chip Resistor, 4.7 kohm, ± 1%, 62.5 mW, 0402 [1005 Metric], Thick Film, General Purpose")
    (property "ki_keywords" "0402, SMT, RESISTOR, PASSIVE")
    (zone_connect 1)
    (attr smd)
    (fp_text reference "R23" (at -0.45 -1.45 180) (layer "F.SilkS")
        (effects (font (size 0.7 0.7) (thickness 0.15)) (justify left bottom))
    )
    (fp_text value "R_4k7_0402" (at -1.011843 1.772047 180) (layer "F.Fab")
        (effects (font (size 0.7 0.7) (thickness 0.15)) (justify left bottom))
    )
    (fp_text user "${REFERENCE}" (at -0.95 3.168 180) (layer "F.Fab") hide
        (effects (font (size 0.7 0.7) (thickness 0.15)) (justify left bottom))
    )
    (fp_text user "License: Apache-2.0" (at -0.95 5.169 180) (layer "F.Fab") hide
        (effects (font (size 0.7 0.7) (thickness 0.15)) (justify left bottom))
    )
    (fp_text user "Author: Antmicro" (at -0.95 4.169 180) (layer "F.Fab") hide
        (effects (font (size 0.7 0.7) (thickness 0.15)) (justify left bottom))
    )
    (fp_rect (start -0.925 -0.47) (end 0.925 0.47)
      (stroke (width 0.05) (type default)) (fill none) (layer "F.CrtYd"))
    (fp_rect (start -0.5 -0.25) (end 0.5 0.25)
      (stroke (width 0.15) (type solid)) (fill none) (layer "F.Fab"))
    (pad "1" smd roundrect (at -0.48 0 180) (size 0.59 0.64) (layers "F.Cu" "F.Paste" "F.Mask") (roundrect_rratio 0.25)
      (net 11 "VCC12V0") (pintype "passive"))
    (pad "2" smd roundrect (at 0.48 0 180) (size 0.59 0.64) (layers "F.Cu" "F.Paste" "F.Mask") (roundrect_rratio 0.25)
      (net 84 "Net-(D16-A)") (pintype "passive"))
  )

  (footprint "antmicro-footprints:TP_SMD_1mm" (layer "F.Cu")
    (at 120.8508 131.4 -90)
    (property "Author" "Antmicro")
    (property "License" "Apache-2.0")
    (property "MPN" "")
    (property "Manufacturer" "")
    (property "Sheetfile" "d1600e-psu-breakout-board.kicad_sch")
    (property "Sheetname" "")
    (property "exclude_from_bom" "")
    (property "ki_description" "Test point 1mm SMD")
    (property "ki_keywords" "TESTPOINT")
    (attr exclude_from_pos_files exclude_from_bom)
    (fp_text reference "TP_S22" (at -0.7 -0.45 -90) (layer "F.SilkS")
        (effects (font (size 0.7 0.7) (thickness 0.15)) (justify left bottom))
    )
    (fp_text value "TP_1mm_SMD" (at 0 1.4 -90) (layer "F.Fab")
        (effects (font (size 0.7 0.7) (thickness 0.15)) (justify left bottom))
    )
    (fp_text user "License: Apache-2.0" (at -0.5 5.2 -90) (layer "F.Fab") hide
        (effects (font (size 0.7 0.7) (thickness 0.15)) (justify left bottom))
    )
    (fp_text user "Author: Antmicro" (at -0.5 4 -90) (layer "F.Fab") hide
        (effects (font (size 0.7 0.7) (thickness 0.15)) (justify left bottom))
    )
    (fp_text user "${REFERENCE}" (at -0.5 2.8 -90) (layer "F.Fab") hide
        (effects (font (size 0.7 0.7) (thickness 0.15)) (justify left bottom))
    )
    (fp_circle (center 0 0) (end 0.6 0)
      (stroke (width 0.05) (type default)) (fill none) (layer "F.CrtYd"))
    (pad "1" smd circle (at 0 0 270) (size 1 1) (layers "F.Cu" "F.Mask")
      (net 70 "Net-(J10-PadS22)") (pinfunction "1") (pintype "passive"))
  )

  (footprint "antmicro-footprints:TP_SMD_1mm" (layer "F.Cu")
    (at 186.2 126.7758)
    (property "Author" "Antmicro")
    (property "License" "Apache-2.0")
    (property "MPN" "")
    (property "Manufacturer" "")
    (property "Sheetfile" "ftdi-module.kicad_sch")
    (property "Sheetname" "FTDI")
    (property "exclude_from_bom" "")
    (property "ki_description" "Test point 1mm SMD")
    (property "ki_keywords" "TESTPOINT")
    (attr exclude_from_pos_files exclude_from_bom)
    (fp_text reference "3V3_USB1" (at -4.3 1.6242) (layer "F.SilkS")
        (effects (font (size 0.7 0.7) (thickness 0.15)) (justify left bottom))
    )
    (fp_text value "TP_1mm_SMD" (at 0 1.4) (layer "F.Fab")
        (effects (font (size 0.7 0.7) (thickness 0.15)) (justify left bottom))
    )
    (fp_text user "Author: Antmicro" (at -0.5 4) (layer "F.Fab") hide
        (effects (font (size 0.7 0.7) (thickness 0.15)) (justify left bottom))
    )
    (fp_text user "License: Apache-2.0" (at -0.5 5.2) (layer "F.Fab") hide
        (effects (font (size 0.7 0.7) (thickness 0.15)) (justify left bottom))
    )
    (fp_text user "${REFERENCE}" (at -0.5 2.8) (layer "F.Fab") hide
        (effects (font (size 0.7 0.7) (thickness 0.15)) (justify left bottom))
    )
    (fp_circle (center 0 0) (end 0.6 0)
      (stroke (width 0.05) (type default)) (fill none) (layer "F.CrtYd"))
    (pad "1" smd circle (at 0 0) (size 1 1) (layers "F.Cu" "F.Mask")
      (net 76 "VCC3V3_USB") (pinfunction "1") (pintype "passive"))
  )

  (footprint "antmicro-footprints:C_0402_1005Metric" (layer "F.Cu")
    (at 174.3 110.55)
    (descr "Capacitor SMD 0402")
    (tags "capacitor SMD 0402")
    (property "Author" "Antmicro")
    (property "Dielectric" "X5R")
    (property "License" "Apache-2.0")
    (property "MPN" "GRM155R61H104KE14D")
    (property "Manufacturer" "Murata")
    (property "Sheetfile" "ftdi-module.kicad_sch")
    (property "Sheetname" "FTDI")
    (property "Val" "100n")
    (property "Voltage" "50V")
    (property "ki_description" "SMD Multilayer Ceramic Capacitor, 0.1 µF, 50 V, 0402 [1005 Metric], ± 10%, X5R, GRM Series")
    (property "ki_keywords" "0402, SMT, CAPACITOR, PASSIVE, CERAMIC, MLCC")
    (attr smd)
    (fp_text reference "C16" (at -1.9 1.45) (layer "F.SilkS")
        (effects (font (size 0.7 0.7) (thickness 0.15)) (justify left bottom))
    )
    (fp_text value "C_100n_0402" (at -1.022927 2.155213) (layer "F.Fab")
        (effects (font (size 0.7 0.7) (thickness 0.15)) (justify left bottom))
    )
    (fp_text user "Author: Antmicro" (at -0.939 3.399) (layer "F.Fab") hide
        (effects (font (size 0.7 0.7) (thickness 0.15)) (justify left bottom))
    )
    (fp_text user "License: Apache-2.0" (at -0.939 5.799) (layer "F.Fab") hide
        (effects (font (size 0.7 0.7) (thickness 0.15)) (justify left bottom))
    )
    (fp_text user "${REFERENCE}" (at -0.939 4.599) (layer "F.Fab") hide
        (effects (font (size 0.7 0.7) (thickness 0.15)) (justify left bottom))
    )
    (fp_rect (start -0.925 -0.47) (end 0.925 0.47)
      (stroke (width 0.05) (type default)) (fill none) (layer "F.CrtYd"))
    (fp_line (start -0.494 -0.25) (end 0.504 -0.25)
      (stroke (width 0.15) (type solid)) (layer "F.Fab"))
    (fp_line (start -0.494 0.248) (end -0.494 -0.25)
      (stroke (width 0.15) (type solid)) (layer "F.Fab"))
    (fp_line (start 0.504 -0.25) (end 0.504 0.248)
      (stroke (width 0.15) (type solid)) (layer "F.Fab"))
    (fp_line (start 0.504 0.248) (end -0.494 0.248)
      (stroke (width 0.15) (type solid)) (layer "F.Fab"))
    (pad "1" smd roundrect (at -0.48 0) (size 0.59 0.64) (layers "F.Cu" "F.Paste" "F.Mask") (roundrect_rratio 0.25)
      (net 77 "GNDD") (pintype "passive"))
    (pad "2" smd roundrect (at 0.48 0) (size 0.59 0.64) (layers "F.Cu" "F.Paste" "F.Mask") (roundrect_rratio 0.25)
      (net 76 "VCC3V3_USB") (pintype "passive"))
  )

  (footprint "antmicro-footprints:C_0402_1005Metric" (layer "F.Cu")
    (at 181.2 117.45)
    (descr "Capacitor SMD 0402")
    (tags "capacitor SMD 0402")
    (property "Author" "Antmicro")
    (property "Dielectric" "")
    (property "License" "Apache-2.0")
    (property "MPN" "GRM155R61A475MEAAD")
    (property "Manufacturer" "Murata")
    (property "Sheetfile" "ftdi-module.kicad_sch")
    (property "Sheetname" "FTDI")
    (property "Val" "4u7")
    (property "Voltage" "")
    (property "ki_description" "SMD Multilayer Ceramic Capacitor, 4.7 µF, 10 V, 0402 [1005 Metric], ± 20%, X5R, GRM Series")
    (property "ki_keywords" "0402, SMT, CAPACITOR, PASSIVE")
    (attr smd)
    (fp_text reference "C19" (at -3.1 0.3) (layer "F.SilkS")
        (effects (font (size 0.7 0.7) (thickness 0.15)) (justify left bottom))
    )
    (fp_text value "C_4u7_0402" (at -1.022927 2.155213) (layer "F.Fab")
        (effects (font (size 0.7 0.7) (thickness 0.15)) (justify left bottom))
    )
    (fp_text user "${REFERENCE}" (at -0.939 4.599) (layer "F.Fab") hide
        (effects (font (size 0.7 0.7) (thickness 0.15)) (justify left bottom))
    )
    (fp_text user "Author: Antmicro" (at -0.939 3.399) (layer "F.Fab") hide
        (effects (font (size 0.7 0.7) (thickness 0.15)) (justify left bottom))
    )
    (fp_text user "License: Apache-2.0" (at -0.939 5.799) (layer "F.Fab") hide
        (effects (font (size 0.7 0.7) (thickness 0.15)) (justify left bottom))
    )
    (fp_rect (start -0.925 -0.47) (end 0.925 0.47)
      (stroke (width 0.05) (type default)) (fill none) (layer "F.CrtYd"))
    (fp_line (start -0.494 -0.25) (end 0.504 -0.25)
      (stroke (width 0.15) (type solid)) (layer "F.Fab"))
    (fp_line (start -0.494 0.248) (end -0.494 -0.25)
      (stroke (width 0.15) (type solid)) (layer "F.Fab"))
    (fp_line (start 0.504 -0.25) (end 0.504 0.248)
      (stroke (width 0.15) (type solid)) (layer "F.Fab"))
    (fp_line (start 0.504 0.248) (end -0.494 0.248)
      (stroke (width 0.15) (type solid)) (layer "F.Fab"))
    (pad "1" smd roundrect (at -0.48 0) (size 0.59 0.64) (layers "F.Cu" "F.Paste" "F.Mask") (roundrect_rratio 0.25)
      (net 77 "GNDD") (pintype "passive"))
    (pad "2" smd roundrect (at 0.48 0) (size 0.59 0.64) (layers "F.Cu" "F.Paste" "F.Mask") (roundrect_rratio 0.25)
      (net 3 "VCC5V0_USB") (pintype "passive"))
  )

  (footprint "antmicro-footprints:C_0402_1005Metric" (layer "F.Cu")
    (at 186.6 124.875 180)
    (descr "Capacitor SMD 0402")
    (tags "capacitor SMD 0402")
    (property "Author" "Antmicro")
    (property "Dielectric" "")
    (property "License" "Apache-2.0")
    (property "MPN" "GRM155R61A475MEAAD")
    (property "Manufacturer" "Murata")
    (property "Sheetfile" "ftdi-module.kicad_sch")
    (property "Sheetname" "FTDI")
    (property "Val" "4u7")
    (property "Voltage" "")
    (property "ki_description" "SMD Multilayer Ceramic Capacitor, 4.7 µF, 10 V, 0402 [1005 Metric], ± 20%, X5R, GRM Series")
    (property "ki_keywords" "0402, SMT, CAPACITOR, PASSIVE")
    (attr smd)
    (fp_text reference "C20" (at 0.95 -0.625) (layer "F.SilkS")
        (effects (font (size 0.7 0.7) (thickness 0.15)) (justify right bottom))
    )
    (fp_text value "C_4u7_0402" (at -1.022927 2.155213) (layer "F.Fab")
        (effects (font (size 0.7 0.7) (thickness 0.15)) (justify right bottom))
    )
    (fp_text user "License: Apache-2.0" (at -0.939 5.799) (layer "F.Fab") hide
        (effects (font (size 0.7 0.7) (thickness 0.15)) (justify right bottom))
    )
    (fp_text user "${REFERENCE}" (at -0.939 4.599) (layer "F.Fab") hide
        (effects (font (size 0.7 0.7) (thickness 0.15)) (justify right bottom))
    )
    (fp_text user "Author: Antmicro" (at -0.939 3.399) (layer "F.Fab") hide
        (effects (font (size 0.7 0.7) (thickness 0.15)) (justify right bottom))
    )
    (fp_rect (start -0.925 -0.47) (end 0.925 0.47)
      (stroke (width 0.05) (type default)) (fill none) (layer "F.CrtYd"))
    (fp_line (start -0.494 -0.25) (end 0.504 -0.25)
      (stroke (width 0.15) (type solid)) (layer "F.Fab"))
    (fp_line (start -0.494 0.248) (end -0.494 -0.25)
      (stroke (width 0.15) (type solid)) (layer "F.Fab"))
    (fp_line (start 0.504 -0.25) (end 0.504 0.248)
      (stroke (width 0.15) (type solid)) (layer "F.Fab"))
    (fp_line (start 0.504 0.248) (end -0.494 0.248)
      (stroke (width 0.15) (type solid)) (layer "F.Fab"))
    (pad "1" smd roundrect (at -0.48 0 180) (size 0.59 0.64) (layers "F.Cu" "F.Paste" "F.Mask") (roundrect_rratio 0.25)
      (net 77 "GNDD") (pintype "passive"))
    (pad "2" smd roundrect (at 0.48 0 180) (size 0.59 0.64) (layers "F.Cu" "F.Paste" "F.Mask") (roundrect_rratio 0.25)
      (net 76 "VCC3V3_USB") (pintype "passive"))
  )

  (footprint "antmicro-footprints:C_0603_1608Metric" (layer "F.Cu")
    (at 109.747132 99.826324 -90)
    (descr "Capacitor SMD 0603")
    (tags "capacitor 0603")
    (property "Author" "Antmicro")
    (property "Dielectric" "")
    (property "License" "Apache-2.0")
    (property "MPN" "C1608X5R1E106M080AC")
    (property "Manufacturer" "TDK")
    (property "Sheetfile" "daughterboard-supply.kicad_sch")
    (property "Sheetname" "daughterboard-supply")
    (property "Val" "10u")
    (property "Voltage" "25V")
    (property "ki_description" "SMD Multilayer Ceramic Capacitor, 10 µF, 25 V, 0603 [1608 Metric], ± 20%, X5R, C")
    (property "ki_keywords" "0603, SMT, CAPACITOR, PASSIVE, CERAMIC, MLCC")
    (attr smd)
    (fp_text reference "C33" (at -2.326324 -1.702868 90) (layer "F.SilkS")
        (effects (font (size 0.7 0.7) (thickness 0.15)) (justify right bottom))
    )
    (fp_text value "C_10u_25V_0603" (at -1.42757 1.770288 90) (layer "F.Fab")
        (effects (font (size 0.7 0.7) (thickness 0.15)) (justify right bottom))
    )
    (fp_text user "${REFERENCE}" (at -1.682 3.895 90) (layer "F.Fab") hide
        (effects (font (size 0.7 0.7) (thickness 0.15)) (justify right bottom))
    )
    (fp_text user "Author: Antmicro" (at -1.682 4.894 90) (layer "F.Fab") hide
        (effects (font (size 0.7 0.7) (thickness 0.15)) (justify right bottom))
    )
    (fp_text user "License: Apache-2.0" (at -1.682 5.895 90) (layer "F.Fab") hide
        (effects (font (size 0.7 0.7) (thickness 0.15)) (justify right bottom))
    )
    (fp_line (start -0.15 -0.4) (end 0.15 -0.4)
      (stroke (width 0.15) (type solid)) (layer "F.SilkS"))
    (fp_line (start -0.15 0.4) (end 0.15 0.4)
      (stroke (width 0.15) (type solid)) (layer "F.SilkS"))
    (fp_rect (start -1.25 -0.65) (end 1.25 0.65)
      (stroke (width 0.05) (type solid)) (fill none) (layer "F.CrtYd"))
    (fp_rect (start -0.8 -0.4) (end 0.8 0.4)
      (stroke (width 0.15) (type solid)) (fill none) (layer "F.Fab"))
    (pad "1" smd roundrect (at -0.7 0 270) (size 0.8 1) (layers "F.Cu" "F.Paste" "F.Mask") (roundrect_rratio 0.2)
      (net 4 "GND") (pintype "passive"))
    (pad "2" smd roundrect (at 0.7 0 270) (size 0.8 1) (layers "F.Cu" "F.Paste" "F.Mask") (roundrect_rratio 0.2)
      (net 11 "VCC12V0") (pintype "passive"))
  )

  (footprint "antmicro-footprints:C_0402_1005Metric" (layer "F.Cu")
    (at 104.647132 97.526324 -90)
    (descr "Capacitor SMD 0402")
    (tags "capacitor SMD 0402")
    (property "Author" "Antmicro")
    (property "Dielectric" "X5R")
    (property "License" "Apache-2.0")
    (property "MPN" "GRM155R61H104KE14D")
    (property "Manufacturer" "Murata")
    (property "Sheetfile" "daughterboard-supply.kicad_sch")
    (property "Sheetname" "daughterboard-supply")
    (property "Val" "100n")
    (property "Voltage" "50V")
    (property "ki_description" "SMD Multilayer Ceramic Capacitor, 0.1 µF, 50 V, 0402 [1005 Metric], ± 10%, X5R, GRM Series")
    (property "ki_keywords" "0402, SMT, CAPACITOR, PASSIVE, CERAMIC, MLCC")
    (attr smd)
    (fp_text reference "C34" (at -3.076324 -0.502868 90) (layer "F.SilkS")
        (effects (font (size 0.7 0.7) (thickness 0.15)) (justify right bottom))
    )
    (fp_text value "C_100n_0402" (at -1.022927 2.155213 90) (layer "F.Fab")
        (effects (font (size 0.7 0.7) (thickness 0.15)) (justify right bottom))
    )
    (fp_text user "${REFERENCE}" (at -0.939 4.599 90) (layer "F.Fab") hide
        (effects (font (size 0.7 0.7) (thickness 0.15)) (justify right bottom))
    )
    (fp_text user "License: Apache-2.0" (at -0.939 5.799 90) (layer "F.Fab") hide
        (effects (font (size 0.7 0.7) (thickness 0.15)) (justify right bottom))
    )
    (fp_text user "Author: Antmicro" (at -0.939 3.399 90) (layer "F.Fab") hide
        (effects (font (size 0.7 0.7) (thickness 0.15)) (justify right bottom))
    )
    (fp_rect (start -0.925 -0.47) (end 0.925 0.47)
      (stroke (width 0.05) (type default)) (fill none) (layer "F.CrtYd"))
    (fp_line (start -0.494 -0.25) (end 0.504 -0.25)
      (stroke (width 0.15) (type solid)) (layer "F.Fab"))
    (fp_line (start -0.494 0.248) (end -0.494 -0.25)
      (stroke (width 0.15) (type solid)) (layer "F.Fab"))
    (fp_line (start 0.504 -0.25) (end 0.504 0.248)
      (stroke (width 0.15) (type solid)) (layer "F.Fab"))
    (fp_line (start 0.504 0.248) (end -0.494 0.248)
      (stroke (width 0.15) (type solid)) (layer "F.Fab"))
    (pad "1" smd roundrect (at -0.48 0 270) (size 0.59 0.64) (layers "F.Cu" "F.Paste" "F.Mask") (roundrect_rratio 0.25)
      (net 16 "Net-(U4-BST)") (pintype "passive"))
    (pad "2" smd roundrect (at 0.48 0 270) (size 0.59 0.64) (layers "F.Cu" "F.Paste" "F.Mask") (roundrect_rratio 0.25)
      (net 32 "Net-(U4-SW)") (pintype "passive"))
  )

  (footprint "antmicro-footprints:C_0603_1608Metric" (layer "F.Cu")
    (at 104.547132 99.826324 -90)
    (descr "Capacitor SMD 0603")
    (tags "capacitor 0603")
    (property "Author" "Antmicro")
    (property "Dielectric" "")
    (property "License" "Apache-2.0")
    (property "MPN" "GRM188R60J226MEA0D")
    (property "Manufacturer" "Murata")
    (property "Sheetfile" "daughterboard-supply.kicad_sch")
    (property "Sheetname" "daughterboard-supply")
    (property "Val" "22u")
    (property "Voltage" "")
    (property "ki_description" "SMD Multilayer Ceramic Capacitor, 22 µF, 6.3 V, 0603 [1608 Metric], ± 20%, X5R, GRM Series")
    (property "ki_keywords" "0603, SMT, CAPACITOR, PASSIVE, CERAMIC, MLCC")
    (attr smd)
    (fp_text reference "C35" (at -4.376324 0.447132 -90) (layer "F.SilkS")
        (effects (font (size 0.7 0.7) (thickness 0.15)) (justify right bottom))
    )
    (fp_text value "C_22u_0603" (at -1.42757 1.770288 90) (layer "F.Fab")
        (effects (font (size 0.7 0.7) (thickness 0.15)) (justify right bottom))
    )
    (fp_text user "License: Apache-2.0" (at -1.682 5.895 90) (layer "F.Fab") hide
        (effects (font (size 0.7 0.7) (thickness 0.15)) (justify right bottom))
    )
    (fp_text user "Author: Antmicro" (at -1.682 4.894 90) (layer "F.Fab") hide
        (effects (font (size 0.7 0.7) (thickness 0.15)) (justify right bottom))
    )
    (fp_text user "${REFERENCE}" (at -1.682 3.895 90) (layer "F.Fab") hide
        (effects (font (size 0.7 0.7) (thickness 0.15)) (justify right bottom))
    )
    (fp_line (start -0.15 -0.4) (end 0.15 -0.4)
      (stroke (width 0.15) (type solid)) (layer "F.SilkS"))
    (fp_line (start -0.15 0.4) (end 0.15 0.4)
      (stroke (width 0.15) (type solid)) (layer "F.SilkS"))
    (fp_rect (start -1.25 -0.65) (end 1.25 0.65)
      (stroke (width 0.05) (type solid)) (fill none) (layer "F.CrtYd"))
    (fp_rect (start -0.8 -0.4) (end 0.8 0.4)
      (stroke (width 0.15) (type solid)) (fill none) (layer "F.Fab"))
    (pad "1" smd roundrect (at -0.7 0 270) (size 0.8 1) (layers "F.Cu" "F.Paste" "F.Mask") (roundrect_rratio 0.2)
      (net 4 "GND") (pintype "passive"))
    (pad "2" smd roundrect (at 0.7 0 270) (size 0.8 1) (layers "F.Cu" "F.Paste" "F.Mask") (roundrect_rratio 0.2)
      (net 1 "VCC3V3") (pintype "passive"))
  )

  (footprint "antmicro-footprints:C_0603_1608Metric" (layer "F.Cu")
    (at 103.047132 99.826324 -90)
    (descr "Capacitor SMD 0603")
    (tags "capacitor 0603")
    (property "Author" "Antmicro")
    (property "Dielectric" "")
    (property "License" "Apache-2.0")
    (property "MPN" "GRM188R60J226MEA0D")
    (property "Manufacturer" "Murata")
    (property "Sheetfile" "daughterboard-supply.kicad_sch")
    (property "Sheetname" "daughterboard-supply")
    (property "Val" "22u")
    (property "Voltage" "")
    (property "ki_description" "SMD Multilayer Ceramic Capacitor, 22 µF, 6.3 V, 0603 [1608 Metric], ± 20%, X5R, GRM Series")
    (property "ki_keywords" "0603, SMT, CAPACITOR, PASSIVE, CERAMIC, MLCC")
    (attr smd)
    (fp_text reference "C36" (at -0.276324 0.747132 90) (layer "F.SilkS")
        (effects (font (size 0.7 0.7) (thickness 0.15)) (justify right bottom))
    )
    (fp_text value "C_22u_0603" (at -1.42757 1.770288 90) (layer "F.Fab")
        (effects (font (size 0.7 0.7) (thickness 0.15)) (justify right bottom))
    )
    (fp_text user "License: Apache-2.0" (at -1.682 5.895 90) (layer "F.Fab") hide
        (effects (font (size 0.7 0.7) (thickness 0.15)) (justify right bottom))
    )
    (fp_text user "Author: Antmicro" (at -1.682 4.894 90) (layer "F.Fab") hide
        (effects (font (size 0.7 0.7) (thickness 0.15)) (justify right bottom))
    )
    (fp_text user "${REFERENCE}" (at -1.682 3.895 90) (layer "F.Fab") hide
        (effects (font (size 0.7 0.7) (thickness 0.15)) (justify right bottom))
    )
    (fp_line (start -0.15 -0.4) (end 0.15 -0.4)
      (stroke (width 0.15) (type solid)) (layer "F.SilkS"))
    (fp_line (start -0.15 0.4) (end 0.15 0.4)
      (stroke (width 0.15) (type solid)) (layer "F.SilkS"))
    (fp_rect (start -1.25 -0.65) (end 1.25 0.65)
      (stroke (width 0.05) (type solid)) (fill none) (layer "F.CrtYd"))
    (fp_rect (start -0.8 -0.4) (end 0.8 0.4)
      (stroke (width 0.15) (type solid)) (fill none) (layer "F.Fab"))
    (pad "1" smd roundrect (at -0.7 0 270) (size 0.8 1) (layers "F.Cu" "F.Paste" "F.Mask") (roundrect_rratio 0.2)
      (net 4 "GND") (pintype "passive"))
    (pad "2" smd roundrect (at 0.7 0 270) (size 0.8 1) (layers "F.Cu" "F.Paste" "F.Mask") (roundrect_rratio 0.2)
      (net 1 "VCC3V3") (pintype "passive"))
  )

  (footprint "antmicro-footprints:L_WE-LHMI-5030" (layer "F.Cu")
    (at 106.047132 104.126324 180)
    (property "Author" "Antmicro")
    (property "IMax" "4.1A")
    (property "ISat" "5.45A")
    (property "License" "Apache-2.0")
    (property "MPN" "74437336033")
    (property "Manufacturer" "Würth Elektronik")
    (property "Sheetfile" "daughterboard-supply.kicad_sch")
    (property "Sheetname" "daughterboard-supply")
    (property "Size" "5.2x5.2")
    (property "Val" "3u3/4.1A")
    (property "ki_description" "Power Inductor (SMT), 3.3 µH, 4.1 A, Shielded, 8.4 A, WE-LHMI")
    (property "ki_keywords" "SMT, INDUCTOR, PASSIVE")
    (attr smd)
    (fp_text reference "L1" (at 3.247132 1.226324 90) (layer "F.SilkS")
        (effects (font (size 0.7 0.7) (thickness 0.15)) (justify left bottom))
    )
    (fp_text value "L_3u3_4.1A_WE-LHMI-5030" (at 0 3.9) (layer "F.Fab")
        (effects (font (size 0.7 0.7) (thickness 0.15)) (justify left bottom))
    )
    (fp_text user "${REFERENCE}" (at -3.5 7.1 180) (layer "F.Fab") hide
        (effects (font (size 0.7 0.7) (thickness 0.15)) (justify left bottom))
    )
    (fp_text user "License: Apache-2.0" (at -3.5 8.3 180) (layer "F.Fab") hide
        (effects (font (size 0.7 0.7) (thickness 0.15)) (justify left bottom))
    )
    (fp_text user "Author: Antmicro" (at -3.5 5.9 180) (layer "F.Fab") hide
        (effects (font (size 0.7 0.7) (thickness 0.15)) (justify left bottom))
    )
    (fp_line (start -2.725 -1.6125) (end -2.725 -1.125)
      (stroke (width 0.15) (type solid)) (layer "F.SilkS"))
    (fp_line (start -2.725 1.6125) (end -2.725 1.125)
      (stroke (width 0.15) (type solid)) (layer "F.SilkS"))
    (fp_line (start -1.6 -2.725) (end 1.6 -2.725)
      (stroke (width 0.15) (type solid)) (layer "F.SilkS"))
    (fp_line (start 1.6 2.725) (end -1.6 2.725)
      (stroke (width 0.15) (type solid)) (layer "F.SilkS"))
    (fp_line (start 2.725 -1.6125) (end 2.725 -1.125)
      (stroke (width 0.15) (type solid)) (layer "F.SilkS"))
    (fp_line (start 2.725 1.6125) (end 2.725 1.125)
      (stroke (width 0.15) (type solid)) (layer "F.SilkS"))
    (fp_arc (start -2.725 -1.6125) (mid -2.392906 -2.401745) (end -1.6 -2.725)
      (stroke (width 0.15) (type solid)) (layer "F.SilkS"))
    (fp_arc (start -1.6 2.725) (mid -2.392906 2.401745) (end -2.725 1.6125)
      (stroke (width 0.15) (type solid)) (layer "F.SilkS"))
    (fp_arc (start 1.6 -2.725) (mid 2.392906 -2.401745) (end 2.725 -1.6125)
      (stroke (width 0.15) (type solid)) (layer "F.SilkS"))
    (fp_arc (start 2.725 1.6125) (mid 2.392906 2.401745) (end 1.6 2.725)
      (stroke (width 0.15) (type solid)) (layer "F.SilkS"))
    (fp_line (start -3.5 1.15) (end -3.5 -1.15)
      (stroke (width 0.05) (type solid)) (layer "F.CrtYd"))
    (fp_line (start -3.1 -2.85) (end 3.1 -2.85)
      (stroke (width 0.05) (type solid)) (layer "F.CrtYd"))
    (fp_line (start -3.1 -1.15) (end -3.5 -1.15)
      (stroke (width 0.05) (type solid)) (layer "F.CrtYd"))
    (fp_line (start -3.1 -1.15) (end -3.1 -2.85)
      (stroke (width 0.05) (type solid)) (layer "F.CrtYd"))
    (fp_line (start -3.1 1.15) (end -3.5 1.15)
      (stroke (width 0.05) (type solid)) (layer "F.CrtYd"))
    (fp_line (start -3.1 2.85) (end -3.1 1.15)
      (stroke (width 0.05) (type solid)) (layer "F.CrtYd"))
    (fp_line (start 3.1 -2.85) (end 3.1 -1.15)
      (stroke (width 0.05) (type solid)) (layer "F.CrtYd"))
    (fp_line (start 3.1 -1.15) (end 3.5 -1.15)
      (stroke (width 0.05) (type solid)) (layer "F.CrtYd"))
    (fp_line (start 3.1 1.15) (end 3.1 2.85)
      (stroke (width 0.05) (type solid)) (layer "F.CrtYd"))
    (fp_line (start 3.1 1.15) (end 3.5 1.15)
      (stroke (width 0.05) (type solid)) (layer "F.CrtYd"))
    (fp_line (start 3.1 2.85) (end -3.1 2.85)
      (stroke (width 0.05) (type solid)) (layer "F.CrtYd"))
    (fp_line (start 3.5 -1.15) (end 3.5 1.15)
      (stroke (width 0.05) (type solid)) (layer "F.CrtYd"))
    (fp_rect (start -2.85 -2.6) (end 2.85 2.6)
      (stroke (width 0.15) (type solid)) (fill none) (layer "F.Fab"))
    (pad "1" smd roundrect (at -2.25 0) (size 2 1.8) (layers "F.Cu" "F.Paste" "F.Mask") (roundrect_rratio 0.1)
      (net 32 "Net-(U4-SW)") (pintype "passive"))
    (pad "2" smd roundrect (at 2.25 0 180) (size 2 1.8) (layers "F.Cu" "F.Paste" "F.Mask") (roundrect_rratio 0.1)
      (net 1 "VCC3V3") (pintype "passive"))
  )

  (footprint "antmicro-footprints:R_0603_1608Metric" (layer "F.Cu")
    (at 173.175 106.25 90)
    (descr "Resistor SMD 0603")
    (tags "resistor SMD 0603")
    (property "Author" "Antmicro")
    (property "Current" "1A")
    (property "DNP" "DNP")
    (property "License" "Apache-2.0")
    (property "MPN" "CR0603-J/-000ELF")
    (property "Manufacturer" "Bourns")
    (property "Sheetfile" "ftdi-module.kicad_sch")
    (property "Sheetname" "FTDI")
    (property "Tolerance" "")
    (property "Val" "0R")
    (property "dnp" "")
    (property "exclude_from_bom" "")
    (property "ki_description" "Zero Ohm Resistor, Jumper, 0603 [1608 Metric], Thick Film, 100 mW, 1 A, Surface Mount Device, CR")
    (property "ki_keywords" "0603, SMT, RESISTOR, PASSIVE")
    (attr smd exclude_from_bom)
    (fp_text reference "R38" (at 0.025 -2.875 90) (layer "F.SilkS")
        (effects (font (size 0.7 0.7) (thickness 0.15)))
    )
    (fp_text value "R_0R_0603" (at 0 1.9 90) (layer "F.Fab") hide
        (effects (font (size 1 1) (thickness 0.15)))
    )
    (fp_text user "Author: Antmicro" (at -1.25 4.9 90) (layer "F.Fab") hide
        (effects (font (size 0.7 0.7) (thickness 0.15)) (justify left bottom))
    )
    (fp_text user "License: Apache-2.0" (at -1.25 5.9 90) (layer "F.Fab") hide
        (effects (font (size 0.7 0.7) (thickness 0.15)) (justify left bottom))
    )
    (fp_text user "${REFERENCE}" (at -1.25 3.898 90) (layer "F.Fab") hide
        (effects (font (size 0.7 0.7) (thickness 0.15)) (justify left bottom))
    )
    (fp_line (start -0.15 -0.4) (end 0.15 -0.4)
      (stroke (width 0.15) (type solid)) (layer "F.SilkS"))
    (fp_line (start -0.15 0.4) (end 0.15 0.4)
      (stroke (width 0.15) (type solid)) (layer "F.SilkS"))
    (fp_rect (start -1.25 -0.65) (end 1.25 0.65)
      (stroke (width 0.05) (type solid)) (fill none) (layer "F.CrtYd"))
    (fp_rect (start -0.8 -0.4) (end 0.8 0.4)
      (stroke (width 0.15) (type solid)) (fill none) (layer "F.Fab"))
    (pad "1" smd roundrect (at -0.7 0 90) (size 0.8 1) (layers "F.Cu" "F.Paste" "F.Mask") (roundrect_rratio 0.2)
      (net 80 "SDA_FTDI") (pintype "passive"))
    (pad "2" smd roundrect (at 0.7 0 90) (size 0.8 1) (layers "F.Cu" "F.Paste" "F.Mask") (roundrect_rratio 0.2)
      (net 18 "SDA") (pintype "passive"))
  )

  (footprint "antmicro-footprints:R_0603_1608Metric" (layer "F.Cu")
    (at 171.675 106.25 90)
    (descr "Resistor SMD 0603")
    (tags "resistor SMD 0603")
    (property "Author" "Antmicro")
    (property "Current" "1A")
    (property "DNP" "DNP")
    (property "License" "Apache-2.0")
    (property "MPN" "CR0603-J/-000ELF")
    (property "Manufacturer" "Bourns")
    (property "Sheetfile" "ftdi-module.kicad_sch")
    (property "Sheetname" "FTDI")
    (property "Tolerance" "")
    (property "Val" "0R")
    (property "dnp" "")
    (property "exclude_from_bom" "")
    (property "ki_description" "Zero Ohm Resistor, Jumper, 0603 [1608 Metric], Thick Film, 100 mW, 1 A, Surface Mount Device, CR")
    (property "ki_keywords" "0603, SMT, RESISTOR, PASSIVE")
    (attr smd exclude_from_bom)
    (fp_text reference "R42" (at 0 -2.675 90) (layer "F.SilkS")
        (effects (font (size 0.7 0.7) (thickness 0.15)))
    )
    (fp_text value "R_0R_0603" (at 0 1.9 90) (layer "F.Fab") hide
        (effects (font (size 1 1) (thickness 0.15)))
    )
    (fp_text user "${REFERENCE}" (at -1.25 3.898 90) (layer "F.Fab") hide
        (effects (font (size 0.7 0.7) (thickness 0.15)) (justify left bottom))
    )
    (fp_text user "Author: Antmicro" (at -1.25 4.9 90) (layer "F.Fab") hide
        (effects (font (size 0.7 0.7) (thickness 0.15)) (justify left bottom))
    )
    (fp_text user "License: Apache-2.0" (at -1.25 5.9 90) (layer "F.Fab") hide
        (effects (font (size 0.7 0.7) (thickness 0.15)) (justify left bottom))
    )
    (fp_line (start -0.15 -0.4) (end 0.15 -0.4)
      (stroke (width 0.15) (type solid)) (layer "F.SilkS"))
    (fp_line (start -0.15 0.4) (end 0.15 0.4)
      (stroke (width 0.15) (type solid)) (layer "F.SilkS"))
    (fp_rect (start -1.25 -0.65) (end 1.25 0.65)
      (stroke (width 0.05) (type solid)) (fill none) (layer "F.CrtYd"))
    (fp_rect (start -0.8 -0.4) (end 0.8 0.4)
      (stroke (width 0.15) (type solid)) (fill none) (layer "F.Fab"))
    (pad "1" smd roundrect (at -0.7 0 90) (size 0.8 1) (layers "F.Cu" "F.Paste" "F.Mask") (roundrect_rratio 0.2)
      (net 77 "GNDD") (pintype "passive"))
    (pad "2" smd roundrect (at 0.7 0 90) (size 0.8 1) (layers "F.Cu" "F.Paste" "F.Mask") (roundrect_rratio 0.2)
      (net 4 "GND") (pintype "passive"))
  )

  (footprint "antmicro-footprints:R_0402_1005Metric" (layer "F.Cu")
    (at 107.147132 96.011324 90)
    (descr "Resistor SMD 0402")
    (tags "resistor SMD 0402")
    (property "Author" "Antmicro")
    (property "License" "Apache-2.0")
    (property "MPN" "CR0402-FX-2151GLF")
    (property "Manufacturer" "Bourns")
    (property "Sheetfile" "daughterboard-supply.kicad_sch")
    (property "Sheetname" "daughterboard-supply")
    (property "Tolerance" "1%")
    (property "Val" "2k15")
    (property "ki_description" "SMD Chip Resistor, 2.15 kohm, ± 1%, 63 mW, 0402 [1005 Metric], Thick Film, General Purpose")
    (property "ki_keywords" "0402, SMT, RESISTOR, PASSIVE")
    (zone_connect 1)
    (attr smd)
    (fp_text reference "R43" (at 0.911324 0.452868 90) (layer "F.SilkS")
        (effects (font (size 0.7 0.7) (thickness 0.15)) (justify left bottom))
    )
    (fp_text value "R_2k15_0402" (at -1.011843 1.772047 90) (layer "F.Fab")
        (effects (font (size 0.7 0.7) (thickness 0.15)) (justify left bottom))
    )
    (fp_text user "${REFERENCE}" (at -0.95 3.168 90) (layer "F.Fab") hide
        (effects (font (size 0.7 0.7) (thickness 0.15)) (justify left bottom))
    )
    (fp_text user "License: Apache-2.0" (at -0.95 5.169 90) (layer "F.Fab") hide
        (effects (font (size 0.7 0.7) (thickness 0.15)) (justify left bottom))
    )
    (fp_text user "Author: Antmicro" (at -0.95 4.169 90) (layer "F.Fab") hide
        (effects (font (size 0.7 0.7) (thickness 0.15)) (justify left bottom))
    )
    (fp_rect (start -0.925 -0.47) (end 0.925 0.47)
      (stroke (width 0.05) (type default)) (fill none) (layer "F.CrtYd"))
    (fp_rect (start -0.5 -0.25) (end 0.5 0.25)
      (stroke (width 0.15) (type solid)) (fill none) (layer "F.Fab"))
    (pad "1" smd roundrect (at -0.48 0 90) (size 0.59 0.64) (layers "F.Cu" "F.Paste" "F.Mask") (roundrect_rratio 0.25)
      (net 112 "Net-(U4-FB)") (pintype "passive"))
    (pad "2" smd roundrect (at 0.48 0 90) (size 0.59 0.64) (layers "F.Cu" "F.Paste" "F.Mask") (roundrect_rratio 0.25)
      (net 1 "VCC3V3") (pintype "passive"))
  )

  (footprint "antmicro-footprints:R_0402_1005Metric" (layer "F.Cu")
    (at 108.147132 96.011324 90)
    (descr "Resistor SMD 0402")
    (tags "resistor SMD 0402")
    (property "Author" "Antmicro")
    (property "License" "Apache-2.0")
    (property "MPN" "CR0402-FX-6800GLF")
    (property "Manufacturer" "Bourns")
    (property "Sheetfile" "daughterboard-supply.kicad_sch")
    (property "Sheetname" "daughterboard-supply")
    (property "Tolerance" "1%")
    (property "Val" "680R")
    (property "ki_description" "SMD Chip Resistor, 680 ohm, ± 1%, 63 mW, 0402 [1005 Metric], Thick Film, General Purpose")
    (property "ki_keywords" "0402, SMT, RESISTOR, PASSIVE")
    (zone_connect 1)
    (attr smd)
    (fp_text reference "R44" (at 0.911324 0.452868 90) (layer "F.SilkS")
        (effects (font (size 0.7 0.7) (thickness 0.15)) (justify left bottom))
    )
    (fp_text value "R_680R_0402" (at -1.011843 1.772047 90) (layer "F.Fab")
        (effects (font (size 0.7 0.7) (thickness 0.15)) (justify left bottom))
    )
    (fp_text user "Author: Antmicro" (at -0.95 4.169 90) (layer "F.Fab") hide
        (effects (font (size 0.7 0.7) (thickness 0.15)) (justify left bottom))
    )
    (fp_text user "${REFERENCE}" (at -0.95 3.168 90) (layer "F.Fab") hide
        (effects (font (size 0.7 0.7) (thickness 0.15)) (justify left bottom))
    )
    (fp_text user "License: Apache-2.0" (at -0.95 5.169 90) (layer "F.Fab") hide
        (effects (font (size 0.7 0.7) (thickness 0.15)) (justify left bottom))
    )
    (fp_rect (start -0.925 -0.47) (end 0.925 0.47)
      (stroke (width 0.05) (type default)) (fill none) (layer "F.CrtYd"))
    (fp_rect (start -0.5 -0.25) (end 0.5 0.25)
      (stroke (width 0.15) (type solid)) (fill none) (layer "F.Fab"))
    (pad "1" smd roundrect (at -0.48 0 90) (size 0.59 0.64) (layers "F.Cu" "F.Paste" "F.Mask") (roundrect_rratio 0.25)
      (net 112 "Net-(U4-FB)") (pintype "passive"))
    (pad "2" smd roundrect (at 0.48 0 90) (size 0.59 0.64) (layers "F.Cu" "F.Paste" "F.Mask") (roundrect_rratio 0.25)
      (net 4 "GND") (pintype "passive"))
  )

  (footprint "antmicro-footprints:SOIC-8_3.9x4.9x1.75mm_P1.27mm" (layer "F.Cu")
    (at 176.7 106.3 90)
    (property "Author" "Antmicro")
    (property "License" "Apache-2.0")
    (property "MPN" "ISO1641BDR")
    (property "Manufacturer" "Texas Instruments")
    (property "Sheetfile" "ftdi-module.kicad_sch")
    (property "Sheetname" "FTDI")
    (property "ki_description" "Bidirectional Optoisolator")
    (property "ki_keywords" "SMT, OPTOCOUPLER, IC, INTERFACE, I2C, ISOLATOR")
    (attr smd)
    (fp_text reference "U2" (at 3.8 -1.2 180) (layer "F.SilkS")
        (effects (font (size 0.7 0.7) (thickness 0.15)) (justify left bottom))
    )
    (fp_text value "ISO1641" (at 0 3.65 90) (layer "F.Fab")
        (effects (font (size 0.7 0.7) (thickness 0.15)) (justify left bottom))
    )
    (fp_text user "${REFERENCE}" (at -3.476 7.099 90) (layer "F.Fab") hide
        (effects (font (size 0.7 0.7) (thickness 0.15)) (justify left bottom))
    )
    (fp_text user "License: Apache-2.0" (at -3.476 5.099 90) (layer "F.Fab") hide
        (effects (font (size 0.7 0.7) (thickness 0.15)) (justify left bottom))
    )
    (fp_text user "Author: Antmicro" (at -3.476 6.099 90) (layer "F.Fab") hide
        (effects (font (size 0.7 0.7) (thickness 0.15)) (justify left bottom))
    )
    (fp_line (start -1.95 -2.452) (end 1.95 -2.45)
      (stroke (width 0.15) (type solid)) (layer "F.SilkS"))
    (fp_line (start -1.95 2.45) (end 1.95 2.45)
      (stroke (width 0.15) (type solid)) (layer "F.SilkS"))
    (fp_circle (center -2.4 -2.45) (end -2.35 -2.4)
      (stroke (width 0.15) (type solid)) (fill solid) (layer "F.SilkS"))
    (fp_rect (start -3.625 -2.7) (end 3.625 2.7)
      (stroke (width 0.05) (type solid)) (fill none) (layer "F.CrtYd"))
    (fp_line (start -1.95 -1.18) (end -0.683 -2.452)
      (stroke (width 0.15) (type solid)) (layer "F.Fab"))
    (fp_line (start -1.95 2.45) (end -1.95 -1.18)
      (stroke (width 0.15) (type solid)) (layer "F.Fab"))
    (fp_line (start -0.683 -2.452) (end 1.949 -2.452)
      (stroke (width 0.15) (type solid)) (layer "F.Fab"))
    (fp_line (start 1.949 -2.452) (end 1.949 2.45)
      (stroke (width 0.15) (type solid)) (layer "F.Fab"))
    (fp_line (start 1.949 2.45) (end -1.95 2.45)
      (stroke (width 0.15) (type solid)) (layer "F.Fab"))
    (pad "1" smd roundrect (at -2.714 -1.905 180) (size 0.65 1.525) (layers "F.Cu" "F.Paste" "F.Mask") (roundrect_rratio 0.25)
      (net 76 "VCC3V3_USB") (pinfunction "VCC1") (pintype "power_in"))
    (pad "2" smd roundrect (at -2.714 -0.635 180) (size 0.65 1.525) (layers "F.Cu" "F.Paste" "F.Mask") (roundrect_rratio 0.25)
      (net 80 "SDA_FTDI") (pinfunction "SDA1") (pintype "bidirectional"))
    (pad "3" smd roundrect (at -2.714 0.632 180) (size 0.65 1.525) (layers "F.Cu" "F.Paste" "F.Mask") (roundrect_rratio 0.25)
      (net 81 "SCL_FTDI") (pinfunction "SCL1") (pintype "bidirectional"))
    (pad "4" smd roundrect (at -2.714 1.902 180) (size 0.65 1.525) (layers "F.Cu" "F.Paste" "F.Mask") (roundrect_rratio 0.25)
      (net 77 "GNDD") (pinfunction "GND1") (pintype "power_in"))
    (pad "5" smd roundrect (at 2.712 1.902 180) (size 0.65 1.525) (layers "F.Cu" "F.Paste" "F.Mask") (roundrect_rratio 0.25)
      (net 4 "GND") (pinfunction "GND2") (pintype "power_in"))
    (pad "6" smd roundrect (at 2.712 0.632 180) (size 0.65 1.525) (layers "F.Cu" "F.Paste" "F.Mask") (roundrect_rratio 0.25)
      (net 17 "SCL") (pinfunction "SCL2") (pintype "bidirectional"))
    (pad "7" smd roundrect (at 2.712 -0.635 180) (size 0.65 1.525) (layers "F.Cu" "F.Paste" "F.Mask") (roundrect_rratio 0.25)
      (net 18 "SDA") (pinfunction "SDA2") (pintype "bidirectional"))
    (pad "8" smd roundrect (at 2.712 -1.905 180) (size 0.65 1.525) (layers "F.Cu" "F.Paste" "F.Mask") (roundrect_rratio 0.25)
      (net 1 "VCC3V3") (pinfunction "VCC2") (pintype "power_in"))
  )

  (footprint "antmicro-footprints:TSOT23-6" (layer "F.Cu")
    (at 107.147132 99.076324 90)
    (property "Author" "Antmicro")
    (property "License" "Apache-2.0")
    (property "MPN" "AP62301WU-7")
    (property "Manufacturer" "Diodes Incorporated")
    (property "Sheetfile" "daughterboard-supply.kicad_sch")
    (property "Sheetname" "daughterboard-supply")
    (property "ki_description" "DC-DC Switching Synchronous Buck Regulator, Adjustable, 4.2V-18Vin, 0.8V-7V/3A out, TSOT-26-6")
    (property "ki_keywords" "SMT, PMIC, IC, VOLTAGE")
    (attr smd)
    (fp_text reference "U4" (at 2.276324 2.652868 90) (layer "F.SilkS")
        (effects (font (size 0.7 0.7) (thickness 0.15)) (justify right bottom))
    )
    (fp_text value "AP62301_TSOT" (at 0 2.6 90) (layer "F.Fab")
        (effects (font (size 0.7 0.7) (thickness 0.15)) (justify left bottom))
    )
    (fp_text user "${REFERENCE}" (at -1.93 3.8 90) (layer "F.Fab") hide
        (effects (font (size 0.7 0.7) (thickness 0.15)) (justify left bottom))
    )
    (fp_text user "Author: Antmicro" (at -1.93 5 90) (layer "F.Fab") hide
        (effects (font (size 0.7 0.7) (thickness 0.15)) (justify left bottom))
    )
    (fp_text user "License: Apache-2.0" (at -1.93 6.199 90) (layer "F.Fab") hide
        (effects (font (size 0.7 0.7) (thickness 0.15)) (justify left bottom))
    )
    (fp_line (start -1 -1.5) (end -1 -1.375)
      (stroke (width 0.15) (type solid)) (layer "F.SilkS"))
    (fp_line (start -1 1.55) (end -1 1.4)
      (stroke (width 0.15) (type solid)) (layer "F.SilkS"))
    (fp_line (start 1 -1.497) (end -1 -1.5)
      (stroke (width 0.15) (type solid)) (layer "F.SilkS"))
    (fp_line (start 1 -1.497) (end 1 -1.375)
      (stroke (width 0.15) (type solid)) (layer "F.SilkS"))
    (fp_line (start 1 1.55) (end -1 1.55)
      (stroke (width 0.15) (type solid)) (layer "F.SilkS"))
    (fp_line (start 1 1.55) (end 1 1.4)
      (stroke (width 0.15) (type solid)) (layer "F.SilkS"))
    (fp_circle (center -1.44 -1.5) (end -1.39 -1.5)
      (stroke (width 0.15) (type solid)) (fill solid) (layer "F.SilkS"))
    (fp_rect (start 1.93 -1.7) (end -1.93 1.7)
      (stroke (width 0.05) (type solid)) (fill none) (layer "F.CrtYd"))
    (fp_line (start -0.45 -1.521) (end -0.876 -1.096)
      (stroke (width 0.15) (type solid)) (layer "F.Fab"))
    (fp_rect (start 0.875 1.528) (end -0.875 -1.525)
      (stroke (width 0.15) (type solid)) (fill none) (layer "F.Fab"))
    (pad "1" smd rect (at -1.301 -0.947) (size 0.7 1.2) (layers "F.Cu" "F.Paste" "F.Mask")
      (net 4 "GND") (pinfunction "GND") (pintype "power_in"))
    (pad "2" smd rect (at -1.301 0.004) (size 0.7 1.2) (layers "F.Cu" "F.Paste" "F.Mask")
      (net 32 "Net-(U4-SW)") (pinfunction "SW") (pintype "power_out"))
    (pad "3" smd rect (at -1.301 0.954) (size 0.7 1.2) (layers "F.Cu" "F.Paste" "F.Mask")
      (net 11 "VCC12V0") (pinfunction "VIN") (pintype "power_in"))
    (pad "4" smd rect (at 1.299 0.954) (size 0.7 1.2) (layers "F.Cu" "F.Paste" "F.Mask")
      (net 112 "Net-(U4-FB)") (pinfunction "FB") (pintype "input"))
    (pad "5" smd rect (at 1.299 0.004) (size 0.7 1.2) (layers "F.Cu" "F.Paste" "F.Mask")
      (net 120 "unconnected-(U4-EN-Pad5)") (pinfunction "EN") (pintype "input+no_connect"))
    (pad "6" smd rect (at 1.299 -0.947) (size 0.7 1.2) (layers "F.Cu" "F.Paste" "F.Mask")
      (net 16 "Net-(U4-BST)") (pinfunction "BST") (pintype "output"))
  )

  (footprint "antmicro-footprints:TP_SMD_1mm" (layer "F.Cu")
    (at 187.55 121.825 180)
    (property "Author" "Antmicro")
    (property "License" "Apache-2.0")
    (property "MPN" "")
    (property "Manufacturer" "")
    (property "Sheetfile" "ftdi-module.kicad_sch")
    (property "Sheetname" "FTDI")
    (property "exclude_from_bom" "")
    (property "ki_description" "Test point 1mm SMD")
    (property "ki_keywords" "TESTPOINT")
    (attr exclude_from_pos_files exclude_from_bom)
    (fp_text reference "5V_USB1" (at -1.55 -3.875 270) (layer "F.SilkS")
        (effects (font (size 0.7 0.7) (thickness 0.15)) (justify left bottom))
    )
    (fp_text value "TP_1mm_SMD" (at 0 1.4 180) (layer "F.Fab")
        (effects (font (size 0.7 0.7) (thickness 0.15)) (justify left bottom))
    )
    (fp_text user "License: Apache-2.0" (at -0.5 5.2 180) (layer "F.Fab") hide
        (effects (font (size 0.7 0.7) (thickness 0.15)) (justify left bottom))
    )
    (fp_text user "${REFERENCE}" (at -0.5 2.8 180) (layer "F.Fab") hide
        (effects (font (size 0.7 0.7) (thickness 0.15)) (justify left bottom))
    )
    (fp_text user "Author: Antmicro" (at -0.5 4 180) (layer "F.Fab") hide
        (effects (font (size 0.7 0.7) (thickness 0.15)) (justify left bottom))
    )
    (fp_circle (center 0 0) (end 0.6 0)
      (stroke (width 0.05) (type default)) (fill none) (layer "F.CrtYd"))
    (pad "1" smd circle (at 0 0 180) (size 1 1) (layers "F.Cu" "F.Mask")
      (net 3 "VCC5V0_USB") (pinfunction "1") (pintype "passive"))
  )

  (footprint "antmicro-footprints:SOT-23-5" (layer "F.Cu")
    (at 185.05 122.225 -90)
    (property "Author" "Antmicro")
    (property "License" "Apache-2.0")
    (property "MPN" "NCP163ASN330T1G")
    (property "Manufacturer" "ON Semiconductor")
    (property "Sheetfile" "ftdi-module.kicad_sch")
    (property "Sheetname" "FTDI")
    (property "ki_description" "Fixed LDO Voltage Regulator, 2.2V to 5.5V, 105mV drop, 3.3V/250mA out, SOT-23-5")
    (property "ki_keywords" "SMT, PMIC, IC, LDO, VOLTAGE, REGULATOR")
    (attr smd)
    (fp_text reference "U3" (at -0.875 1.85 90) (layer "F.SilkS")
        (effects (font (size 0.7 0.7) (thickness 0.15)) (justify right bottom))
    )
    (fp_text value "NCP163ASN330T1G" (at 0.002 2.799 90) (layer "F.Fab")
        (effects (font (size 0.7 0.7) (thickness 0.15)) (justify right bottom))
    )
    (fp_text user "${REFERENCE}" (at -1.898 4.299 90) (layer "F.Fab") hide
        (effects (font (size 0.7 0.7) (thickness 0.15)) (justify right bottom))
    )
    (fp_text user "Author: Antmicro" (at -1.898 5.499 90) (layer "F.Fab") hide
        (effects (font (size 0.7 0.7) (thickness 0.15)) (justify right bottom))
    )
    (fp_text user "License: Apache-2.0" (at -1.898 6.7 90) (layer "F.Fab") hide
        (effects (font (size 0.7 0.7) (thickness 0.15)) (justify right bottom))
    )
    (fp_line (start -0.85 1.6) (end -0.85 1.301)
      (stroke (width 0.15) (type solid)) (layer "F.SilkS"))
    (fp_line (start -0.8 -1.6) (end -0.8 -1.3)
      (stroke (width 0.15) (type solid)) (layer "F.SilkS"))
    (fp_line (start -0.8 -1.6) (end -0.5 -1.6)
      (stroke (width 0.15) (type solid)) (layer "F.SilkS"))
    (fp_line (start -0.55 1.6) (end -0.85 1.6)
      (stroke (width 0.15) (type solid)) (layer "F.SilkS"))
    (fp_line (start 0.8 -1.6) (end 0.5 -1.6)
      (stroke (width 0.15) (type solid)) (layer "F.SilkS"))
    (fp_line (start 0.8 -1.3) (end 0.8 -1.6)
      (stroke (width 0.15) (type solid)) (layer "F.SilkS"))
    (fp_line (start 0.8 0.55) (end 0.8 -0.55)
      (stroke (width 0.15) (type solid)) (layer "F.SilkS"))
    (fp_line (start 0.8 1.3) (end 0.8 1.599)
      (stroke (width 0.15) (type solid)) (layer "F.SilkS"))
    (fp_line (start 0.8 1.599) (end 0.549 1.599)
      (stroke (width 0.15) (type solid)) (layer "F.SilkS"))
    (fp_circle (center -1.25 -1.5) (end -1.2 -1.5)
      (stroke (width 0.15) (type solid)) (fill solid) (layer "F.SilkS"))
    (fp_rect (start 1.9 -1.76) (end -1.9 1.75)
      (stroke (width 0.05) (type solid)) (fill none) (layer "F.CrtYd"))
    (fp_line (start -0.398 -1.526) (end -0.874 -1.05)
      (stroke (width 0.15) (type solid)) (layer "F.Fab"))
    (fp_rect (start 0.874 1.523) (end -0.873 -1.525)
      (stroke (width 0.15) (type solid)) (fill none) (layer "F.Fab"))
    (pad "1" smd rect (at -1.351 -0.951 180) (size 0.55 1) (layers "F.Cu" "F.Paste" "F.Mask")
      (net 3 "VCC5V0_USB") (pinfunction "VIN") (pintype "power_in"))
    (pad "2" smd rect (at -1.351 0 180) (size 0.55 1) (layers "F.Cu" "F.Paste" "F.Mask")
      (net 77 "GNDD") (pinfunction "GND") (pintype "power_in"))
    (pad "3" smd rect (at -1.351 0.949 180) (size 0.55 1) (layers "F.Cu" "F.Paste" "F.Mask")
      (net 3 "VCC5V0_USB") (pinfunction "EN") (pintype "input"))
    (pad "4" smd rect (at 1.35 0.949 180) (size 0.55 1) (layers "F.Cu" "F.Paste" "F.Mask")
      (net 119 "unconnected-(U3-NC-Pad4)") (pinfunction "NC") (pintype "no_connect"))
    (pad "5" smd rect (at 1.35 -0.951 180) (size 0.55 1) (layers "F.Cu" "F.Paste" "F.Mask")
      (net 76 "VCC3V3_USB") (pinfunction "VOUT") (pintype "power_out"))
  )

  (footprint "antmicro-footprints:R_0603_1608Metric" (layer "F.Cu")
    (at 180.225 106.25 90)
    (descr "Resistor SMD 0603")
    (tags "resistor SMD 0603")
    (property "Author" "Antmicro")
    (property "Current" "1A")
    (property "DNP" "DNP")
    (property "License" "Apache-2.0")
    (property "MPN" "CR0603-J/-000ELF")
    (property "Manufacturer" "Bourns")
    (property "Sheetfile" "ftdi-module.kicad_sch")
    (property "Sheetname" "FTDI")
    (property "Tolerance" "")
    (property "Val" "0R")
    (property "dnp" "")
    (property "exclude_from_bom" "")
    (property "ki_description" "Zero Ohm Resistor, Jumper, 0603 [1608 Metric], Thick Film, 100 mW, 1 A, Surface Mount Device, CR")
    (property "ki_keywords" "0603, SMT, RESISTOR, PASSIVE")
    (attr smd exclude_from_bom)
    (fp_text reference "R39" (at -0.05 1.775 90) (layer "F.SilkS")
        (effects (font (size 0.7 0.7) (thickness 0.15)) (justify left bottom))
    )
    (fp_text value "R_0R_0603" (at 0 1.6 90) (layer "F.Fab")
        (effects (font (size 0.7 0.7) (thickness 0.15)) (justify left bottom))
    )
    (fp_text user "${REFERENCE}" (at -1.25 3.898 90) (layer "F.Fab") hide
        (effects (font (size 0.7 0.7) (thickness 0.15)) (justify left bottom))
    )
    (fp_text user "Author: Antmicro" (at -1.25 4.9 90) (layer "F.Fab") hide
        (effects (font (size 0.7 0.7) (thickness 0.15)) (justify left bottom))
    )
    (fp_text user "License: Apache-2.0" (at -1.25 5.9 90) (layer "F.Fab") hide
        (effects (font (size 0.7 0.7) (thickness 0.15)) (justify left bottom))
    )
    (fp_line (start -0.15 -0.4) (end 0.15 -0.4)
      (stroke (width 0.15) (type solid)) (layer "F.SilkS"))
    (fp_line (start -0.15 0.4) (end 0.15 0.4)
      (stroke (width 0.15) (type solid)) (layer "F.SilkS"))
    (fp_rect (start -1.25 -0.65) (end 1.25 0.65)
      (stroke (width 0.05) (type solid)) (fill none) (layer "F.CrtYd"))
    (fp_rect (start -0.8 -0.4) (end 0.8 0.4)
      (stroke (width 0.15) (type solid)) (fill none) (layer "F.Fab"))
    (pad "1" smd roundrect (at -0.7 0 90) (size 0.8 1) (layers "F.Cu" "F.Paste" "F.Mask") (roundrect_rratio 0.2)
      (net 81 "SCL_FTDI") (pintype "passive"))
    (pad "2" smd roundrect (at 0.7 0 90) (size 0.8 1) (layers "F.Cu" "F.Paste" "F.Mask") (roundrect_rratio 0.2)
      (net 17 "SCL") (pintype "passive"))
  )

  (footprint "antmicro-footprints:C_0402_1005Metric" (layer "F.Cu")
    (at 162.8 103.7 180)
    (descr "Capacitor SMD 0402")
    (tags "capacitor SMD 0402")
    (property "Author" "Antmicro")
    (property "Dielectric" "X5R")
    (property "License" "Apache-2.0")
    (property "MPN" "GRM155R61H104KE14D")
    (property "Manufacturer" "Murata")
    (property "Sheetfile" "pow-cycl-curr-meas.kicad_sch")
    (property "Sheetname" "Power Cycling & Current Measurement")
    (property "Val" "100n")
    (property "Voltage" "50V")
    (property "ki_description" "SMD Multilayer Ceramic Capacitor, 0.1 µF, 50 V, 0402 [1005 Metric], ± 10%, X5R, GRM Series")
    (property "ki_keywords" "0402, SMT, CAPACITOR, PASSIVE, CERAMIC, MLCC")
    (attr smd)
    (fp_text reference "C21" (at -1.2 -1.45) (layer "F.SilkS")
        (effects (font (size 0.7 0.7) (thickness 0.15)) (justify right bottom))
    )
    (fp_text value "C_100n_0402" (at -1.022927 2.155213) (layer "F.Fab")
        (effects (font (size 0.7 0.7) (thickness 0.15)) (justify right bottom))
    )
    (fp_text user "License: Apache-2.0" (at -0.939 5.799) (layer "F.Fab") hide
        (effects (font (size 0.7 0.7) (thickness 0.15)) (justify right bottom))
    )
    (fp_text user "${REFERENCE}" (at -0.939 4.599) (layer "F.Fab") hide
        (effects (font (size 0.7 0.7) (thickness 0.15)) (justify right bottom))
    )
    (fp_text user "Author: Antmicro" (at -0.939 3.399) (layer "F.Fab") hide
        (effects (font (size 0.7 0.7) (thickness 0.15)) (justify right bottom))
    )
    (fp_rect (start -0.925 -0.47) (end 0.925 0.47)
      (stroke (width 0.05) (type default)) (fill none) (layer "F.CrtYd"))
    (fp_line (start -0.494 -0.25) (end 0.504 -0.25)
      (stroke (width 0.15) (type solid)) (layer "F.Fab"))
    (fp_line (start -0.494 0.248) (end -0.494 -0.25)
      (stroke (width 0.15) (type solid)) (layer "F.Fab"))
    (fp_line (start 0.504 -0.25) (end 0.504 0.248)
      (stroke (width 0.15) (type solid)) (layer "F.Fab"))
    (fp_line (start 0.504 0.248) (end -0.494 0.248)
      (stroke (width 0.15) (type solid)) (layer "F.Fab"))
    (pad "1" smd roundrect (at -0.48 0 180) (size 0.59 0.64) (layers "F.Cu" "F.Paste" "F.Mask") (roundrect_rratio 0.25)
      (net 4 "GND") (pintype "passive"))
    (pad "2" smd roundrect (at 0.48 0 180) (size 0.59 0.64) (layers "F.Cu" "F.Paste" "F.Mask") (roundrect_rratio 0.25)
      (net 1 "VCC3V3") (pintype "passive"))
  )

  (footprint "antmicro-footprints:C_0402_1005Metric" (layer "F.Cu")
    (at 168.5 117.45 90)
    (descr "Capacitor SMD 0402")
    (tags "capacitor SMD 0402")
    (property "Author" "Antmicro")
    (property "Dielectric" "")
    (property "License" "Apache-2.0")
    (property "MPN" "GRM155R61A475MEAAD")
    (property "Manufacturer" "Murata")
    (property "Sheetfile" "ftdi-module.kicad_sch")
    (property "Sheetname" "FTDI")
    (property "Val" "4u7")
    (property "Voltage" "")
    (property "ki_description" "SMD Multilayer Ceramic Capacitor, 4.7 µF, 10 V, 0402 [1005 Metric], ± 20%, X5R, GRM Series")
    (property "ki_keywords" "0402, SMT, CAPACITOR, PASSIVE")
    (attr smd)
    (fp_text reference "C11" (at 0.9 0.4 90) (layer "F.SilkS")
        (effects (font (size 0.7 0.7) (thickness 0.15)) (justify left bottom))
    )
    (fp_text value "C_4u7_0402" (at -1.022927 2.155213 90) (layer "F.Fab")
        (effects (font (size 0.7 0.7) (thickness 0.15)) (justify left bottom))
    )
    (fp_text user "Author: Antmicro" (at -0.939 3.399 90) (layer "F.Fab") hide
        (effects (font (size 0.7 0.7) (thickness 0.15)) (justify left bottom))
    )
    (fp_text user "License: Apache-2.0" (at -0.939 5.799 90) (layer "F.Fab") hide
        (effects (font (size 0.7 0.7) (thickness 0.15)) (justify left bottom))
    )
    (fp_text user "${REFERENCE}" (at -0.939 4.599 90) (layer "F.Fab") hide
        (effects (font (size 0.7 0.7) (thickness 0.15)) (justify left bottom))
    )
    (fp_rect (start -0.925 -0.47) (end 0.925 0.47)
      (stroke (width 0.05) (type default)) (fill none) (layer "F.CrtYd"))
    (fp_line (start -0.494 -0.25) (end 0.504 -0.25)
      (stroke (width 0.15) (type solid)) (layer "F.Fab"))
    (fp_line (start -0.494 0.248) (end -0.494 -0.25)
      (stroke (width 0.15) (type solid)) (layer "F.Fab"))
    (fp_line (start 0.504 -0.25) (end 0.504 0.248)
      (stroke (width 0.15) (type solid)) (layer "F.Fab"))
    (fp_line (start 0.504 0.248) (end -0.494 0.248)
      (stroke (width 0.15) (type solid)) (layer "F.Fab"))
    (pad "1" smd roundrect (at -0.48 0 90) (size 0.59 0.64) (layers "F.Cu" "F.Paste" "F.Mask") (roundrect_rratio 0.25)
      (net 6 "/FTDI/FTDI_VPLL") (pintype "passive"))
    (pad "2" smd roundrect (at 0.48 0 90) (size 0.59 0.64) (layers "F.Cu" "F.Paste" "F.Mask") (roundrect_rratio 0.25)
      (net 77 "GNDD") (pintype "passive"))
  )

  (footprint "antmicro-footprints:C_0402_1005Metric" (layer "F.Cu")
    (at 167.45 117.435 90)
    (descr "Capacitor SMD 0402")
    (tags "capacitor SMD 0402")
    (property "Author" "Antmicro")
    (property "Dielectric" "X5R")
    (property "License" "Apache-2.0")
    (property "MPN" "GRM155R61H104KE14D")
    (property "Manufacturer" "Murata")
    (property "Sheetfile" "ftdi-module.kicad_sch")
    (property "Sheetname" "FTDI")
    (property "Val" "100n")
    (property "Voltage" "50V")
    (property "ki_description" "SMD Multilayer Ceramic Capacitor, 0.1 µF, 50 V, 0402 [1005 Metric], ± 10%, X5R, GRM Series")
    (property "ki_keywords" "0402, SMT, CAPACITOR, PASSIVE, CERAMIC, MLCC")
    (attr smd)
    (fp_text reference "C14" (at 0.885 0.45 90) (layer "F.SilkS")
        (effects (font (size 0.7 0.7) (thickness 0.15)) (justify left bottom))
    )
    (fp_text value "C_100n_0402" (at -1.022927 2.155213 90) (layer "F.Fab")
        (effects (font (size 0.7 0.7) (thickness 0.15)) (justify left bottom))
    )
    (fp_text user "${REFERENCE}" (at -0.939 4.599 90) (layer "F.Fab") hide
        (effects (font (size 0.7 0.7) (thickness 0.15)) (justify left bottom))
    )
    (fp_text user "License: Apache-2.0" (at -0.939 5.799 90) (layer "F.Fab") hide
        (effects (font (size 0.7 0.7) (thickness 0.15)) (justify left bottom))
    )
    (fp_text user "Author: Antmicro" (at -0.939 3.399 90) (layer "F.Fab") hide
        (effects (font (size 0.7 0.7) (thickness 0.15)) (justify left bottom))
    )
    (fp_rect (start -0.925 -0.47) (end 0.925 0.47)
      (stroke (width 0.05) (type default)) (fill none) (layer "F.CrtYd"))
    (fp_line (start -0.494 -0.25) (end 0.504 -0.25)
      (stroke (width 0.15) (type solid)) (layer "F.Fab"))
    (fp_line (start -0.494 0.248) (end -0.494 -0.25)
      (stroke (width 0.15) (type solid)) (layer "F.Fab"))
    (fp_line (start 0.504 -0.25) (end 0.504 0.248)
      (stroke (width 0.15) (type solid)) (layer "F.Fab"))
    (fp_line (start 0.504 0.248) (end -0.494 0.248)
      (stroke (width 0.15) (type solid)) (layer "F.Fab"))
    (pad "1" smd roundrect (at -0.48 0 90) (size 0.59 0.64) (layers "F.Cu" "F.Paste" "F.Mask") (roundrect_rratio 0.25)
      (net 6 "/FTDI/FTDI_VPLL") (pintype "passive"))
    (pad "2" smd roundrect (at 0.48 0 90) (size 0.59 0.64) (layers "F.Cu" "F.Paste" "F.Mask") (roundrect_rratio 0.25)
      (net 77 "GNDD") (pintype "passive"))
  )

  (footprint "antmicro-footprints:C_0402_1005Metric" (layer "F.Cu")
    (at 168.9575 120.915 90)
    (descr "Capacitor SMD 0402")
    (tags "capacitor SMD 0402")
    (property "Author" "Antmicro")
    (property "Dielectric" "X5R")
    (property "License" "Apache-2.0")
    (property "MPN" "GRM155R61H104KE14D")
    (property "Manufacturer" "Murata")
    (property "Sheetfile" "ftdi-module.kicad_sch")
    (property "Sheetname" "FTDI")
    (property "Val" "100n")
    (property "Voltage" "50V")
    (property "ki_description" "SMD Multilayer Ceramic Capacitor, 0.1 µF, 50 V, 0402 [1005 Metric], ± 10%, X5R, GRM Series")
    (property "ki_keywords" "0402, SMT, CAPACITOR, PASSIVE, CERAMIC, MLCC")
    (attr smd)
    (fp_text reference "C15" (at 0.965 1.1425 90) (layer "F.SilkS")
        (effects (font (size 0.7 0.7) (thickness 0.15)) (justify left bottom))
    )
    (fp_text value "C_100n_0402" (at -1.022927 2.155213 90) (layer "F.Fab")
        (effects (font (size 0.7 0.7) (thickness 0.15)) (justify left bottom))
    )
    (fp_text user "${REFERENCE}" (at -0.939 4.599 90) (layer "F.Fab") hide
        (effects (font (size 0.7 0.7) (thickness 0.15)) (justify left bottom))
    )
    (fp_text user "Author: Antmicro" (at -0.939 3.399 90) (layer "F.Fab") hide
        (effects (font (size 0.7 0.7) (thickness 0.15)) (justify left bottom))
    )
    (fp_text user "License: Apache-2.0" (at -0.939 5.799 90) (layer "F.Fab") hide
        (effects (font (size 0.7 0.7) (thickness 0.15)) (justify left bottom))
    )
    (fp_rect (start -0.925 -0.47) (end 0.925 0.47)
      (stroke (width 0.05) (type default)) (fill none) (layer "F.CrtYd"))
    (fp_line (start -0.494 -0.25) (end 0.504 -0.25)
      (stroke (width 0.15) (type solid)) (layer "F.Fab"))
    (fp_line (start -0.494 0.248) (end -0.494 -0.25)
      (stroke (width 0.15) (type solid)) (layer "F.Fab"))
    (fp_line (start 0.504 -0.25) (end 0.504 0.248)
      (stroke (width 0.15) (type solid)) (layer "F.Fab"))
    (fp_line (start 0.504 0.248) (end -0.494 0.248)
      (stroke (width 0.15) (type solid)) (layer "F.Fab"))
    (pad "1" smd roundrect (at -0.48 0 90) (size 0.59 0.64) (layers "F.Cu" "F.Paste" "F.Mask") (roundrect_rratio 0.25)
      (net 8 "/FTDI/FTDI_VPHY") (pintype "passive"))
    (pad "2" smd roundrect (at 0.48 0 90) (size 0.59 0.64) (layers "F.Cu" "F.Paste" "F.Mask") (roundrect_rratio 0.25)
      (net 77 "GNDD") (pintype "passive"))
  )

  (footprint "antmicro-footprints:C_0402_1005Metric" (layer "F.Cu")
    (at 170.0575 120.9 90)
    (descr "Capacitor SMD 0402")
    (tags "capacitor SMD 0402")
    (property "Author" "Antmicro")
    (property "Dielectric" "")
    (property "License" "Apache-2.0")
    (property "MPN" "GRM155R61A475MEAAD")
    (property "Manufacturer" "Murata")
    (property "Sheetfile" "ftdi-module.kicad_sch")
    (property "Sheetname" "FTDI")
    (property "Val" "4u7")
    (property "Voltage" "")
    (property "ki_description" "SMD Multilayer Ceramic Capacitor, 4.7 µF, 10 V, 0402 [1005 Metric], ± 20%, X5R, GRM Series")
    (property "ki_keywords" "0402, SMT, CAPACITOR, PASSIVE")
    (attr smd)
    (fp_text reference "C12" (at 0.9 1.0925 90) (layer "F.SilkS")
        (effects (font (size 0.7 0.7) (thickness 0.15)) (justify left bottom))
    )
    (fp_text value "C_4u7_0402" (at -1.022927 2.155213 90) (layer "F.Fab")
        (effects (font (size 0.7 0.7) (thickness 0.15)) (justify left bottom))
    )
    (fp_text user "Author: Antmicro" (at -0.939 3.399 90) (layer "F.Fab") hide
        (effects (font (size 0.7 0.7) (thickness 0.15)) (justify left bottom))
    )
    (fp_text user "License: Apache-2.0" (at -0.939 5.799 90) (layer "F.Fab") hide
        (effects (font (size 0.7 0.7) (thickness 0.15)) (justify left bottom))
    )
    (fp_text user "${REFERENCE}" (at -0.939 4.599 90) (layer "F.Fab") hide
        (effects (font (size 0.7 0.7) (thickness 0.15)) (justify left bottom))
    )
    (fp_rect (start -0.925 -0.47) (end 0.925 0.47)
      (stroke (width 0.05) (type default)) (fill none) (layer "F.CrtYd"))
    (fp_line (start -0.494 -0.25) (end 0.504 -0.25)
      (stroke (width 0.15) (type solid)) (layer "F.Fab"))
    (fp_line (start -0.494 0.248) (end -0.494 -0.25)
      (stroke (width 0.15) (type solid)) (layer "F.Fab"))
    (fp_line (start 0.504 -0.25) (end 0.504 0.248)
      (stroke (width 0.15) (type solid)) (layer "F.Fab"))
    (fp_line (start 0.504 0.248) (end -0.494 0.248)
      (stroke (width 0.15) (type solid)) (layer "F.Fab"))
    (pad "1" smd roundrect (at -0.48 0 90) (size 0.59 0.64) (layers "F.Cu" "F.Paste" "F.Mask") (roundrect_rratio 0.25)
      (net 8 "/FTDI/FTDI_VPHY") (pintype "passive"))
    (pad "2" smd roundrect (at 0.48 0 90) (size 0.59 0.64) (layers "F.Cu" "F.Paste" "F.Mask") (roundrect_rratio 0.25)
      (net 77 "GNDD") (pintype "passive"))
  )

  (footprint "antmicro-footprints:C_0402_1005Metric" (layer "F.Cu")
    (at 162.185 113.9)
    (descr "Capacitor SMD 0402")
    (tags "capacitor SMD 0402")
    (property "Author" "Antmicro")
    (property "Dielectric" "X5R")
    (property "License" "Apache-2.0")
    (property "MPN" "GRM155R61H104KE14D")
    (property "Manufacturer" "Murata")
    (property "Sheetfile" "ftdi-module.kicad_sch")
    (property "Sheetname" "FTDI")
    (property "Val" "100n")
    (property "Voltage" "50V")
    (property "ki_description" "SMD Multilayer Ceramic Capacitor, 0.1 µF, 50 V, 0402 [1005 Metric], ± 10%, X5R, GRM Series")
    (property "ki_keywords" "0402, SMT, CAPACITOR, PASSIVE, CERAMIC, MLCC")
    (attr smd)
    (fp_text reference "C3" (at -1.385 -0.5) (layer "F.SilkS")
        (effects (font (size 0.7 0.7) (thickness 0.15)) (justify left bottom))
    )
    (fp_text value "C_100n_0402" (at -1.022927 2.155213) (layer "F.Fab")
        (effects (font (size 0.7 0.7) (thickness 0.15)) (justify left bottom))
    )
    (fp_text user "License: Apache-2.0" (at -0.939 5.799) (layer "F.Fab") hide
        (effects (font (size 0.7 0.7) (thickness 0.15)) (justify left bottom))
    )
    (fp_text user "${REFERENCE}" (at -0.939 4.599) (layer "F.Fab") hide
        (effects (font (size 0.7 0.7) (thickness 0.15)) (justify left bottom))
    )
    (fp_text user "Author: Antmicro" (at -0.939 3.399) (layer "F.Fab") hide
        (effects (font (size 0.7 0.7) (thickness 0.15)) (justify left bottom))
    )
    (fp_rect (start -0.925 -0.47) (end 0.925 0.47)
      (stroke (width 0.05) (type default)) (fill none) (layer "F.CrtYd"))
    (fp_line (start -0.494 -0.25) (end 0.504 -0.25)
      (stroke (width 0.15) (type solid)) (layer "F.Fab"))
    (fp_line (start -0.494 0.248) (end -0.494 -0.25)
      (stroke (width 0.15) (type solid)) (layer "F.Fab"))
    (fp_line (start 0.504 -0.25) (end 0.504 0.248)
      (stroke (width 0.15) (type solid)) (layer "F.Fab"))
    (fp_line (start 0.504 0.248) (end -0.494 0.248)
      (stroke (width 0.15) (type solid)) (layer "F.Fab"))
    (pad "1" smd roundrect (at -0.48 0) (size 0.59 0.64) (layers "F.Cu" "F.Paste" "F.Mask") (roundrect_rratio 0.25)
      (net 77 "GNDD") (pintype "passive"))
    (pad "2" smd roundrect (at 0.48 0) (size 0.59 0.64) (layers "F.Cu" "F.Paste" "F.Mask") (roundrect_rratio 0.25)
      (net 76 "VCC3V3_USB") (pintype "passive"))
  )

  (footprint "antmicro-footprints:FB_0603_1608Metric" (layer "F.Cu")
    (at 171.9575 121.4)
    (property "Author" "Antmicro")
    (property "Current" "")
    (property "License" "Apache-2.0")
    (property "MPN" "BLM18AG601SN1D")
    (property "Manufacturer" "Murata")
    (property "Sheetfile" "ftdi-module.kicad_sch")
    (property "Sheetname" "FTDI")
    (property "Val" "600Z/0.5A")
    (property "ki_description" "Ferrite Bead, 0603 [1608 Metric], 600 ohm, 500 mA, BLM18A, 0.38 ohm, ± 25%, General use")
    (property "ki_keywords" "0603, SMT, FERRITE BEAD, PASSIVE")
    (attr smd)
    (fp_text reference "FB2" (at 1.1925 0.25) (layer "F.SilkS")
        (effects (font (size 0.7 0.7) (thickness 0.15)) (justify left bottom))
    )
    (fp_text value "FB_600Z_0.5A_Murata-BLM18AG_0603" (at 0 1.5) (layer "F.Fab")
        (effects (font (size 0.7 0.7) (thickness 0.15)) (justify left bottom))
    )
    (fp_text user "Author: Antmicro" (at -1.653 3.162) (layer "F.Fab") hide
        (effects (font (size 0.7 0.7) (thickness 0.15)) (justify left bottom))
    )
    (fp_text user "License: Apache-2.0" (at -1.653 5.9) (layer "F.Fab") hide
        (effects (font (size 0.7 0.7) (thickness 0.15)) (justify left bottom))
    )
    (fp_text user "${REFERENCE}" (at -1.653 4.6) (layer "F.Fab") hide
        (effects (font (size 0.7 0.7) (thickness 0.15)) (justify left bottom))
    )
    (fp_line (start -0.15 -0.4) (end 0.15 -0.4)
      (stroke (width 0.15) (type solid)) (layer "F.SilkS"))
    (fp_line (start -0.15 0.4) (end 0.15 0.4)
      (stroke (width 0.15) (type solid)) (layer "F.SilkS"))
    (fp_rect (start -1.25 -0.65) (end 1.25 0.65)
      (stroke (width 0.05) (type solid)) (fill none) (layer "F.CrtYd"))
    (fp_line (start -0.803 0.406) (end -0.803 -0.408)
      (stroke (width 0.15) (type solid)) (layer "F.Fab"))
    (fp_line (start 0.8 -0.408) (end -0.803 -0.408)
      (stroke (width 0.15) (type solid)) (layer "F.Fab"))
    (fp_line (start 0.8 -0.408) (end 0.8 0.406)
      (stroke (width 0.15) (type solid)) (layer "F.Fab"))
    (fp_line (start 0.8 0.406) (end -0.803 0.406)
      (stroke (width 0.15) (type solid)) (layer "F.Fab"))
    (pad "1" smd roundrect (at -0.7 0) (size 0.8 1) (layers "F.Cu" "F.Paste" "F.Mask") (roundrect_rratio 0.2)
      (net 8 "/FTDI/FTDI_VPHY") (pintype "passive"))
    (pad "2" smd roundrect (at 0.7 0) (size 0.8 1) (layers "F.Cu" "F.Paste" "F.Mask") (roundrect_rratio 0.2)
      (net 76 "VCC3V3_USB") (pintype "passive"))
  )

  (footprint "antmicro-footprints:C_0402_1005Metric" (layer "F.Cu")
    (at 154.6 116.4 -90)
    (descr "Capacitor SMD 0402")
    (tags "capacitor SMD 0402")
    (property "Author" "Antmicro")
    (property "Dielectric" "X5R")
    (property "License" "Apache-2.0")
    (property "MPN" "GRM155R61H104KE14D")
    (property "Manufacturer" "Murata")
    (property "Sheetfile" "ftdi-module.kicad_sch")
    (property "Sheetname" "FTDI")
    (property "Val" "100n")
    (property "Voltage" "50V")
    (property "ki_description" "SMD Multilayer Ceramic Capacitor, 0.1 µF, 50 V, 0402 [1005 Metric], ± 10%, X5R, GRM Series")
    (property "ki_keywords" "0402, SMT, CAPACITOR, PASSIVE, CERAMIC, MLCC")
    (zone_connect 1)
    (attr smd)
    (fp_text reference "C10" (at -2.1 0.6 90) (layer "F.SilkS")
        (effects (font (size 0.7 0.7) (thickness 0.15)) (justify right bottom))
    )
    (fp_text value "C_100n_0402" (at -1.022927 2.155213 90) (layer "F.Fab")
        (effects (font (size 0.7 0.7) (thickness 0.15)) (justify right bottom))
    )
    (fp_text user "License: Apache-2.0" (at -0.939 5.799 90) (layer "F.Fab") hide
        (effects (font (size 0.7 0.7) (thickness 0.15)) (justify right bottom))
    )
    (fp_text user "Author: Antmicro" (at -0.939 3.399 90) (layer "F.Fab") hide
        (effects (font (size 0.7 0.7) (thickness 0.15)) (justify right bottom))
    )
    (fp_text user "${REFERENCE}" (at -0.939 4.599 90) (layer "F.Fab") hide
        (effects (font (size 0.7 0.7) (thickness 0.15)) (justify right bottom))
    )
    (fp_rect (start -0.925 -0.47) (end 0.925 0.47)
      (stroke (width 0.05) (type default)) (fill none) (layer "F.CrtYd"))
    (fp_line (start -0.494 -0.25) (end 0.504 -0.25)
      (stroke (width 0.15) (type solid)) (layer "F.Fab"))
    (fp_line (start -0.494 0.248) (end -0.494 -0.25)
      (stroke (width 0.15) (type solid)) (layer "F.Fab"))
    (fp_line (start 0.504 -0.25) (end 0.504 0.248)
      (stroke (width 0.15) (type solid)) (layer "F.Fab"))
    (fp_line (start 0.504 0.248) (end -0.494 0.248)
      (stroke (width 0.15) (type solid)) (layer "F.Fab"))
    (pad "1" smd roundrect (at -0.48 0 270) (size 0.59 0.64) (layers "F.Cu" "F.Paste" "F.Mask") (roundrect_rratio 0.25)
      (net 77 "GNDD") (pintype "passive"))
    (pad "2" smd roundrect (at 0.48 0 270) (size 0.59 0.64) (layers "F.Cu" "F.Paste" "F.Mask") (roundrect_rratio 0.25)
      (net 7 "1V8_FT") (pintype "passive"))
  )

  (footprint "antmicro-footprints:Resonator_SMD_Geyer_KX-7_3.2x2.5x0.8mm" (layer "F.Cu")
    (at 167.815 124.3)
    (property "Author" "Antmicro")
    (property "License" "Apache-2.0")
    (property "MPN" "KX-7_SMD_CRYSTAL_12,0 MHZ")
    (property "Manufacturer" "Geyer Electronic")
    (property "Sheetfile" "ftdi-module.kicad_sch")
    (property "Sheetname" "FTDI")
    (property "Val" "12 MHz")
    (property "ki_description" "Crystal, 12 MHz, SMT, 3.2mm x 2.5mm, 30 ppm, 12 pF, KX-7")
    (property "ki_keywords" "SMT, CERAMIC, OSCILLATOR")
    (attr smd)
    (fp_text reference "Y1" (at -1.465 2.9) (layer "F.SilkS")
        (effects (font (size 0.7 0.7) (thickness 0.15)) (justify left bottom))
    )
    (fp_text value "Resonator_12MHz_KX_7" (at 0 2.85) (layer "F.Fab")
        (effects (font (size 0.7 0.7) (thickness 0.15)) (justify left bottom))
    )
    (fp_text user "${REFERENCE}" (at -1.75 4.884) (layer "F.Fab") hide
        (effects (font (size 0.7 0.7) (thickness 0.15)) (justify left bottom))
    )
    (fp_text user "Author: Antmicro" (at -1.75 6.084) (layer "F.Fab") hide
        (effects (font (size 0.7 0.7) (thickness 0.15)) (justify left bottom))
    )
    (fp_text user "License: Apache-2.0" (at -1.75 7.283) (layer "F.Fab") hide
        (effects (font (size 0.7 0.7) (thickness 0.15)) (justify left bottom))
    )
    (fp_line (start -1.4 -0.3) (end -1.4 0.28)
      (stroke (width 0.15) (type solid)) (layer "F.SilkS"))
    (fp_line (start 1.399 -0.3) (end 1.399 0.28)
      (stroke (width 0.15) (type solid)) (layer "F.SilkS"))
    (fp_circle (center -1.65 -1.7) (end -1.6 -1.7)
      (stroke (width 0.15) (type solid)) (fill solid) (layer "F.SilkS"))
    (fp_rect (start -1.55 -1.9) (end 1.55 1.9)
      (stroke (width 0.05) (type solid)) (fill none) (layer "F.CrtYd"))
    (fp_line (start -1.25 -1.35) (end -1.25 1.6)
      (stroke (width 0.15) (type solid)) (layer "F.Fab"))
    (fp_line (start -1.25 -1.35) (end -1 -1.601)
      (stroke (width 0.15) (type solid)) (layer "F.Fab"))
    (fp_line (start -1 -1.601) (end 1.249 -1.601)
      (stroke (width 0.15) (type solid)) (layer "F.Fab"))
    (fp_line (start 1.249 -1.601) (end 1.249 1.6)
      (stroke (width 0.15) (type solid)) (layer "F.Fab"))
    (fp_line (start 1.249 1.6) (end -1.25 1.6)
      (stroke (width 0.15) (type solid)) (layer "F.Fab"))
    (pad "1" smd rect (at -0.9 -1.15) (size 1.1 1.3) (layers "F.Cu" "F.Paste" "F.Mask")
      (net 125 "/FTDI/OSCO") (pintype "passive"))
    (pad "2" smd rect (at -0.9 1.15) (size 1.1 1.3) (layers "F.Cu" "F.Paste" "F.Mask")
      (net 77 "GNDD") (pinfunction "SH") (pintype "passive"))
    (pad "3" smd rect (at 0.9 1.15) (size 1.1 1.3) (layers "F.Cu" "F.Paste" "F.Mask")
      (net 5 "/FTDI/OSCI") (pintype "passive"))
    (pad "4" smd rect (at 0.9 -1.15) (size 1.1 1.3) (layers "F.Cu" "F.Paste" "F.Mask")
      (net 77 "GNDD") (pinfunction "SH") (pintype "passive"))
  )

  (footprint "antmicro-footprints:C_0402_1005Metric" (layer "F.Cu")
    (at 156.6 126.8 180)
    (descr "Capacitor SMD 0402")
    (tags "capacitor SMD 0402")
    (property "Author" "Antmicro")
    (property "Dielectric" "")
    (property "License" "Apache-2.0")
    (property "MPN" "GRM155R61A475MEAAD")
    (property "Manufacturer" "Murata")
    (property "Sheetfile" "ftdi-module.kicad_sch")
    (property "Sheetname" "FTDI")
    (property "Val" "4u7")
    (property "Voltage" "")
    (property "ki_description" "SMD Multilayer Ceramic Capacitor, 4.7 µF, 10 V, 0402 [1005 Metric], ± 20%, X5R, GRM Series")
    (property "ki_keywords" "0402, SMT, CAPACITOR, PASSIVE")
    (attr smd)
    (fp_text reference "C13" (at -3.05 -0.4) (layer "F.SilkS")
        (effects (font (size 0.7 0.7) (thickness 0.15)) (justify right bottom))
    )
    (fp_text value "C_4u7_0402" (at -1.022927 2.155213) (layer "F.Fab")
        (effects (font (size 0.7 0.7) (thickness 0.15)) (justify right bottom))
    )
    (fp_text user "Author: Antmicro" (at -0.939 3.399) (layer "F.Fab") hide
        (effects (font (size 0.7 0.7) (thickness 0.15)) (justify right bottom))
    )
    (fp_text user "License: Apache-2.0" (at -0.939 5.799) (layer "F.Fab") hide
        (effects (font (size 0.7 0.7) (thickness 0.15)) (justify right bottom))
    )
    (fp_text user "${REFERENCE}" (at -0.939 4.599) (layer "F.Fab") hide
        (effects (font (size 0.7 0.7) (thickness 0.15)) (justify right bottom))
    )
    (fp_rect (start -0.925 -0.47) (end 0.925 0.47)
      (stroke (width 0.05) (type default)) (fill none) (layer "F.CrtYd"))
    (fp_line (start -0.494 -0.25) (end 0.504 -0.25)
      (stroke (width 0.15) (type solid)) (layer "F.Fab"))
    (fp_line (start -0.494 0.248) (end -0.494 -0.25)
      (stroke (width 0.15) (type solid)) (layer "F.Fab"))
    (fp_line (start 0.504 -0.25) (end 0.504 0.248)
      (stroke (width 0.15) (type solid)) (layer "F.Fab"))
    (fp_line (start 0.504 0.248) (end -0.494 0.248)
      (stroke (width 0.15) (type solid)) (layer "F.Fab"))
    (pad "1" smd roundrect (at -0.48 0 180) (size 0.59 0.64) (layers "F.Cu" "F.Paste" "F.Mask") (roundrect_rratio 0.25)
      (net 77 "GNDD") (pintype "passive"))
    (pad "2" smd roundrect (at 0.48 0 180) (size 0.59 0.64) (layers "F.Cu" "F.Paste" "F.Mask") (roundrect_rratio 0.25)
      (net 7 "1V8_FT") (pintype "passive"))
  )

  (footprint "antmicro-footprints:FB_0603_1608Metric" (layer "F.Cu")
    (at 170.4 117.2)
    (property "Author" "Antmicro")
    (property "Current" "")
    (property "License" "Apache-2.0")
    (property "MPN" "BLM18AG601SN1D")
    (property "Manufacturer" "Murata")
    (property "Sheetfile" "ftdi-module.kicad_sch")
    (property "Sheetname" "FTDI")
    (property "Val" "600Z/0.5A")
    (property "ki_description" "Ferrite Bead, 0603 [1608 Metric], 600 ohm, 500 mA, BLM18A, 0.38 ohm, ± 25%, General use")
    (property "ki_keywords" "0603, SMT, FERRITE BEAD, PASSIVE")
    (attr smd)
    (fp_text reference "FB1" (at -0.95 -0.75) (layer "F.SilkS")
        (effects (font (size 0.7 0.7) (thickness 0.15)) (justify left bottom))
    )
    (fp_text value "FB_600Z_0.5A_Murata-BLM18AG_0603" (at 0 1.5) (layer "F.Fab")
        (effects (font (size 0.7 0.7) (thickness 0.15)) (justify left bottom))
    )
    (fp_text user "${REFERENCE}" (at -1.653 4.6) (layer "F.Fab") hide
        (effects (font (size 0.7 0.7) (thickness 0.15)) (justify left bottom))
    )
    (fp_text user "License: Apache-2.0" (at -1.653 5.9) (layer "F.Fab") hide
        (effects (font (size 0.7 0.7) (thickness 0.15)) (justify left bottom))
    )
    (fp_text user "Author: Antmicro" (at -1.653 3.162) (layer "F.Fab") hide
        (effects (font (size 0.7 0.7) (thickness 0.15)) (justify left bottom))
    )
    (fp_line (start -0.15 -0.4) (end 0.15 -0.4)
      (stroke (width 0.15) (type solid)) (layer "F.SilkS"))
    (fp_line (start -0.15 0.4) (end 0.15 0.4)
      (stroke (width 0.15) (type solid)) (layer "F.SilkS"))
    (fp_rect (start -1.25 -0.65) (end 1.25 0.65)
      (stroke (width 0.05) (type solid)) (fill none) (layer "F.CrtYd"))
    (fp_line (start -0.803 0.406) (end -0.803 -0.408)
      (stroke (width 0.15) (type solid)) (layer "F.Fab"))
    (fp_line (start 0.8 -0.408) (end -0.803 -0.408)
      (stroke (width 0.15) (type solid)) (layer "F.Fab"))
    (fp_line (start 0.8 -0.408) (end 0.8 0.406)
      (stroke (width 0.15) (type solid)) (layer "F.Fab"))
    (fp_line (start 0.8 0.406) (end -0.803 0.406)
      (stroke (width 0.15) (type solid)) (layer "F.Fab"))
    (pad "1" smd roundrect (at -0.7 0) (size 0.8 1) (layers "F.Cu" "F.Paste" "F.Mask") (roundrect_rratio 0.2)
      (net 6 "/FTDI/FTDI_VPLL") (pintype "passive"))
    (pad "2" smd roundrect (at 0.7 0) (size 0.8 1) (layers "F.Cu" "F.Paste" "F.Mask") (roundrect_rratio 0.2)
      (net 76 "VCC3V3_USB") (pintype "passive"))
  )

  (footprint "antmicro-footprints:C_0402_1005Metric" (layer "F.Cu")
    (at 154.5 119.915 90)
    (descr "Capacitor SMD 0402")
    (tags "capacitor SMD 0402")
    (property "Author" "Antmicro")
    (property "Dielectric" "X5R")
    (property "License" "Apache-2.0")
    (property "MPN" "GRM155R61H104KE14D")
    (property "Manufacturer" "Murata")
    (property "Sheetfile" "ftdi-module.kicad_sch")
    (property "Sheetname" "FTDI")
    (property "Val" "100n")
    (property "Voltage" "50V")
    (property "ki_description" "SMD Multilayer Ceramic Capacitor, 0.1 µF, 50 V, 0402 [1005 Metric], ± 10%, X5R, GRM Series")
    (property "ki_keywords" "0402, SMT, CAPACITOR, PASSIVE, CERAMIC, MLCC")
    (zone_connect 1)
    (attr smd)
    (fp_text reference "C4" (at -1.285 -0.6 90) (layer "F.SilkS")
        (effects (font (size 0.7 0.7) (thickness 0.15)) (justify left bottom))
    )
    (fp_text value "C_100n_0402" (at -1.022927 2.155213 90) (layer "F.Fab")
        (effects (font (size 0.7 0.7) (thickness 0.15)) (justify left bottom))
    )
    (fp_text user "${REFERENCE}" (at -0.939 4.599 90) (layer "F.Fab") hide
        (effects (font (size 0.7 0.7) (thickness 0.15)) (justify left bottom))
    )
    (fp_text user "Author: Antmicro" (at -0.939 3.399 90) (layer "F.Fab") hide
        (effects (font (size 0.7 0.7) (thickness 0.15)) (justify left bottom))
    )
    (fp_text user "License: Apache-2.0" (at -0.939 5.799 90) (layer "F.Fab") hide
        (effects (font (size 0.7 0.7) (thickness 0.15)) (justify left bottom))
    )
    (fp_rect (start -0.925 -0.47) (end 0.925 0.47)
      (stroke (width 0.05) (type default)) (fill none) (layer "F.CrtYd"))
    (fp_line (start -0.494 -0.25) (end 0.504 -0.25)
      (stroke (width 0.15) (type solid)) (layer "F.Fab"))
    (fp_line (start -0.494 0.248) (end -0.494 -0.25)
      (stroke (width 0.15) (type solid)) (layer "F.Fab"))
    (fp_line (start 0.504 -0.25) (end 0.504 0.248)
      (stroke (width 0.15) (type solid)) (layer "F.Fab"))
    (fp_line (start 0.504 0.248) (end -0.494 0.248)
      (stroke (width 0.15) (type solid)) (layer "F.Fab"))
    (pad "1" smd roundrect (at -0.48 0 90) (size 0.59 0.64) (layers "F.Cu" "F.Paste" "F.Mask") (roundrect_rratio 0.25)
      (net 77 "GNDD") (pintype "passive"))
    (pad "2" smd roundrect (at 0.48 0 90) (size 0.59 0.64) (layers "F.Cu" "F.Paste" "F.Mask") (roundrect_rratio 0.25)
      (net 76 "VCC3V3_USB") (pintype "passive"))
  )

  (footprint "antmicro-footprints:C_0402_1005Metric" (layer "F.Cu")
    (at 159.8 124.7)
    (descr "Capacitor SMD 0402")
    (tags "capacitor SMD 0402")
    (property "Author" "Antmicro")
    (property "Dielectric" "X5R")
    (property "License" "Apache-2.0")
    (property "MPN" "GRM155R61H104KE14D")
    (property "Manufacturer" "Murata")
    (property "Sheetfile" "ftdi-module.kicad_sch")
    (property "Sheetname" "FTDI")
    (property "Val" "100n")
    (property "Voltage" "50V")
    (property "ki_description" "SMD Multilayer Ceramic Capacitor, 0.1 µF, 50 V, 0402 [1005 Metric], ± 10%, X5R, GRM Series")
    (property "ki_keywords" "0402, SMT, CAPACITOR, PASSIVE, CERAMIC, MLCC")
    (zone_connect 1)
    (attr smd)
    (fp_text reference "C7" (at -0.65 1.45) (layer "F.SilkS")
        (effects (font (size 0.7 0.7) (thickness 0.15)) (justify left bottom))
    )
    (fp_text value "C_100n_0402" (at -1.022927 2.155213) (layer "F.Fab")
        (effects (font (size 0.7 0.7) (thickness 0.15)) (justify left bottom))
    )
    (fp_text user "${REFERENCE}" (at -0.939 4.599) (layer "F.Fab") hide
        (effects (font (size 0.7 0.7) (thickness 0.15)) (justify left bottom))
    )
    (fp_text user "License: Apache-2.0" (at -0.939 5.799) (layer "F.Fab") hide
        (effects (font (size 0.7 0.7) (thickness 0.15)) (justify left bottom))
    )
    (fp_text user "Author: Antmicro" (at -0.939 3.399) (layer "F.Fab") hide
        (effects (font (size 0.7 0.7) (thickness 0.15)) (justify left bottom))
    )
    (fp_rect (start -0.925 -0.47) (end 0.925 0.47)
      (stroke (width 0.05) (type default)) (fill none) (layer "F.CrtYd"))
    (fp_line (start -0.494 -0.25) (end 0.504 -0.25)
      (stroke (width 0.15) (type solid)) (layer "F.Fab"))
    (fp_line (start -0.494 0.248) (end -0.494 -0.25)
      (stroke (width 0.15) (type solid)) (layer "F.Fab"))
    (fp_line (start 0.504 -0.25) (end 0.504 0.248)
      (stroke (width 0.15) (type solid)) (layer "F.Fab"))
    (fp_line (start 0.504 0.248) (end -0.494 0.248)
      (stroke (width 0.15) (type solid)) (layer "F.Fab"))
    (pad "1" smd roundrect (at -0.48 0) (size 0.59 0.64) (layers "F.Cu" "F.Paste" "F.Mask") (roundrect_rratio 0.25)
      (net 77 "GNDD") (pintype "passive"))
    (pad "2" smd roundrect (at 0.48 0) (size 0.59 0.64) (layers "F.Cu" "F.Paste" "F.Mask") (roundrect_rratio 0.25)
      (net 76 "VCC3V3_USB") (pintype "passive"))
  )

  (footprint "antmicro-footprints:C_0402_1005Metric" (layer "F.Cu")
    (at 157.7 124.7 180)
    (descr "Capacitor SMD 0402")
    (tags "capacitor SMD 0402")
    (property "Author" "Antmicro")
    (property "Dielectric" "X5R")
    (property "License" "Apache-2.0")
    (property "MPN" "GRM155R61H104KE14D")
    (property "Manufacturer" "Murata")
    (property "Sheetfile" "ftdi-module.kicad_sch")
    (property "Sheetname" "FTDI")
    (property "Val" "100n")
    (property "Voltage" "50V")
    (property "ki_description" "SMD Multilayer Ceramic Capacitor, 0.1 µF, 50 V, 0402 [1005 Metric], ± 10%, X5R, GRM Series")
    (property "ki_keywords" "0402, SMT, CAPACITOR, PASSIVE, CERAMIC, MLCC")
    (zone_connect 1)
    (attr smd)
    (fp_text reference "C6" (at -1.5 -1.45) (layer "F.SilkS")
        (effects (font (size 0.7 0.7) (thickness 0.15)) (justify right bottom))
    )
    (fp_text value "C_100n_0402" (at -1.022927 2.155213) (layer "F.Fab")
        (effects (font (size 0.7 0.7) (thickness 0.15)) (justify right bottom))
    )
    (fp_text user "${REFERENCE}" (at -0.939 4.599) (layer "F.Fab") hide
        (effects (font (size 0.7 0.7) (thickness 0.15)) (justify right bottom))
    )
    (fp_text user "Author: Antmicro" (at -0.939 3.399) (layer "F.Fab") hide
        (effects (font (size 0.7 0.7) (thickness 0.15)) (justify right bottom))
    )
    (fp_text user "License: Apache-2.0" (at -0.939 5.799) (layer "F.Fab") hide
        (effects (font (size 0.7 0.7) (thickness 0.15)) (justify right bottom))
    )
    (fp_rect (start -0.925 -0.47) (end 0.925 0.47)
      (stroke (width 0.05) (type default)) (fill none) (layer "F.CrtYd"))
    (fp_line (start -0.494 -0.25) (end 0.504 -0.25)
      (stroke (width 0.15) (type solid)) (layer "F.Fab"))
    (fp_line (start -0.494 0.248) (end -0.494 -0.25)
      (stroke (width 0.15) (type solid)) (layer "F.Fab"))
    (fp_line (start 0.504 -0.25) (end 0.504 0.248)
      (stroke (width 0.15) (type solid)) (layer "F.Fab"))
    (fp_line (start 0.504 0.248) (end -0.494 0.248)
      (stroke (width 0.15) (type solid)) (layer "F.Fab"))
    (pad "1" smd roundrect (at -0.48 0 180) (size 0.59 0.64) (layers "F.Cu" "F.Paste" "F.Mask") (roundrect_rratio 0.25)
      (net 77 "GNDD") (pintype "passive"))
    (pad "2" smd roundrect (at 0.48 0 180) (size 0.59 0.64) (layers "F.Cu" "F.Paste" "F.Mask") (roundrect_rratio 0.25)
      (net 76 "VCC3V3_USB") (pintype "passive"))
  )

  (footprint "antmicro-footprints:R_0603_1608Metric" (layer "F.Cu")
    (at 165.4 114.8 90)
    (descr "Resistor SMD 0603")
    (tags "resistor SMD 0603")
    (property "Author" "Antmicro")
    (property "Current" "1A")
    (property "License" "Apache-2.0")
    (property "MPN" "CR0603-J/-000ELF")
    (property "Manufacturer" "Bourns")
    (property "Sheetfile" "ftdi-module.kicad_sch")
    (property "Sheetname" "FTDI")
    (property "Tolerance" "")
    (property "Val" "0R")
    (property "ki_description" "Zero Ohm Resistor, Jumper, 0603 [1608 Metric], Thick Film, 100 mW, 1 A, Surface Mount Device, CR")
    (property "ki_keywords" "0603, SMT, RESISTOR, PASSIVE")
    (attr smd)
    (fp_text reference "R4" (at 1.2 0.5 90) (layer "F.SilkS")
        (effects (font (size 0.7 0.7) (thickness 0.15)) (justify left bottom))
    )
    (fp_text value "R_0R_0603" (at 0 1.6 90) (layer "F.Fab")
        (effects (font (size 0.7 0.7) (thickness 0.15)) (justify left bottom))
    )
    (fp_text user "License: Apache-2.0" (at -1.25 5.9 90) (layer "F.Fab") hide
        (effects (font (size 0.7 0.7) (thickness 0.15)) (justify left bottom))
    )
    (fp_text user "${REFERENCE}" (at -1.25 3.898 90) (layer "F.Fab") hide
        (effects (font (size 0.7 0.7) (thickness 0.15)) (justify left bottom))
    )
    (fp_text user "Author: Antmicro" (at -1.25 4.9 90) (layer "F.Fab") hide
        (effects (font (size 0.7 0.7) (thickness 0.15)) (justify left bottom))
    )
    (fp_line (start -0.15 -0.4) (end 0.15 -0.4)
      (stroke (width 0.15) (type solid)) (layer "F.SilkS"))
    (fp_line (start -0.15 0.4) (end 0.15 0.4)
      (stroke (width 0.15) (type solid)) (layer "F.SilkS"))
    (fp_rect (start -1.25 -0.65) (end 1.25 0.65)
      (stroke (width 0.05) (type solid)) (fill none) (layer "F.CrtYd"))
    (fp_rect (start -0.8 -0.4) (end 0.8 0.4)
      (stroke (width 0.15) (type solid)) (fill none) (layer "F.Fab"))
    (pad "1" smd roundrect (at -0.7 0 90) (size 0.8 1) (layers "F.Cu" "F.Paste" "F.Mask") (roundrect_rratio 0.2)
      (net 9 "/FTDI/SDA_FTDI_2") (pintype "passive"))
    (pad "2" smd roundrect (at 0.7 0 90) (size 0.8 1) (layers "F.Cu" "F.Paste" "F.Mask") (roundrect_rratio 0.2)
      (net 80 "SDA_FTDI") (pintype "passive"))
  )

  (footprint "antmicro-footprints:C_0402_1005Metric" (layer "F.Cu")
    (at 174.3 102.05 180)
    (descr "Capacitor SMD 0402")
    (tags "capacitor SMD 0402")
    (property "Author" "Antmicro")
    (property "Dielectric" "X5R")
    (property "License" "Apache-2.0")
    (property "MPN" "GRM155R61H104KE14D")
    (property "Manufacturer" "Murata")
    (property "Sheetfile" "ftdi-module.kicad_sch")
    (property "Sheetname" "FTDI")
    (property "Val" "100n")
    (property "Voltage" "50V")
    (property "ki_description" "SMD Multilayer Ceramic Capacitor, 0.1 µF, 50 V, 0402 [1005 Metric], ± 10%, X5R, GRM Series")
    (property "ki_keywords" "0402, SMT, CAPACITOR, PASSIVE, CERAMIC, MLCC")
    (attr smd)
    (fp_text reference "C18" (at -0.075 0.975 180) (layer "F.SilkS")
        (effects (font (size 0.7 0.7) (thickness 0.15)))
    )
    (fp_text value "C_100n_0402" (at 0 1.17) (layer "F.Fab") hide
        (effects (font (size 1 1) (thickness 0.15)))
    )
    (fp_text user "Author: Antmicro" (at -0.939 3.399 180) (layer "F.Fab") hide
        (effects (font (size 0.7 0.7) (thickness 0.15)) (justify left bottom))
    )
    (fp_text user "${REFERENCE}" (at 0 0) (layer "F.Fab")
        (effects (font (size 0.25 0.25) (thickness 0.04)))
    )
    (fp_text user "License: Apache-2.0" (at -0.939 5.799 180) (layer "F.Fab") hide
        (effects (font (size 0.7 0.7) (thickness 0.15)) (justify left bottom))
    )
    (fp_rect (start -0.925 -0.47) (end 0.925 0.47)
      (stroke (width 0.05) (type default)) (fill none) (layer "F.CrtYd"))
    (fp_line (start -0.494 -0.25) (end 0.504 -0.25)
      (stroke (width 0.15) (type solid)) (layer "F.Fab"))
    (fp_line (start -0.494 0.248) (end -0.494 -0.25)
      (stroke (width 0.15) (type solid)) (layer "F.Fab"))
    (fp_line (start 0.504 -0.25) (end 0.504 0.248)
      (stroke (width 0.15) (type solid)) (layer "F.Fab"))
    (fp_line (start 0.504 0.248) (end -0.494 0.248)
      (stroke (width 0.15) (type solid)) (layer "F.Fab"))
    (pad "1" smd roundrect (at -0.48 0 180) (size 0.59 0.64) (layers "F.Cu" "F.Paste" "F.Mask") (roundrect_rratio 0.25)
      (net 1 "VCC3V3") (pintype "passive"))
    (pad "2" smd roundrect (at 0.48 0 180) (size 0.59 0.64) (layers "F.Cu" "F.Paste" "F.Mask") (roundrect_rratio 0.25)
      (net 4 "GND") (pintype "passive"))
  )

  (footprint "antmicro-footprints:C_0402_1005Metric" (layer "F.Cu")
    (at 155.6 124.7)
    (descr "Capacitor SMD 0402")
    (tags "capacitor SMD 0402")
    (property "Author" "Antmicro")
    (property "Dielectric" "X5R")
    (property "License" "Apache-2.0")
    (property "MPN" "GRM155R61H104KE14D")
    (property "Manufacturer" "Murata")
    (property "Sheetfile" "ftdi-module.kicad_sch")
    (property "Sheetname" "FTDI")
    (property "Val" "100n")
    (property "Voltage" "50V")
    (property "ki_description" "SMD Multilayer Ceramic Capacitor, 0.1 µF, 50 V, 0402 [1005 Metric], ± 10%, X5R, GRM Series")
    (property "ki_keywords" "0402, SMT, CAPACITOR, PASSIVE, CERAMIC, MLCC")
    (zone_connect 1)
    (attr smd)
    (fp_text reference "C8" (at -1.4 1.5) (layer "F.SilkS")
        (effects (font (size 0.7 0.7) (thickness 0.15)) (justify left bottom))
    )
    (fp_text value "C_100n_0402" (at -1.022927 2.155213) (layer "F.Fab")
        (effects (font (size 0.7 0.7) (thickness 0.15)) (justify left bottom))
    )
    (fp_text user "Author: Antmicro" (at -0.939 3.399) (layer "F.Fab") hide
        (effects (font (size 0.7 0.7) (thickness 0.15)) (justify left bottom))
    )
    (fp_text user "License: Apache-2.0" (at -0.939 5.799) (layer "F.Fab") hide
        (effects (font (size 0.7 0.7) (thickness 0.15)) (justify left bottom))
    )
    (fp_text user "${REFERENCE}" (at -0.939 4.599) (layer "F.Fab") hide
        (effects (font (size 0.7 0.7) (thickness 0.15)) (justify left bottom))
    )
    (fp_rect (start -0.925 -0.47) (end 0.925 0.47)
      (stroke (width 0.05) (type default)) (fill none) (layer "F.CrtYd"))
    (fp_line (start -0.494 -0.25) (end 0.504 -0.25)
      (stroke (width 0.15) (type solid)) (layer "F.Fab"))
    (fp_line (start -0.494 0.248) (end -0.494 -0.25)
      (stroke (width 0.15) (type solid)) (layer "F.Fab"))
    (fp_line (start 0.504 -0.25) (end 0.504 0.248)
      (stroke (width 0.15) (type solid)) (layer "F.Fab"))
    (fp_line (start 0.504 0.248) (end -0.494 0.248)
      (stroke (width 0.15) (type solid)) (layer "F.Fab"))
    (pad "1" smd roundrect (at -0.48 0) (size 0.59 0.64) (layers "F.Cu" "F.Paste" "F.Mask") (roundrect_rratio 0.25)
      (net 77 "GNDD") (pintype "passive"))
    (pad "2" smd roundrect (at 0.48 0) (size 0.59 0.64) (layers "F.Cu" "F.Paste" "F.Mask") (roundrect_rratio 0.25)
      (net 7 "1V8_FT") (pintype "passive"))
  )

  (footprint "antmicro-footprints:R_0402_1005Metric" (layer "F.Cu")
    (at 167.3 120.4 180)
    (descr "Resistor SMD 0402")
    (tags "resistor SMD 0402")
    (property "Author" "Antmicro")
    (property "License" "Apache-2.0")
    (property "MPN" "CR0402-FX-1202GLF")
    (property "Manufacturer" "Bourns")
    (property "Sheetfile" "ftdi-module.kicad_sch")
    (property "Sheetname" "FTDI")
    (property "Tolerance" "1%")
    (property "Val" "12k")
    (property "ki_description" "SMD Chip Resistor, 12 kohm, ± 1%, 62.5 mW, 0402 [1005 Metric], Thick Film, General Purpose")
    (property "ki_keywords" "0402, SMT, RESISTOR, PASSIVE")
    (attr smd)
    (fp_text reference "R3" (at 0.8 0.5 180) (layer "F.SilkS")
        (effects (font (size 0.7 0.7) (thickness 0.15)) (justify left bottom))
    )
    (fp_text value "R_12k_0402" (at -1.011843 1.772047 180) (layer "F.Fab")
        (effects (font (size 0.7 0.7) (thickness 0.15)) (justify left bottom))
    )
    (fp_text user "Author: Antmicro" (at -0.95 4.169 180) (layer "F.Fab") hide
        (effects (font (size 0.7 0.7) (thickness 0.15)) (justify left bottom))
    )
    (fp_text user "${REFERENCE}" (at -0.95 3.168 180) (layer "F.Fab") hide
        (effects (font (size 0.7 0.7) (thickness 0.15)) (justify left bottom))
    )
    (fp_text user "License: Apache-2.0" (at -0.95 5.169 180) (layer "F.Fab") hide
        (effects (font (size 0.7 0.7) (thickness 0.15)) (justify left bottom))
    )
    (fp_rect (start -0.925 -0.47) (end 0.925 0.47)
      (stroke (width 0.05) (type default)) (fill none) (layer "F.CrtYd"))
    (fp_rect (start -0.5 -0.25) (end 0.5 0.25)
      (stroke (width 0.15) (type solid)) (fill none) (layer "F.Fab"))
    (pad "1" smd roundrect (at -0.48 0 180) (size 0.59 0.64) (layers "F.Cu" "F.Paste" "F.Mask") (roundrect_rratio 0.25)
      (net 77 "GNDD") (pintype "passive"))
    (pad "2" smd roundrect (at 0.48 0 180) (size 0.59 0.64) (layers "F.Cu" "F.Paste" "F.Mask") (roundrect_rratio 0.25)
      (net 104 "Net-(U5-REF)") (pintype "passive"))
  )

  (footprint "antmicro-footprints:R_0402_1005Metric" (layer "F.Cu")
    (at 169.9 115.1 180)
    (descr "Resistor SMD 0402")
    (tags "resistor SMD 0402")
    (property "Author" "Antmicro")
    (property "License" "Apache-2.0")
    (property "MPN" "CR0402-FX-1001GLF")
    (property "Manufacturer" "Bourns")
    (property "Sheetfile" "ftdi-module.kicad_sch")
    (property "Sheetname" "FTDI")
    (property "Tolerance" "1%")
    (property "Val" "1k")
    (property "ki_description" "SMD Chip Resistor, 1 kohm, ± 1%, 63 mW, 0402 [1005 Metric], Thick Film, General Purpose")
    (property "ki_keywords" "0402, SMT, RESISTOR, PASSIVE")
    (attr smd)
    (fp_text reference "R1" (at 0.75 0.45 180) (layer "F.SilkS")
        (effects (font (size 0.7 0.7) (thickness 0.15)) (justify left bottom))
    )
    (fp_text value "R_1k_0402" (at -1.011843 1.772047 180) (layer "F.Fab")
        (effects (font (size 0.7 0.7) (thickness 0.15)) (justify left bottom))
    )
    (fp_text user "${REFERENCE}" (at -0.95 3.168 180) (layer "F.Fab") hide
        (effects (font (size 0.7 0.7) (thickness 0.15)) (justify left bottom))
    )
    (fp_text user "Author: Antmicro" (at -0.95 4.169 180) (layer "F.Fab") hide
        (effects (font (size 0.7 0.7) (thickness 0.15)) (justify left bottom))
    )
    (fp_text user "License: Apache-2.0" (at -0.95 5.169 180) (layer "F.Fab") hide
        (effects (font (size 0.7 0.7) (thickness 0.15)) (justify left bottom))
    )
    (fp_rect (start -0.925 -0.47) (end 0.925 0.47)
      (stroke (width 0.05) (type default)) (fill none) (layer "F.CrtYd"))
    (fp_rect (start -0.5 -0.25) (end 0.5 0.25)
      (stroke (width 0.15) (type solid)) (fill none) (layer "F.Fab"))
    (pad "1" smd roundrect (at -0.48 0 180) (size 0.59 0.64) (layers "F.Cu" "F.Paste" "F.Mask") (roundrect_rratio 0.25)
      (net 76 "VCC3V3_USB") (pintype "passive"))
    (pad "2" smd roundrect (at 0.48 0 180) (size 0.59 0.64) (layers "F.Cu" "F.Paste" "F.Mask") (roundrect_rratio 0.25)
      (net 31 "/FTDI/FTDI_RST") (pintype "passive"))
  )

  (footprint "antmicro-footprints:R_0402_1005Metric" (layer "F.Cu")
    (at 96.4 137 90)
    (descr "Resistor SMD 0402")
    (tags "resistor SMD 0402")
    (property "Author" "Antmicro")
    (property "Current" "1A")
    (property "DNP" "DNP")
    (property "License" "Apache-2.0")
    (property "MPN" "ERJ2GE0R00X")
    (property "Manufacturer" "Panasonic")
    (property "Sheetfile" "d1600e-psu-breakout-board.kicad_sch")
    (property "Sheetname" "")
    (property "Tolerance" "")
    (property "Val" "0R")
    (property "dnp" "")
    (property "exclude_from_bom" "")
    (property "ki_description" "SMD Chip Resistor, Jumper, 0 ohm, 100 mW, 0402 [1005 Metric], Thick Film, General Purpose")
    (property "ki_keywords" "0402, SMT, RESISTOR, PASSIVE")
    (attr smd exclude_from_bom)
    (fp_text reference "R45" (at -3.2 0.45 90) (layer "F.SilkS")
        (effects (font (size 0.7 0.7) (thickness 0.15)) (justify left bottom))
    )
    (fp_text value "R_0R_0402" (at -1.011843 1.772047 90) (layer "F.Fab")
        (effects (font (size 0.7 0.7) (thickness 0.15)) (justify left bottom))
    )
    (fp_text user "Author: Antmicro" (at -0.95 4.169 90) (layer "F.Fab") hide
        (effects (font (size 0.7 0.7) (thickness 0.15)) (justify left bottom))
    )
    (fp_text user "License: Apache-2.0" (at -0.95 5.169 90) (layer "F.Fab") hide
        (effects (font (size 0.7 0.7) (thickness 0.15)) (justify left bottom))
    )
    (fp_text user "${REFERENCE}" (at -0.95 3.168 90) (layer "F.Fab") hide
        (effects (font (size 0.7 0.7) (thickness 0.15)) (justify left bottom))
    )
    (fp_rect (start -0.925 -0.47) (end 0.925 0.47)
      (stroke (width 0.05) (type default)) (fill none) (layer "F.CrtYd"))
    (fp_rect (start -0.5 -0.25) (end 0.5 0.25)
      (stroke (width 0.15) (type solid)) (fill none) (layer "F.Fab"))
    (pad "1" smd roundrect (at -0.48 0 90) (size 0.59 0.64) (layers "F.Cu" "F.Paste" "F.Mask") (roundrect_rratio 0.25)
      (net 4 "GND") (pintype "passive"))
    (pad "2" smd roundrect (at 0.48 0 90) (size 0.59 0.64) (layers "F.Cu" "F.Paste" "F.Mask") (roundrect_rratio 0.25)
      (net 51 "PSU_ON") (pintype "passive"))
  )

  (footprint "antmicro-footprints:TP_SMD_1mm" (layer "F.Cu")
    (at 123.4 137.4 -90)
    (property "Author" "Antmicro")
    (property "License" "Apache-2.0")
    (property "MPN" "")
    (property "Manufacturer" "")
    (property "Sheetfile" "d1600e-psu-breakout-board.kicad_sch")
    (property "Sheetname" "")
    (property "exclude_from_bom" "")
    (property "ki_description" "Test point 1mm SMD")
    (property "ki_keywords" "TESTPOINT")
    (attr exclude_from_pos_files exclude_from_bom)
    (fp_text reference "TP_S1" (at -0.8 -0.499996 -90) (layer "F.SilkS")
        (effects (font (size 0.7 0.7) (thickness 0.15)) (justify left bottom))
    )
    (fp_text value "TP_1mm_SMD" (at 0 1.4 -90) (layer "F.Fab")
        (effects (font (size 0.7 0.7) (thickness 0.15)) (justify left bottom))
    )
    (fp_text user "${REFERENCE}" (at -0.5 2.8 -90) (layer "F.Fab") hide
        (effects (font (size 0.7 0.7) (thickness 0.15)) (justify left bottom))
    )
    (fp_text user "Author: Antmicro" (at -0.5 4 -90) (layer "F.Fab") hide
        (effects (font (size 0.7 0.7) (thickness 0.15)) (justify left bottom))
    )
    (fp_text user "License: Apache-2.0" (at -0.5 5.2 -90) (layer "F.Fab") hide
        (effects (font (size 0.7 0.7) (thickness 0.15)) (justify left bottom))
    )
    (fp_circle (center 0 0) (end 0.6 0)
      (stroke (width 0.05) (type default)) (fill none) (layer "F.CrtYd"))
    (pad "1" smd circle (at 0 0 270) (size 1 1) (layers "F.Cu" "F.Mask")
      (net 64 "Net-(J10-PadS1)") (pinfunction "1") (pintype "passive"))
  )

  (footprint "antmicro-footprints:TP_SMD_1mm" (layer "F.Cu")
    (at 120.85 137.4 -90)
    (property "Author" "Antmicro")
    (property "License" "Apache-2.0")
    (property "MPN" "")
    (property "Manufacturer" "")
    (property "Sheetfile" "d1600e-psu-breakout-board.kicad_sch")
    (property "Sheetname" "")
    (property "exclude_from_bom" "")
    (property "ki_description" "Test point 1mm SMD")
    (property "ki_keywords" "TESTPOINT")
    (attr exclude_from_pos_files exclude_from_bom)
    (fp_text reference "TP_S3" (at -0.745801 -0.401591 -90) (layer "F.SilkS")
        (effects (font (size 0.7 0.7) (thickness 0.15)) (justify left bottom))
    )
    (fp_text value "TP_1mm_SMD" (at 0 1.4 -90) (layer "F.Fab")
        (effects (font (size 0.7 0.7) (thickness 0.15)) (justify left bottom))
    )
    (fp_text user "Author: Antmicro" (at -0.5 4 -90) (layer "F.Fab") hide
        (effects (font (size 0.7 0.7) (thickness 0.15)) (justify left bottom))
    )
    (fp_text user "License: Apache-2.0" (at -0.5 5.2 -90) (layer "F.Fab") hide
        (effects (font (size 0.7 0.7) (thickness 0.15)) (justify left bottom))
    )
    (fp_text user "${REFERENCE}" (at -0.5 2.8 -90) (layer "F.Fab") hide
        (effects (font (size 0.7 0.7) (thickness 0.15)) (justify left bottom))
    )
    (fp_circle (center 0 0) (end 0.6 0)
      (stroke (width 0.05) (type default)) (fill none) (layer "F.CrtYd"))
    (pad "1" smd circle (at 0 0 270) (size 1 1) (layers "F.Cu" "F.Mask")
      (net 66 "Net-(J10-PadS3)") (pinfunction "1") (pintype "passive"))
  )

  (footprint "antmicro-footprints:TP_SMD_1mm" (layer "F.Cu")
    (at 122.1 137.4 -90)
    (property "Author" "Antmicro")
    (property "License" "Apache-2.0")
    (property "MPN" "")
    (property "Manufacturer" "")
    (property "Sheetfile" "d1600e-psu-breakout-board.kicad_sch")
    (property "Sheetname" "")
    (property "exclude_from_bom" "")
    (property "ki_description" "Test point 1mm SMD")
    (property "ki_keywords" "TESTPOINT")
    (attr exclude_from_pos_files exclude_from_bom)
    (fp_text reference "TP_S2" (at -0.745801 -0.466104 -90) (layer "F.SilkS")
        (effects (font (size 0.7 0.7) (thickness 0.15)) (justify left bottom))
    )
    (fp_text value "TP_1mm_SMD" (at 0 1.4 -90) (layer "F.Fab")
        (effects (font (size 0.7 0.7) (thickness 0.15)) (justify left bottom))
    )
    (fp_text user "License: Apache-2.0" (at -0.5 5.2 -90) (layer "F.Fab") hide
        (effects (font (size 0.7 0.7) (thickness 0.15)) (justify left bottom))
    )
    (fp_text user "Author: Antmicro" (at -0.5 4 -90) (layer "F.Fab") hide
        (effects (font (size 0.7 0.7) (thickness 0.15)) (justify left bottom))
    )
    (fp_text user "${REFERENCE}" (at -0.5 2.8 -90) (layer "F.Fab") hide
        (effects (font (size 0.7 0.7) (thickness 0.15)) (justify left bottom))
    )
    (fp_circle (center 0 0) (end 0.6 0)
      (stroke (width 0.05) (type default)) (fill none) (layer "F.CrtYd"))
    (pad "1" smd circle (at 0 0 270) (size 1 1) (layers "F.Cu" "F.Mask")
      (net 65 "Net-(J10-PadS2)") (pinfunction "1") (pintype "passive"))
  )

  (footprint "antmicro-footprints:TP_SMD_1mm" (layer "F.Cu")
    (at 119.6 137.4 -90)
    (property "Author" "Antmicro")
    (property "License" "Apache-2.0")
    (property "MPN" "")
    (property "Manufacturer" "")
    (property "Sheetfile" "d1600e-psu-breakout-board.kicad_sch")
    (property "Sheetname" "")
    (property "exclude_from_bom" "")
    (property "ki_description" "Test point 1mm SMD")
    (property "ki_keywords" "TESTPOINT")
    (attr exclude_from_pos_files exclude_from_bom)
    (fp_text reference "TP_S4" (at -0.745801 -0.337078 -90) (layer "F.SilkS")
        (effects (font (size 0.7 0.7) (thickness 0.15)) (justify left bottom))
    )
    (fp_text value "TP_1mm_SMD" (at 0 1.4 -90) (layer "F.Fab")
        (effects (font (size 0.7 0.7) (thickness 0.15)) (justify left bottom))
    )
    (fp_text user "Author: Antmicro" (at -0.5 4 -90) (layer "F.Fab") hide
        (effects (font (size 0.7 0.7) (thickness 0.15)) (justify left bottom))
    )
    (fp_text user "${REFERENCE}" (at -0.5 2.8 -90) (layer "F.Fab") hide
        (effects (font (size 0.7 0.7) (thickness 0.15)) (justify left bottom))
    )
    (fp_text user "License: Apache-2.0" (at -0.5 5.2 -90) (layer "F.Fab") hide
        (effects (font (size 0.7 0.7) (thickness 0.15)) (justify left bottom))
    )
    (fp_circle (center 0 0) (end 0.6 0)
      (stroke (width 0.05) (type default)) (fill none) (layer "F.CrtYd"))
    (pad "1" smd circle (at 0 0 270) (size 1 1) (layers "F.Cu" "F.Mask")
      (net 67 "Net-(J10-PadS4)") (pinfunction "1") (pintype "passive"))
  )

  (footprint "antmicro-footprints:TP_SMD_1mm" (layer "F.Cu")
    (at 114.4 137.4 -90)
    (property "Author" "Antmicro")
    (property "License" "Apache-2.0")
    (property "MPN" "")
    (property "Manufacturer" "")
    (property "Sheetfile" "d1600e-psu-breakout-board.kicad_sch")
    (property "Sheetname" "")
    (property "exclude_from_bom" "")
    (property "ki_description" "Test point 1mm SMD")
    (property "ki_keywords" "TESTPOINT")
    (attr exclude_from_pos_files exclude_from_bom)
    (fp_text reference "TP_S8" (at -0.745801 -0.35 -90) (layer "F.SilkS")
        (effects (font (size 0.7 0.7) (thickness 0.15)) (justify left bottom))
    )
    (fp_text value "TP_1mm_SMD" (at 0 1.4 -90) (layer "F.Fab")
        (effects (font (size 0.7 0.7) (thickness 0.15)) (justify left bottom))
    )
    (fp_text user "Author: Antmicro" (at -0.5 4 -90) (layer "F.Fab") hide
        (effects (font (size 0.7 0.7) (thickness 0.15)) (justify left bottom))
    )
    (fp_text user "License: Apache-2.0" (at -0.5 5.2 -90) (layer "F.Fab") hide
        (effects (font (size 0.7 0.7) (thickness 0.15)) (justify left bottom))
    )
    (fp_text user "${REFERENCE}" (at -0.5 2.8 -90) (layer "F.Fab") hide
        (effects (font (size 0.7 0.7) (thickness 0.15)) (justify left bottom))
    )
    (fp_circle (center 0 0) (end 0.6 0)
      (stroke (width 0.05) (type default)) (fill none) (layer "F.CrtYd"))
    (pad "1" smd circle (at 0 0 270) (size 1 1) (layers "F.Cu" "F.Mask")
      (net 63 "Net-(J10-PadS8)") (pinfunction "1") (pintype "passive"))
  )

  (footprint "antmicro-footprints:TP_SMD_1mm" (layer "F.Cu")
    (at 115.625 137.425 -90)
    (property "Author" "Antmicro")
    (property "License" "Apache-2.0")
    (property "MPN" "")
    (property "Manufacturer" "")
    (property "Sheetfile" "d1600e-psu-breakout-board.kicad_sch")
    (property "Sheetname" "")
    (property "exclude_from_bom" "")
    (property "ki_description" "Test point 1mm SMD")
    (property "ki_keywords" "TESTPOINT")
    (attr exclude_from_pos_files exclude_from_bom)
    (fp_text reference "TP_S7" (at -0.725 -0.525 -90) (layer "F.SilkS")
        (effects (font (size 0.7 0.7) (thickness 0.15)) (justify left bottom))
    )
    (fp_text value "TP_1mm_SMD" (at 0 1.4 -90) (layer "F.Fab")
        (effects (font (size 0.7 0.7) (thickness 0.15)) (justify left bottom))
    )
    (fp_text user "Author: Antmicro" (at -0.5 4 -90) (layer "F.Fab") hide
        (effects (font (size 0.7 0.7) (thickness 0.15)) (justify left bottom))
    )
    (fp_text user "${REFERENCE}" (at -0.5 2.8 -90) (layer "F.Fab") hide
        (effects (font (size 0.7 0.7) (thickness 0.15)) (justify left bottom))
    )
    (fp_text user "License: Apache-2.0" (at -0.5 5.2 -90) (layer "F.Fab") hide
        (effects (font (size 0.7 0.7) (thickness 0.15)) (justify left bottom))
    )
    (fp_circle (center 0 0) (end 0.6 0)
      (stroke (width 0.05) (type default)) (fill none) (layer "F.CrtYd"))
    (pad "1" smd circle (at 0 0 270) (size 1 1) (layers "F.Cu" "F.Mask")
      (net 62 "Net-(J10-PadS7)") (pinfunction "1") (pintype "passive"))
  )

  (footprint "antmicro-footprints:TP_SMD_1mm" (layer "F.Cu")
    (at 118.3 137.4 -90)
    (property "Author" "Antmicro")
    (property "License" "Apache-2.0")
    (property "MPN" "")
    (property "Manufacturer" "")
    (property "Sheetfile" "d1600e-psu-breakout-board.kicad_sch")
    (property "Sheetname" "")
    (property "exclude_from_bom" "")
    (property "ki_description" "Test point 1mm SMD")
    (property "ki_keywords" "TESTPOINT")
    (attr exclude_from_pos_files exclude_from_bom)
    (fp_text reference "TP_S5" (at -0.745801 -0.322565 -90) (layer "F.SilkS")
        (effects (font (size 0.7 0.7) (thickness 0.15)) (justify left bottom))
    )
    (fp_text value "TP_1mm_SMD" (at 0 1.4 -90) (layer "F.Fab")
        (effects (font (size 0.7 0.7) (thickness 0.15)) (justify left bottom))
    )
    (fp_text user "Author: Antmicro" (at -0.5 4 -90) (layer "F.Fab") hide
        (effects (font (size 0.7 0.7) (thickness 0.15)) (justify left bottom))
    )
    (fp_text user "License: Apache-2.0" (at -0.5 5.2 -90) (layer "F.Fab") hide
        (effects (font (size 0.7 0.7) (thickness 0.15)) (justify left bottom))
    )
    (fp_text user "${REFERENCE}" (at -0.5 2.8 -90) (layer "F.Fab") hide
        (effects (font (size 0.7 0.7) (thickness 0.15)) (justify left bottom))
    )
    (fp_circle (center 0 0) (end 0.6 0)
      (stroke (width 0.05) (type default)) (fill none) (layer "F.CrtYd"))
    (pad "1" smd circle (at 0 0 270) (size 1 1) (layers "F.Cu" "F.Mask")
      (net 60 "Net-(J10-PadS5)") (pinfunction "1") (pintype "passive"))
  )

  (footprint "antmicro-footprints:TP_SMD_1mm" (layer "F.Cu")
    (at 117 137.4 -90)
    (property "Author" "Antmicro")
    (property "License" "Apache-2.0")
    (property "MPN" "")
    (property "Manufacturer" "")
    (property "Sheetfile" "d1600e-psu-breakout-board.kicad_sch")
    (property "Sheetname" "")
    (property "exclude_from_bom" "")
    (property "ki_description" "Test point 1mm SMD")
    (property "ki_keywords" "TESTPOINT")
    (attr exclude_from_pos_files exclude_from_bom)
    (fp_text reference "TP_S6" (at -0.745801 -0.308052 -90) (layer "F.SilkS")
        (effects (font (size 0.7 0.7) (thickness 0.15)) (justify left bottom))
    )
    (fp_text value "TP_1mm_SMD" (at 0 1.4 -90) (layer "F.Fab")
        (effects (font (size 0.7 0.7) (thickness 0.15)) (justify left bottom))
    )
    (fp_text user "${REFERENCE}" (at -0.5 2.8 -90) (layer "F.Fab") hide
        (effects (font (size 0.7 0.7) (thickness 0.15)) (justify left bottom))
    )
    (fp_text user "License: Apache-2.0" (at -0.5 5.2 -90) (layer "F.Fab") hide
        (effects (font (size 0.7 0.7) (thickness 0.15)) (justify left bottom))
    )
    (fp_text user "Author: Antmicro" (at -0.5 4 -90) (layer "F.Fab") hide
        (effects (font (size 0.7 0.7) (thickness 0.15)) (justify left bottom))
    )
    (fp_circle (center 0 0) (end 0.6 0)
      (stroke (width 0.05) (type default)) (fill none) (layer "F.CrtYd"))
    (pad "1" smd circle (at 0 0 270) (size 1 1) (layers "F.Cu" "F.Mask")
      (net 61 "Net-(J10-PadS6)") (pinfunction "1") (pintype "passive"))
  )

  (footprint "antmicro-footprints:TP_SMD_1mm" (layer "F.Cu")
    (at 107 136.5508)
    (property "Author" "Antmicro")
    (property "License" "Apache-2.0")
    (property "MPN" "")
    (property "Manufacturer" "")
    (property "Sheetfile" "d1600e-psu-breakout-board.kicad_sch")
    (property "Sheetname" "")
    (property "exclude_from_bom" "")
    (property "ki_description" "Test point 1mm SMD")
    (property "ki_keywords" "TESTPOINT")
    (attr exclude_from_pos_files exclude_from_bom)
    (fp_text reference "TP_S_ON1" (at 0.3 -0.4508 90) (layer "F.SilkS")
        (effects (font (size 0.7 0.7) (thickness 0.15)) (justify left bottom))
    )
    (fp_text value "TP_1mm_SMD" (at 0 1.4) (layer "F.Fab")
        (effects (font (size 0.7 0.7) (thickness 0.15)) (justify left bottom))
    )
    (fp_text user "Author: Antmicro" (at -0.5 4) (layer "F.Fab") hide
        (effects (font (size 0.7 0.7) (thickness 0.15)) (justify left bottom))
    )
    (fp_text user "License: Apache-2.0" (at -0.5 5.2) (layer "F.Fab") hide
        (effects (font (size 0.7 0.7) (thickness 0.15)) (justify left bottom))
    )
    (fp_text user "${REFERENCE}" (at -0.5 2.8) (layer "F.Fab") hide
        (effects (font (size 0.7 0.7) (thickness 0.15)) (justify left bottom))
    )
    (fp_circle (center 0 0) (end 0.6 0)
      (stroke (width 0.05) (type default)) (fill none) (layer "F.CrtYd"))
    (pad "1" smd circle (at 0 0) (size 1 1) (layers "F.Cu" "F.Mask")
      (net 51 "PSU_ON") (pinfunction "1") (pintype "passive"))
  )

  (footprint "antmicro-footprints:TP_SMD_1mm" (layer "F.Cu")
    (at 172.45 115.1)
    (property "Author" "Antmicro")
    (property "License" "Apache-2.0")
    (property "MPN" "")
    (property "Manufacturer" "")
    (property "Sheetfile" "ftdi-module.kicad_sch")
    (property "Sheetname" "FTDI")
    (property "exclude_from_bom" "")
    (property "ki_description" "Test point 1mm SMD")
    (property "ki_keywords" "TESTPOINT")
    (attr exclude_from_pos_files exclude_from_bom)
    (fp_text reference "SCL_FTDI1" (at 0.55 0.1) (layer "F.SilkS")
        (effects (font (size 0.7 0.7) (thickness 0.15)) (justify left bottom))
    )
    (fp_text value "TP_1mm_SMD" (at 0 1.4) (layer "F.Fab")
        (effects (font (size 0.7 0.7) (thickness 0.15)) (justify left bottom))
    )
    (fp_text user "License: Apache-2.0" (at -0.5 5.2) (layer "F.Fab") hide
        (effects (font (size 0.7 0.7) (thickness 0.15)) (justify left bottom))
    )
    (fp_text user "${REFERENCE}" (at -0.5 2.8) (layer "F.Fab") hide
        (effects (font (size 0.7 0.7) (thickness 0.15)) (justify left bottom))
    )
    (fp_text user "Author: Antmicro" (at -0.5 4) (layer "F.Fab") hide
        (effects (font (size 0.7 0.7) (thickness 0.15)) (justify left bottom))
    )
    (fp_circle (center 0 0) (end 0.6 0)
      (stroke (width 0.05) (type default)) (fill none) (layer "F.CrtYd"))
    (pad "1" smd circle (at 0 0) (size 1 1) (layers "F.Cu" "F.Mask")
      (net 81 "SCL_FTDI") (pinfunction "1") (pintype "passive"))
  )

  (footprint "antmicro-footprints:TP_SMD_1mm" (layer "F.Cu")
    (at 172.05 112.6)
    (property "Author" "Antmicro")
    (property "License" "Apache-2.0")
    (property "MPN" "")
    (property "Manufacturer" "")
    (property "Sheetfile" "ftdi-module.kicad_sch")
    (property "Sheetname" "FTDI")
    (property "exclude_from_bom" "")
    (property "ki_description" "Test point 1mm SMD")
    (property "ki_keywords" "TESTPOINT")
    (attr exclude_from_pos_files exclude_from_bom)
    (fp_text reference "SDA_FTDI1" (at 0.2 1.45) (layer "F.SilkS")
        (effects (font (size 0.7 0.7) (thickness 0.15)) (justify left bottom))
    )
    (fp_text value "TP_1mm_SMD" (at 0 1.4) (layer "F.Fab")
        (effects (font (size 0.7 0.7) (thickness 0.15)) (justify left bottom))
    )
    (fp_text user "License: Apache-2.0" (at -0.5 5.2) (layer "F.Fab") hide
        (effects (font (size 0.7 0.7) (thickness 0.15)) (justify left bottom))
    )
    (fp_text user "${REFERENCE}" (at -0.5 2.8) (layer "F.Fab") hide
        (effects (font (size 0.7 0.7) (thickness 0.15)) (justify left bottom))
    )
    (fp_text user "Author: Antmicro" (at -0.5 4) (layer "F.Fab") hide
        (effects (font (size 0.7 0.7) (thickness 0.15)) (justify left bottom))
    )
    (fp_circle (center 0 0) (end 0.6 0)
      (stroke (width 0.05) (type default)) (fill none) (layer "F.CrtYd"))
    (pad "1" smd circle (at 0 0) (size 1 1) (layers "F.Cu" "F.Mask")
      (net 80 "SDA_FTDI") (pinfunction "1") (pintype "passive"))
  )

  (footprint "antmicro-footprints:TP_SMD_1mm" (layer "F.Cu")
    (at 111.65 137.4 -90)
    (property "Author" "Antmicro")
    (property "License" "Apache-2.0")
    (property "MPN" "")
    (property "Manufacturer" "")
    (property "Sheetfile" "d1600e-psu-breakout-board.kicad_sch")
    (property "Sheetname" "")
    (property "exclude_from_bom" "")
    (property "ki_description" "Test point 1mm SMD")
    (property "ki_keywords" "TESTPOINT")
    (attr exclude_from_pos_files exclude_from_bom)
    (fp_text reference "TP_S10" (at -0.45 -0.4 -90) (layer "F.SilkS")
        (effects (font (size 0.7 0.7) (thickness 0.15)) (justify left bottom))
    )
    (fp_text value "TP_1mm_SMD" (at 0 1.4 -90) (layer "F.Fab")
        (effects (font (size 0.7 0.7) (thickness 0.15)) (justify left bottom))
    )
    (fp_text user "${REFERENCE}" (at -0.5 2.8 -90) (layer "F.Fab") hide
        (effects (font (size 0.7 0.7) (thickness 0.15)) (justify left bottom))
    )
    (fp_text user "Author: Antmicro" (at -0.5 4 -90) (layer "F.Fab") hide
        (effects (font (size 0.7 0.7) (thickness 0.15)) (justify left bottom))
    )
    (fp_text user "License: Apache-2.0" (at -0.5 5.2 -90) (layer "F.Fab") hide
        (effects (font (size 0.7 0.7) (thickness 0.15)) (justify left bottom))
    )
    (fp_circle (center 0 0) (end 0.6 0)
      (stroke (width 0.05) (type default)) (fill none) (layer "F.CrtYd"))
    (pad "1" smd circle (at 0 0 270) (size 1 1) (layers "F.Cu" "F.Mask")
      (net 58 "Net-(J10-PadS10)") (pinfunction "1") (pintype "passive"))
  )

  (footprint "antmicro-footprints:TP_SMD_1mm" (layer "F.Cu")
    (at 113.05 137.4 -90)
    (property "Author" "Antmicro")
    (property "License" "Apache-2.0")
    (property "MPN" "")
    (property "Manufacturer" "")
    (property "Sheetfile" "d1600e-psu-breakout-board.kicad_sch")
    (property "Sheetname" "")
    (property "exclude_from_bom" "")
    (property "ki_description" "Test point 1mm SMD")
    (property "ki_keywords" "TESTPOINT")
    (attr exclude_from_pos_files exclude_from_bom)
    (fp_text reference "TP_S9" (at -0.745801 -0.314513 -90) (layer "F.SilkS")
        (effects (font (size 0.7 0.7) (thickness 0.15)) (justify left bottom))
    )
    (fp_text value "TP_1mm_SMD" (at 0 1.4 -90) (layer "F.Fab")
        (effects (font (size 0.7 0.7) (thickness 0.15)) (justify left bottom))
    )
    (fp_text user "${REFERENCE}" (at -0.5 2.8 -90) (layer "F.Fab") hide
        (effects (font (size 0.7 0.7) (thickness 0.15)) (justify left bottom))
    )
    (fp_text user "Author: Antmicro" (at -0.5 4 -90) (layer "F.Fab") hide
        (effects (font (size 0.7 0.7) (thickness 0.15)) (justify left bottom))
    )
    (fp_text user "License: Apache-2.0" (at -0.5 5.2 -90) (layer "F.Fab") hide
        (effects (font (size 0.7 0.7) (thickness 0.15)) (justify left bottom))
    )
    (fp_circle (center 0 0) (end 0.6 0)
      (stroke (width 0.05) (type default)) (fill none) (layer "F.CrtYd"))
    (pad "1" smd circle (at 0 0 270) (size 1 1) (layers "F.Cu" "F.Mask")
      (net 59 "Net-(J10-PadS9)") (pinfunction "1") (pintype "passive"))
  )

  (footprint "antmicro-footprints:R_0402_1005Metric" (layer "F.Cu")
    (at 177.35 92)
    (descr "Resistor SMD 0402")
    (tags "resistor SMD 0402")
    (property "Author" "Antmicro")
    (property "DNP" "DNP")
    (property "License" "Apache-2.0")
    (property "MPN" "CR0402-FX-1002GLF")
    (property "Manufacturer" "Bourns")
    (property "Sheetfile" "power-switch.kicad_sch")
    (property "Sheetname" "Power switch 5")
    (property "Tolerance" "1%")
    (property "Val" "10k")
    (property "dnp" "")
    (property "exclude_from_bom" "")
    (property "ki_description" "SMD Chip Resistor, 10 kohm, ± 1%, 62.5 mW, 0402 [1005 Metric], Thick Film, General Purpose")
    (property "ki_keywords" "0402, SMT, RESISTOR, PASSIVE")
    (attr smd exclude_from_bom)
    (fp_text reference "R48" (at -0.05 1.05) (layer "F.SilkS")
        (effects (font (size 0.7 0.7) (thickness 0.15)))
    )
    (fp_text value "R_10k_0402" (at 0 1.17) (layer "F.Fab") hide
        (effects (font (size 1 1) (thickness 0.15)))
    )
    (fp_text user "Author: Antmicro" (at -0.95 4.169) (layer "F.Fab") hide
        (effects (font (size 0.7 0.7) (thickness 0.15)) (justify left bottom))
    )
    (fp_text user "${REFERENCE}" (at 0 0) (layer "F.Fab")
        (effects (font (size 0.25 0.25) (thickness 0.04)))
    )
    (fp_text user "License: Apache-2.0" (at -0.95 5.169) (layer "F.Fab") hide
        (effects (font (size 0.7 0.7) (thickness 0.15)) (justify left bottom))
    )
    (fp_rect (start -0.925 -0.47) (end 0.925 0.47)
      (stroke (width 0.05) (type default)) (fill none) (layer "F.CrtYd"))
    (fp_rect (start -0.5 -0.25) (end 0.5 0.25)
      (stroke (width 0.15) (type solid)) (fill none) (layer "F.Fab"))
    (pad "1" smd roundrect (at -0.48 0) (size 0.59 0.64) (layers "F.Cu" "F.Paste" "F.Mask") (roundrect_rratio 0.25)
      (net 26 "/Power Cycling & Current Measurement/PC_5") (pintype "passive"))
    (pad "2" smd roundrect (at 0.48 0) (size 0.59 0.64) (layers "F.Cu" "F.Paste" "F.Mask") (roundrect_rratio 0.25)
      (net 4 "GND") (pintype "passive"))
  )

  (footprint "antmicro-footprints:Conn_Molex_KK_1x4_22-27-2041" (layer "F.Cu")
    (at 99.91 54.15)
    (property "Author" "Antmicro")
    (property "License" "Apache-2.0")
    (property "MPN" "22-27-2041")
    (property "Manufacturer" "Molex")
    (property "Sheetfile" "d1600e-psu-breakout-board.kicad_sch")
    (property "Sheetname" "")
    (property "ki_description" "Rectangular connector (header, female pins)")
    (property "ki_keywords" "VERTICAL, THT, HEADER, CONNECTOR, MALE")
    (attr through_hole)
    (fp_text reference "J1" (at 2.165 4.3) (layer "F.SilkS")
        (effects (font (size 0.7 0.7) (thickness 0.15)) (justify left bottom))
    )
    (fp_text value "Molex_KK_1x4_22-27-2041" (at -0.8 4.6 180) (layer "F.Fab")
        (effects (font (size 0.7 0.7) (thickness 0.15)) (justify left bottom))
    )
    (fp_text user "${REFERENCE}" (at -2.12 9.15) (layer "F.Fab") hide
        (effects (font (size 0.7 0.7) (thickness 0.15)) (justify left bottom))
    )
    (fp_text user "Author: Antmicro" (at -2.12 6.75) (layer "F.Fab") hide
        (effects (font (size 0.7 0.7) (thickness 0.15)) (justify left bottom))
    )
    (fp_text user "License: Apache-2.0" (at -2.12 7.95) (layer "F.Fab") hide
        (effects (font (size 0.7 0.7) (thickness 0.15)) (justify left bottom))
    )
    (fp_line (start -1.39 -3.03) (end -1.39 2.99)
      (stroke (width 0.15) (type solid)) (layer "F.SilkS"))
    (fp_line (start -1.39 2.99) (end 8.99 2.99)
      (stroke (width 0.15) (type solid)) (layer "F.SilkS"))
    (fp_line (start -0.81 -3.03) (end -0.81 -2.43)
      (stroke (width 0.15) (type solid)) (layer "F.SilkS"))
    (fp_line (start -0.81 -2.43) (end 0.79 -2.43)
      (stroke (width 0.15) (type solid)) (layer "F.SilkS"))
    (fp_line (start -0.01 1.99) (end 0.24 1.46)
      (stroke (width 0.15) (type solid)) (layer "F.SilkS"))
    (fp_line (start -0.01 1.99) (end 7.61 1.99)
      (stroke (width 0.15) (type solid)) (layer "F.SilkS"))
    (fp_line (start -0.01 2.99) (end -0.01 1.99)
      (stroke (width 0.15) (type solid)) (layer "F.SilkS"))
    (fp_line (start 0.24 1.46) (end 7.36 1.46)
      (stroke (width 0.15) (type solid)) (layer "F.SilkS"))
    (fp_line (start 0.24 2.99) (end 0.24 1.99)
      (stroke (width 0.15) (type solid)) (layer "F.SilkS"))
    (fp_line (start 0.79 -2.43) (end 0.79 -3.03)
      (stroke (width 0.15) (type solid)) (layer "F.SilkS"))
    (fp_line (start 1.73 -3.03) (end 1.73 -2.43)
      (stroke (width 0.15) (type solid)) (layer "F.SilkS"))
    (fp_line (start 1.73 -2.43) (end 3.33 -2.43)
      (stroke (width 0.15) (type solid)) (layer "F.SilkS"))
    (fp_line (start 3.33 -2.43) (end 3.33 -3.03)
      (stroke (width 0.15) (type solid)) (layer "F.SilkS"))
    (fp_line (start 4.27 -3.03) (end 4.27 -2.43)
      (stroke (width 0.15) (type solid)) (layer "F.SilkS"))
    (fp_line (start 4.27 -2.43) (end 5.87 -2.43)
      (stroke (width 0.15) (type solid)) (layer "F.SilkS"))
    (fp_line (start 5.87 -2.43) (end 5.87 -3.03)
      (stroke (width 0.15) (type solid)) (layer "F.SilkS"))
    (fp_line (start 6.81 -3.03) (end 6.81 -2.43)
      (stroke (width 0.15) (type solid)) (layer "F.SilkS"))
    (fp_line (start 6.81 -2.43) (end 8.41 -2.43)
      (stroke (width 0.15) (type solid)) (layer "F.SilkS"))
    (fp_line (start 7.36 1.46) (end 7.61 1.99)
      (stroke (width 0.15) (type solid)) (layer "F.SilkS"))
    (fp_line (start 7.36 2.99) (end 7.36 1.99)
      (stroke (width 0.15) (type solid)) (layer "F.SilkS"))
    (fp_line (start 7.61 1.99) (end 7.61 2.99)
      (stroke (width 0.15) (type solid)) (layer "F.SilkS"))
    (fp_line (start 8.41 -2.43) (end 8.41 -3.03)
      (stroke (width 0.15) (type solid)) (layer "F.SilkS"))
    (fp_line (start 8.99 -3.03) (end -1.39 -3.03)
      (stroke (width 0.15) (type solid)) (layer "F.SilkS"))
    (fp_line (start 8.99 2.99) (end 8.99 -3.03)
      (stroke (width 0.15) (type solid)) (layer "F.SilkS"))
    (fp_line (start -1.79 -3.38) (end -1.79 3.42)
      (stroke (width 0.05) (type solid)) (layer "F.CrtYd"))
    (fp_line (start -1.79 3.42) (end 9.37 3.42)
      (stroke (width 0.05) (type solid)) (layer "F.CrtYd"))
    (fp_line (start 9.37 -3.38) (end -1.79 -3.38)
      (stroke (width 0.05) (type solid)) (layer "F.CrtYd"))
    (fp_line (start 9.37 3.42) (end 9.37 -3.38)
      (stroke (width 0.05) (type solid)) (layer "F.CrtYd"))
    (fp_line (start -1.29 -2.88) (end -1.29 2.92)
      (stroke (width 0.15) (type solid)) (layer "F.Fab"))
    (fp_line (start -1.29 2.92) (end 8.87 2.92)
      (stroke (width 0.15) (type solid)) (layer "F.Fab"))
    (fp_line (start 8.163 0) (end 8.87 -0.5)
      (stroke (width 0.15) (type solid)) (layer "F.Fab"))
    (fp_line (start 8.87 -2.88) (end -1.29 -2.88)
      (stroke (width 0.15) (type solid)) (layer "F.Fab"))
    (fp_line (start 8.87 0.5) (end 8.163 0)
      (stroke (width 0.15) (type solid)) (layer "F.Fab"))
    (fp_line (start 8.87 2.92) (end 8.87 -2.88)
      (stroke (width 0.15) (type solid)) (layer "F.Fab"))
    (pad "1" thru_hole roundrect (at 0 0) (size 1.74 2.19) (drill 1.19) (layers "*.Cu" "*.Mask") (roundrect_rratio 0.143678)
      (net 11 "VCC12V0") (pintype "passive"))
    (pad "2" thru_hole oval (at 2.54 0) (size 1.74 2.19) (drill 1.19) (layers "*.Cu" "*.Mask")
      (net 4 "GND") (pintype "passive"))
    (pad "3" thru_hole oval (at 5.08 0) (size 1.74 2.19) (drill 1.19) (layers "*.Cu" "*.Mask")
      (net 4 "GND") (pintype "passive"))
    (pad "4" thru_hole oval (at 7.62 0) (size 1.74 2.19) (drill 1.19) (layers "*.Cu" "*.Mask")
      (net 2 "VCC5V0") (pintype "passive"))
  )

  (footprint "antmicro-footprints:R_0402_1005Metric" (layer "F.Cu")
    (at 179.85 100.12)
    (descr "Resistor SMD 0402")
    (tags "resistor SMD 0402")
    (property "Author" "Antmicro")
    (property "Current" "1A")
    (property "DNP" "DNP")
    (property "License" "Apache-2.0")
    (property "MPN" "ERJ2GE0R00X")
    (property "Manufacturer" "Panasonic")
    (property "Sheetfile" "d1600e-psu-breakout-board.kicad_sch")
    (property "Sheetname" "")
    (property "Tolerance" "")
    (property "Val" "0R")
    (property "dnp" "")
    (property "exclude_from_bom" "")
    (property "ki_description" "SMD Chip Resistor, Jumper, 0 ohm, 100 mW, 0402 [1005 Metric], Thick Film, General Purpose")
    (property "ki_keywords" "0402, SMT, RESISTOR, PASSIVE")
    (attr smd exclude_from_bom)
    (fp_text reference "R71" (at -1.122484 -0.772697) (layer "F.SilkS")
        (effects (font (size 0.7 0.7) (thickness 0.15)) (justify left bottom))
    )
    (fp_text value "R_0R_0402" (at -1.011843 1.772047) (layer "F.Fab")
        (effects (font (size 0.7 0.7) (thickness 0.15)) (justify left bottom))
    )
    (fp_text user "License: Apache-2.0" (at -0.95 5.169) (layer "F.Fab") hide
        (effects (font (size 0.7 0.7) (thickness 0.15)) (justify left bottom))
    )
    (fp_text user "Author: Antmicro" (at -0.95 4.169) (layer "F.Fab") hide
        (effects (font (size 0.7 0.7) (thickness 0.15)) (justify left bottom))
    )
    (fp_text user "${REFERENCE}" (at -0.95 3.168) (layer "F.Fab") hide
        (effects (font (size 0.7 0.7) (thickness 0.15)) (justify left bottom))
    )
    (fp_rect (start -0.925 -0.47) (end 0.925 0.47)
      (stroke (width 0.05) (type default)) (fill none) (layer "F.CrtYd"))
    (fp_rect (start -0.5 -0.25) (end 0.5 0.25)
      (stroke (width 0.15) (type solid)) (fill none) (layer "F.Fab"))
    (pad "1" smd roundrect (at -0.48 0) (size 0.59 0.64) (layers "F.Cu" "F.Paste" "F.Mask") (roundrect_rratio 0.25)
      (net 18 "SDA") (pintype "passive"))
    (pad "2" smd roundrect (at 0.48 0) (size 0.59 0.64) (layers "F.Cu" "F.Paste" "F.Mask") (roundrect_rratio 0.25)
      (net 99 "SDA_CON") (pintype "passive"))
  )

  (footprint "antmicro-footprints:R_0603_1608Metric" (layer "F.Cu")
    (at 148.7 53.85)
    (descr "Resistor SMD 0603")
    (tags "resistor SMD 0603")
    (property "Author" "Antmicro")
    (property "License" "Apache-2.0")
    (property "MPN" "CR0603-FX-4701ELF")
    (property "Manufacturer" "Bourns")
    (property "Sheetfile" "d1600e-psu-breakout-board.kicad_sch")
    (property "Sheetname" "")
    (property "Tolerance" "1%")
    (property "Val" "4k7")
    (property "ki_description" "SMD Chip Resistor, 4.7 kohm, ± 1%, 100 mW, 0603 [1608 Metric], Thick Film, General Purpose")
    (property "ki_keywords" "0603, SMT, RESISTOR, PASSIVE")
    (attr smd)
    (fp_text reference "R51" (at -1.1 1.65) (layer "F.SilkS")
        (effects (font (size 0.7 0.7) (thickness 0.15)) (justify left bottom))
    )
    (fp_text value "R_4k7_0603" (at 0 1.6) (layer "F.Fab")
        (effects (font (size 0.7 0.7) (thickness 0.15)) (justify left bottom))
    )
    (fp_text user "License: Apache-2.0" (at -1.25 5.9) (layer "F.Fab") hide
        (effects (font (size 0.7 0.7) (thickness 0.15)) (justify left bottom))
    )
    (fp_text user "${REFERENCE}" (at -1.25 3.898) (layer "F.Fab") hide
        (effects (font (size 0.7 0.7) (thickness 0.15)) (justify left bottom))
    )
    (fp_text user "Author: Antmicro" (at -1.25 4.9) (layer "F.Fab") hide
        (effects (font (size 0.7 0.7) (thickness 0.15)) (justify left bottom))
    )
    (fp_line (start -0.15 -0.4) (end 0.15 -0.4)
      (stroke (width 0.15) (type solid)) (layer "F.SilkS"))
    (fp_line (start -0.15 0.4) (end 0.15 0.4)
      (stroke (width 0.15) (type solid)) (layer "F.SilkS"))
    (fp_rect (start -1.25 -0.65) (end 1.25 0.65)
      (stroke (width 0.05) (type solid)) (fill none) (layer "F.CrtYd"))
    (fp_rect (start -0.8 -0.4) (end 0.8 0.4)
      (stroke (width 0.15) (type solid)) (fill none) (layer "F.Fab"))
    (pad "1" smd roundrect (at -0.7 0) (size 0.8 1) (layers "F.Cu" "F.Paste" "F.Mask") (roundrect_rratio 0.2)
      (net 40 "Net-(D6-A)") (pintype "passive"))
    (pad "2" smd roundrect (at 0.7 0) (size 0.8 1) (layers "F.Cu" "F.Paste" "F.Mask") (roundrect_rratio 0.2)
      (net 42 "LOAD_3") (pintype "passive"))
  )

  (footprint "antmicro-footprints:R_0402_1005Metric" (layer "F.Cu")
    (at 167.65 113.5 90)
    (descr "Resistor SMD 0402")
    (tags "resistor SMD 0402")
    (property "Author" "Antmicro")
    (property "License" "Apache-2.0")
    (property "MPN" "CR0402-FX-4701GLF")
    (property "Manufacturer" "Bourns")
    (property "Sheetfile" "ftdi-module.kicad_sch")
    (property "Sheetname" "FTDI")
    (property "Tolerance" "1%")
    (property "Val" "4k7")
    (property "ki_description" "SMD Chip Resistor, 4.7 kohm, ± 1%, 62.5 mW, 0402 [1005 Metric], Thick Film, General Purpose")
    (property "ki_keywords" "0402, SMT, RESISTOR, PASSIVE")
    (attr smd)
    (fp_text reference "R5" (at 0.9 0.45 90) (layer "F.SilkS")
        (effects (font (size 0.7 0.7) (thickness 0.15)) (justify left bottom))
    )
    (fp_text value "R_4k7_0402" (at -1.011843 1.772047 90) (layer "F.Fab")
        (effects (font (size 0.7 0.7) (thickness 0.15)) (justify left bottom))
    )
    (fp_text user "Author: Antmicro" (at -0.95 4.169 90) (layer "F.Fab") hide
        (effects (font (size 0.7 0.7) (thickness 0.15)) (justify left bottom))
    )
    (fp_text user "License: Apache-2.0" (at -0.95 5.169 90) (layer "F.Fab") hide
        (effects (font (size 0.7 0.7) (thickness 0.15)) (justify left bottom))
    )
    (fp_text user "${REFERENCE}" (at -0.95 3.168 90) (layer "F.Fab") hide
        (effects (font (size 0.7 0.7) (thickness 0.15)) (justify left bottom))
    )
    (fp_rect (start -0.925 -0.47) (end 0.925 0.47)
      (stroke (width 0.05) (type default)) (fill none) (layer "F.CrtYd"))
    (fp_rect (start -0.5 -0.25) (end 0.5 0.25)
      (stroke (width 0.15) (type solid)) (fill none) (layer "F.Fab"))
    (pad "1" smd roundrect (at -0.48 0 90) (size 0.59 0.64) (layers "F.Cu" "F.Paste" "F.Mask") (roundrect_rratio 0.25)
      (net 81 "SCL_FTDI") (pintype "passive"))
    (pad "2" smd roundrect (at 0.48 0 90) (size 0.59 0.64) (layers "F.Cu" "F.Paste" "F.Mask") (roundrect_rratio 0.25)
      (net 76 "VCC3V3_USB") (pintype "passive"))
  )

  (footprint "antmicro-footprints:R_0603_1608Metric" (layer "F.Cu")
    (at 164.5 106.3 90)
    (descr "Resistor SMD 0603")
    (tags "resistor SMD 0603")
    (property "Author" "Antmicro")
    (property "Current" "1A")
    (property "DNP" "DNP")
    (property "License" "Apache-2.0")
    (property "MPN" "CR0603-J/-000ELF")
    (property "Manufacturer" "Bourns")
    (property "Sheetfile" "ftdi-module.kicad_sch")
    (property "Sheetname" "FTDI")
    (property "Tolerance" "")
    (property "Val" "0R")
    (property "dnp" "")
    (property "exclude_from_bom" "")
    (property "ki_description" "Zero Ohm Resistor, Jumper, 0603 [1608 Metric], Thick Film, 100 mW, 1 A, Surface Mount Device, CR")
    (property "ki_keywords" "0603, SMT, RESISTOR, PASSIVE")
    (attr smd exclude_from_bom)
    (fp_text reference "R75" (at 0 -1.2 90) (layer "F.SilkS")
        (effects (font (size 0.7 0.7) (thickness 0.15)))
    )
    (fp_text value "R_0R_0603" (at 0 1.9 90) (layer "F.Fab")
        (effects (font (size 1 1) (thickness 0.15)))
    )
    (fp_text user "${REFERENCE}" (at -1.25 3.898 90) (layer "F.Fab") hide
        (effects (font (size 0.7 0.7) (thickness 0.15)) (justify left bottom))
    )
    (fp_text user "License: Apache-2.0" (at -1.25 5.9 90) (layer "F.Fab") hide
        (effects (font (size 0.7 0.7) (thickness 0.15)) (justify left bottom))
    )
    (fp_text user "Author: Antmicro" (at -1.25 4.9 90) (layer "F.Fab") hide
        (effects (font (size 0.7 0.7) (thickness 0.15)) (justify left bottom))
    )
    (fp_line (start -0.15 -0.4) (end 0.15 -0.4)
      (stroke (width 0.15) (type solid)) (layer "F.SilkS"))
    (fp_line (start -0.15 0.4) (end 0.15 0.4)
      (stroke (width 0.15) (type solid)) (layer "F.SilkS"))
    (fp_rect (start -1.25 -0.65) (end 1.25 0.65)
      (stroke (width 0.05) (type solid)) (fill none) (layer "F.CrtYd"))
    (fp_rect (start -0.8 -0.4) (end 0.8 0.4)
      (stroke (width 0.15) (type solid)) (fill none) (layer "F.Fab"))
    (pad "1" smd roundrect (at -0.7 0 90) (size 0.8 1) (layers "F.Cu" "F.Paste" "F.Mask") (roundrect_rratio 0.2)
      (net 116 "Net-(U5-BDBUS1)") (pintype "passive"))
    (pad "2" smd roundrect (at 0.7 0 90) (size 0.8 1) (layers "F.Cu" "F.Paste" "F.Mask") (roundrect_rratio 0.2)
      (net 145 "LED_DATA") (pintype "passive"))
  )

  (footprint "antmicro-footprints:TP_SMD_1mm" (layer "F.Cu")
    (at 189.15 107.65)
    (property "Author" "Antmicro")
    (property "License" "Apache-2.0")
    (property "MPN" "")
    (property "Manufacturer" "")
    (property "Sheetfile" "ftdi-module.kicad_sch")
    (property "Sheetname" "FTDI")
    (property "exclude_from_bom" "")
    (property "ki_description" "Test point 1mm SMD")
    (property "ki_keywords" "TESTPOINT")
    (attr exclude_from_pos_files exclude_from_bom)
    (fp_text reference "TP4" (at 0.4 -0.55 90) (layer "F.SilkS")
        (effects (font (size 0.7 0.7) (thickness 0.15)) (justify left bottom))
    )
    (fp_text value "TP_1mm_SMD" (at 0 1.4) (layer "F.Fab")
        (effects (font (size 0.7 0.7) (thickness 0.15)) (justify left bottom))
    )
    (fp_text user "${REFERENCE}" (at -0.5 2.8) (layer "F.Fab") hide
        (effects (font (size 0.7 0.7) (thickness 0.15)) (justify left bottom))
    )
    (fp_text user "Author: Antmicro" (at -0.5 4) (layer "F.Fab") hide
        (effects (font (size 0.7 0.7) (thickness 0.15)) (justify left bottom))
    )
    (fp_text user "License: Apache-2.0" (at -0.5 5.2) (layer "F.Fab") hide
        (effects (font (size 0.7 0.7) (thickness 0.15)) (justify left bottom))
    )
    (fp_circle (center 0 0) (end 0.6 0)
      (stroke (width 0.05) (type default)) (fill none) (layer "F.CrtYd"))
    (pad "1" smd circle (at 0 0) (size 1 1) (layers "F.Cu" "F.Mask")
      (net 114 "Net-(U1-CC_{2})") (pinfunction "1") (pintype "passive"))
  )

  (footprint "antmicro-footprints:LED_0603_1608Metric_G" (layer "F.Cu")
    (at 180.85 53.45)
    (descr "LED SMD 0603 Green")
    (tags "LED SMD 0603 Green")
    (property "Author" "Antmicro")
    (property "Color" "Green")
    (property "License" "Apache-2.0")
    (property "MPN" "LG L29K-G2J1-24-Z")
    (property "Manufacturer" "OSRAM")
    (property "Sheetfile" "d1600e-psu-breakout-board.kicad_sch")
    (property "Sheetname" "")
    (property "ki_description" "LED, Green, SMD, 0603, 20 mA, 1.7 V, 570 nm")
    (property "ki_keywords" "SMT, DIODE, SEMICONDUCTOR, LED")
    (zone_connect 1)
    (attr smd)
    (fp_text reference "D8" (at 1.2 0.45) (layer "F.SilkS")
        (effects (font (size 0.7 0.7) (thickness 0.15)) (justify left bottom))
    )
    (fp_text value "LED_G_0603_LG_L29K-G2J1-24-Z" (at -0.001 1.599) (layer "F.Fab")
        (effects (font (size 0.7 0.7) (thickness 0.15)) (justify left bottom))
    )
    (fp_text user "Author: Antmicro" (at -1.4224 4.799) (layer "F.Fab") hide
        (effects (font (size 0.7 0.7) (thickness 0.15)) (justify left bottom))
    )
    (fp_text user "License: Apache-2.0" (at -1.4224 3.599) (layer "F.Fab") hide
        (effects (font (size 0.7 0.7) (thickness 0.15)) (justify left bottom))
    )
    (fp_text user "${REFERENCE}" (at -1.4224 5.999) (layer "F.Fab") hide
        (effects (font (size 0.7 0.7) (thickness 0.15)) (justify left bottom))
    )
    (fp_line (start -1.18 -0.319) (end -1.18 0.321)
      (stroke (width 0.15) (type solid)) (layer "F.SilkS"))
    (fp_line (start -0.094672 0.001008) (end -0.24 0.001008)
      (stroke (width 0.1) (type solid)) (layer "F.SilkS"))
    (fp_line (start -0.094672 0.001008) (end 0.105328 -0.198992)
      (stroke (width 0.1) (type solid)) (layer "F.SilkS"))
    (fp_line (start -0.094672 0.201008) (end -0.094672 -0.198992)
      (stroke (width 0.1) (type solid)) (layer "F.SilkS"))
    (fp_line (start 0.105328 0.001008) (end 0.24 0.001)
      (stroke (width 0.1) (type solid)) (layer "F.SilkS"))
    (fp_line (start 0.105328 0.201008) (end -0.094672 0.001008)
      (stroke (width 0.1) (type solid)) (layer "F.SilkS"))
    (fp_line (start 0.105328 0.201008) (end 0.105328 -0.198992)
      (stroke (width 0.1) (type solid)) (layer "F.SilkS"))
    (fp_line (start 0.22 -0.35) (end -0.22 -0.35)
      (stroke (width 0.15) (type solid)) (layer "F.SilkS"))
    (fp_line (start 0.22 0.35) (end -0.22 0.35)
      (stroke (width 0.15) (type solid)) (layer "F.SilkS"))
    (fp_rect (start 1.25 0.65) (end -1.25 -0.65)
      (stroke (width 0.05) (type solid)) (fill none) (layer "F.CrtYd"))
    (fp_line (start -0.199 -0.202) (end -0.199 0.1)
      (stroke (width 0.15) (type solid)) (layer "F.Fab"))
    (fp_line (start -0.199 0) (end -0.597 0)
      (stroke (width 0.15) (type solid)) (layer "F.Fab"))
    (fp_line (start -0.199 0.2) (end -0.199 0.1)
      (stroke (width 0.15) (type solid)) (layer "F.Fab"))
    (fp_line (start -0.101 0) (end 0.201 0.2)
      (stroke (width 0.15) (type solid)) (layer "F.Fab"))
    (fp_line (start 0.201 -0.202) (end -0.101 0)
      (stroke (width 0.15) (type solid)) (layer "F.Fab"))
    (fp_line (start 0.201 0) (end 0.201 -0.202)
      (stroke (width 0.15) (type solid)) (layer "F.Fab"))
    (fp_line (start 0.201 0.2) (end 0.201 0)
      (stroke (width 0.15) (type solid)) (layer "F.Fab"))
    (fp_line (start 0.599 0) (end 0.201 0)
      (stroke (width 0.15) (type solid)) (layer "F.Fab"))
    (fp_rect (start 0.848 0.4) (end -0.85 -0.402)
      (stroke (width 0.15) (type solid)) (fill none) (layer "F.Fab"))
    (pad "1" smd roundrect (at -0.7 0 180) (size 0.8 1) (layers "F.Cu" "F.Paste" "F.Mask") (roundrect_rratio 0.2)
      (net 4 "GND") (pinfunction "C") (pintype "passive"))
    (pad "2" smd roundrect (at 0.7 0 180) (size 0.8 1) (layers "F.Cu" "F.Paste" "F.Mask") (roundrect_rratio 0.2)
      (net 53 "Net-(D8-A)") (pinfunction "A") (pintype "passive"))
  )

  (footprint "antmicro-footprints:Conn_Molex_KK_1x4_22-27-2041" (layer "F.Cu")
    (at 152.37 53.99)
    (property "Author" "Antmicro")
    (property "License" "Apache-2.0")
    (property "MPN" "22-27-2041")
    (property "Manufacturer" "Molex")
    (property "Sheetfile" "d1600e-psu-breakout-board.kicad_sch")
    (property "Sheetname" "")
    (property "ki_description" "Rectangular connector (header, female pins)")
    (property "ki_keywords" "VERTICAL, THT, HEADER, CONNECTOR, MALE")
    (attr through_hole)
    (fp_text reference "J13" (at 4.255 4.21) (layer "F.SilkS")
        (effects (font (size 0.7 0.7) (thickness 0.15)) (justify left bottom))
    )
    (fp_text value "Molex_KK_1x4_22-27-2041" (at -0.8 4.6 180) (layer "F.Fab")
        (effects (font (size 0.7 0.7) (thickness 0.15)) (justify left bottom))
    )
    (fp_text user "License: Apache-2.0" (at -2.12 7.95) (layer "F.Fab") hide
        (effects (font (size 0.7 0.7) (thickness 0.15)) (justify left bottom))
    )
    (fp_text user "${REFERENCE}" (at -2.12 9.15) (layer "F.Fab") hide
        (effects (font (size 0.7 0.7) (thickness 0.15)) (justify left bottom))
    )
    (fp_text user "Author: Antmicro" (at -2.12 6.75) (layer "F.Fab") hide
        (effects (font (size 0.7 0.7) (thickness 0.15)) (justify left bottom))
    )
    (fp_line (start -1.39 -3.03) (end -1.39 2.99)
      (stroke (width 0.15) (type solid)) (layer "F.SilkS"))
    (fp_line (start -1.39 2.99) (end 8.99 2.99)
      (stroke (width 0.15) (type solid)) (layer "F.SilkS"))
    (fp_line (start -0.81 -3.03) (end -0.81 -2.43)
      (stroke (width 0.15) (type solid)) (layer "F.SilkS"))
    (fp_line (start -0.81 -2.43) (end 0.79 -2.43)
      (stroke (width 0.15) (type solid)) (layer "F.SilkS"))
    (fp_line (start -0.01 1.99) (end 0.24 1.46)
      (stroke (width 0.15) (type solid)) (layer "F.SilkS"))
    (fp_line (start -0.01 1.99) (end 7.61 1.99)
      (stroke (width 0.15) (type solid)) (layer "F.SilkS"))
    (fp_line (start -0.01 2.99) (end -0.01 1.99)
      (stroke (width 0.15) (type solid)) (layer "F.SilkS"))
    (fp_line (start 0.24 1.46) (end 7.36 1.46)
      (stroke (width 0.15) (type solid)) (layer "F.SilkS"))
    (fp_line (start 0.24 2.99) (end 0.24 1.99)
      (stroke (width 0.15) (type solid)) (layer "F.SilkS"))
    (fp_line (start 0.79 -2.43) (end 0.79 -3.03)
      (stroke (width 0.15) (type solid)) (layer "F.SilkS"))
    (fp_line (start 1.73 -3.03) (end 1.73 -2.43)
      (stroke (width 0.15) (type solid)) (layer "F.SilkS"))
    (fp_line (start 1.73 -2.43) (end 3.33 -2.43)
      (stroke (width 0.15) (type solid)) (layer "F.SilkS"))
    (fp_line (start 3.33 -2.43) (end 3.33 -3.03)
      (stroke (width 0.15) (type solid)) (layer "F.SilkS"))
    (fp_line (start 4.27 -3.03) (end 4.27 -2.43)
      (stroke (width 0.15) (type solid)) (layer "F.SilkS"))
    (fp_line (start 4.27 -2.43) (end 5.87 -2.43)
      (stroke (width 0.15) (type solid)) (layer "F.SilkS"))
    (fp_line (start 5.87 -2.43) (end 5.87 -3.03)
      (stroke (width 0.15) (type solid)) (layer "F.SilkS"))
    (fp_line (start 6.81 -3.03) (end 6.81 -2.43)
      (stroke (width 0.15) (type solid)) (layer "F.SilkS"))
    (fp_line (start 6.81 -2.43) (end 8.41 -2.43)
      (stroke (width 0.15) (type solid)) (layer "F.SilkS"))
    (fp_line (start 7.36 1.46) (end 7.61 1.99)
      (stroke (width 0.15) (type solid)) (layer "F.SilkS"))
    (fp_line (start 7.36 2.99) (end 7.36 1.99)
      (stroke (width 0.15) (type solid)) (layer "F.SilkS"))
    (fp_line (start 7.61 1.99) (end 7.61 2.99)
      (stroke (width 0.15) (type solid)) (layer "F.SilkS"))
    (fp_line (start 8.41 -2.43) (end 8.41 -3.03)
      (stroke (width 0.15) (type solid)) (layer "F.SilkS"))
    (fp_line (start 8.99 -3.03) (end -1.39 -3.03)
      (stroke (width 0.15) (type solid)) (layer "F.SilkS"))
    (fp_line (start 8.99 2.99) (end 8.99 -3.03)
      (stroke (width 0.15) (type solid)) (layer "F.SilkS"))
    (fp_line (start -1.79 -3.38) (end -1.79 3.42)
      (stroke (width 0.05) (type solid)) (layer "F.CrtYd"))
    (fp_line (start -1.79 3.42) (end 9.37 3.42)
      (stroke (width 0.05) (type solid)) (layer "F.CrtYd"))
    (fp_line (start 9.37 -3.38) (end -1.79 -3.38)
      (stroke (width 0.05) (type solid)) (layer "F.CrtYd"))
    (fp_line (start 9.37 3.42) (end 9.37 -3.38)
      (stroke (width 0.05) (type solid)) (layer "F.CrtYd"))
    (fp_line (start -1.29 -2.88) (end -1.29 2.92)
      (stroke (width 0.15) (type solid)) (layer "F.Fab"))
    (fp_line (start -1.29 2.92) (end 8.87 2.92)
      (stroke (width 0.15) (type solid)) (layer "F.Fab"))
    (fp_line (start 8.163 0) (end 8.87 -0.5)
      (stroke (width 0.15) (type solid)) (layer "F.Fab"))
    (fp_line (start 8.87 -2.88) (end -1.29 -2.88)
      (stroke (width 0.15) (type solid)) (layer "F.Fab"))
    (fp_line (start 8.87 0.5) (end 8.163 0)
      (stroke (width 0.15) (type solid)) (layer "F.Fab"))
    (fp_line (start 8.87 2.92) (end 8.87 -2.88)
      (stroke (width 0.15) (type solid)) (layer "F.Fab"))
    (pad "1" thru_hole roundrect (at 0 0) (size 1.74 2.19) (drill 1.19) (layers "*.Cu" "*.Mask") (roundrect_rratio 0.143678)
      (net 11 "VCC12V0") (pintype "passive"))
    (pad "2" thru_hole oval (at 2.54 0) (size 1.74 2.19) (drill 1.19) (layers "*.Cu" "*.Mask")
      (net 4 "GND") (pintype "passive"))
    (pad "3" thru_hole oval (at 5.08 0) (size 1.74 2.19) (drill 1.19) (layers "*.Cu" "*.Mask")
      (net 4 "GND") (pintype "passive"))
    (pad "4" thru_hole oval (at 7.62 0) (size 1.74 2.19) (drill 1.19) (layers "*.Cu" "*.Mask")
      (net 2 "VCC5V0") (pintype "passive"))
  )

  (footprint "antmicro-footprints:SOIC-4_4.55x2.6mm_P1.27mm" (layer "F.Cu")
    (at 166.95 106.85 90)
    (descr "ACPL-217-500E")
    (tags "Integrated Circuit")
    (property "Author" "Antmicro")
    (property "Description" "Broadcom ACPL-217-500E DC Input Transistor Output Optocoupler, Surface Mount, 4-Pin SO")
    (property "License" "Apache-2.0")
    (property "MPN" "ACPL-217-500E")
    (property "Manufacturer" "Broadcom")
    (property "Sheetfile" "ftdi-module.kicad_sch")
    (property "Sheetname" "FTDI")
    (property "ki_description" "Optocoupler, Transistor Output, 1 Channel, SOIC, 4 Pins, 50 mA, 3 kV, 50 %")
    (property "ki_keywords" "SMT, OPTOCOUPLER, IC")
    (attr smd)
    (fp_text reference "U7" (at -4.25 -1.9 90) (layer "F.SilkS")
        (effects (font (size 0.7 0.7) (thickness 0.15)) (justify left bottom))
    )
    (fp_text value "ACPL-217-500E" (at -4.25 2.75 90) (layer "F.Fab")
        (effects (font (size 0.7 0.7) (thickness 0.15)) (justify left bottom))
    )
    (fp_text user "." (at -2.7 -1.6 90) (layer "F.SilkS")
        (effects (font (size 1 1) (thickness 0.15)))
    )
    (fp_text user "${REFERENCE}" (at -4.3 4.25 90) (layer "F.Fab") hide
        (effects (font (size 0.7 0.7) (thickness 0.15)) (justify left bottom))
    )
    (fp_text user "Author: Antmicro" (at -4.3 5.5 90) (layer "F.Fab") hide
        (effects (font (size 0.7 0.7) (thickness 0.15)) (justify left bottom))
    )
    (fp_text user "License: Apache-2.0" (at -4.25 7 90) (layer "F.Fab") hide
        (effects (font (size 0.7 0.7) (thickness 0.15)) (justify left bottom))
    )
    (fp_line (start -2.3 -1.4) (end -1.8 -1.4)
      (stroke (width 0.12) (type solid)) (layer "F.SilkS"))
    (fp_line (start -2.3 1.1) (end -2.3 1.4)
      (stroke (width 0.12) (type solid)) (layer "F.SilkS"))
    (fp_line (start -1.8 1.4) (end -2.3 1.4)
      (stroke (width 0.12) (type solid)) (layer "F.SilkS"))
    (fp_line (start 1.8 -1.4) (end 2.3 -1.4)
      (stroke (width 0.12) (type solid)) (layer "F.SilkS"))
    (fp_line (start 2.3 -1.1) (end 2.3 -1.4)
      (stroke (width 0.12) (type solid)) (layer "F.SilkS"))
    (fp_line (start 2.3 1.1) (end 2.3 1.4)
      (stroke (width 0.12) (type solid)) (layer "F.SilkS"))
    (fp_line (start 2.3 1.4) (end 1.8 1.4)
      (stroke (width 0.12) (type solid)) (layer "F.SilkS"))
    (fp_line (start -4.3 -1.7) (end 4.29 -1.7)
      (stroke (width 0.05) (type solid)) (layer "F.CrtYd"))
    (fp_line (start -4.3 1.69) (end -4.3 -1.7)
      (stroke (width 0.05) (type solid)) (layer "F.CrtYd"))
    (fp_line (start 4.29 -1.7) (end 4.29 1.69)
      (stroke (width 0.05) (type solid)) (layer "F.CrtYd"))
    (fp_line (start 4.29 1.69) (end -4.3 1.69)
      (stroke (width 0.05) (type solid)) (layer "F.CrtYd"))
    (fp_line (start -2.201 -1.301) (end 2.2 -1.301)
      (stroke (width 0.15) (type solid)) (layer "F.Fab"))
    (fp_line (start -2.201 -0.03) (end -0.931 -1.301)
      (stroke (width 0.15) (type solid)) (layer "F.Fab"))
    (fp_line (start -2.201 1.3) (end -2.201 -1.301)
      (stroke (width 0.15) (type solid)) (layer "F.Fab"))
    (fp_line (start 2.2 -1.301) (end 2.2 1.3)
      (stroke (width 0.15) (type solid)) (layer "F.Fab"))
    (fp_line (start 2.2 1.3) (end -2.201 1.3)
      (stroke (width 0.15) (type solid)) (layer "F.Fab"))
    (pad "1" smd roundrect (at -3.125 -0.635 180) (size 0.65 1.85) (layers "F.Cu" "F.Paste" "F.Mask") (roundrect_rratio 0.15)
      (net 116 "Net-(U5-BDBUS1)") (pintype "passive"))
    (pad "2" smd roundrect (at -3.125 0.634 180) (size 0.65 1.85) (layers "F.Cu" "F.Paste" "F.Mask") (roundrect_rratio 0.15)
      (net 147 "Net-(R74-Pad2)") (pintype "passive"))
    (pad "3" smd roundrect (at 3.124 0.634 180) (size 0.65 1.85) (layers "F.Cu" "F.Paste" "F.Mask") (roundrect_rratio 0.15)
      (net 4 "GND") (pintype "passive"))
    (pad "4" smd roundrect (at 3.124 -0.635 180) (size 0.65 1.85) (layers "F.Cu" "F.Paste" "F.Mask") (roundrect_rratio 0.15)
      (net 115 "Net-(U6-A)") (pintype "passive"))
  )

  (footprint "antmicro-footprints:Vishay_PowerPAK_1212-8_Single" (layer "F.Cu")
    (at 171.1 86.2 90)
    (descr "PowerPAK 1212-8 Single")
    (tags "Vishay PowerPAK 1212-8 Single")
    (property "Author" "Antmicro")
    (property "License" "Apache-2.0")
    (property "MPN" "SI7613DN-T1-GE3")
    (property "Manufacturer" "Vishay")
    (property "Sheetfile" "power-switch.kicad_sch")
    (property "Sheetname" "Power switch 4")
    (property "ki_description" "Power MOSFET, P Channel, 20 V, 35 A, 0.0072 ohm, PowerPAK 1212, Surface Mount")
    (property "ki_keywords" "SMT, TRANSISTOR, SEMICONDUCTOR, MOSFET, PMOS")
    (attr smd)
    (fp_text reference "QB4" (at -2.95 0.25 180) (layer "F.SilkS")
        (effects (font (size 0.7 0.7) (thickness 0.15)) (justify left bottom))
    )
    (fp_text value "SI7613DN-T1-GE3" (at 0 2.7 90) (layer "F.Fab")
        (effects (font (size 0.7 0.7) (thickness 0.15)) (justify left bottom))
    )
    (fp_text user "Author: Antmicro" (at -8 5.9 90) (layer "F.Fab") hide
        (effects (font (size 0.7 0.7) (thickness 0.15)) (justify left bottom))
    )
    (fp_text user "License: Apache-2.0" (at -8 7.1 90) (layer "F.Fab") hide
        (effects (font (size 0.7 0.7) (thickness 0.15)) (justify left bottom))
    )
    (fp_text user "${REFERENCE}" (at -8 4.7 90) (layer "F.Fab") hide
        (effects (font (size 0.7 0.7) (thickness 0.15)) (justify left bottom))
    )
    (fp_line (start -1.651 -1.651) (end -1.651 -1.317)
      (stroke (width 0.15) (type solid)) (layer "F.SilkS"))
    (fp_line (start -1.651 -1.651) (end 1.648 -1.651)
      (stroke (width 0.15) (type solid)) (layer "F.SilkS"))
    (fp_line (start -1.635 1.3) (end -1.635 1.634)
      (stroke (width 0.15) (type solid)) (layer "F.SilkS"))
    (fp_line (start -1.635 1.634) (end 1.634 1.634)
      (stroke (width 0.15) (type solid)) (layer "F.SilkS"))
    (fp_line (start 1.634 1.3) (end 1.634 1.634)
      (stroke (width 0.15) (type solid)) (layer "F.SilkS"))
    (fp_line (start 1.648 -1.651) (end 1.648 -1.317)
      (stroke (width 0.15) (type solid)) (layer "F.SilkS"))
    (fp_circle (center -1.9 -1.4) (end -1.85 -1.4)
      (stroke (width 0.15) (type solid)) (fill solid) (layer "F.SilkS"))
    (fp_rect (start -2 -1.8) (end 2 1.798)
      (stroke (width 0.05) (type solid)) (fill none) (layer "F.CrtYd"))
    (fp_line (start -1.6425 -1.4175) (end -1.4175 -1.6425)
      (stroke (width 0.15) (type solid)) (layer "F.Fab"))
    (fp_rect (start -1.651 -1.651) (end 1.648 1.648)
      (stroke (width 0.15) (type solid)) (fill none) (layer "F.Fab"))
    (pad "1" smd rect (at -1.436 -0.99 90) (size 0.99 0.405) (layers "F.Cu" "F.Paste" "F.Mask")
      (net 11 "VCC12V0") (pinfunction "S") (pintype "passive"))
    (pad "2" smd rect (at -1.436 -0.332 90) (size 0.99 0.405) (layers "F.Cu" "F.Paste" "F.Mask")
      (net 11 "VCC12V0") (pinfunction "S") (pintype "passive"))
    (pad "3" smd rect (at -1.436 0.33 90) (size 0.99 0.405) (layers "F.Cu" "F.Paste" "F.Mask")
      (net 11 "VCC12V0") (pinfunction "S") (pintype "passive"))
    (pad "4" smd rect (at -1.436 0.988 90) (size 0.99 0.405) (layers "F.Cu" "F.Paste" "F.Mask")
      (net 102 "Net-(QB4-G)") (pinfunction "G") (pintype "passive"))
    (pad "5" smd custom (at 0.557 0 90) (size 1.725 2.235) (layers "F.Cu" "F.Paste" "F.Mask")
      (net 27 "C_MEAS_4") (pinfunction "D") (pintype "passive") (zone_connect 2)
      (options (clearance outline) (anchor rect))
      (primitives
        (gr_poly
          (pts
            (xy 0.8625 0.1275)
            (xy 0.8625 -0.1275)
            (xy 1.3725 -0.1275)
            (xy 1.3725 -0.5325)
            (xy 0.8625 -0.5325)
            (xy 0.8625 -0.7875)
            (xy 1.3725 -0.7875)
            (xy 1.3725 -1.195)
            (xy 0.6125 -1.195)
            (xy 0.6125 1.195)
            (xy 1.3725 1.195)
            (xy 1.3725 0.7875)
            (xy 0.8625 0.7875)
            (xy 0.8625 0.5325)
            (xy 1.3725 0.5325)
            (xy 1.3725 0.1275)
          )
          (width 0) (fill yes))
      ))
  )

  (footprint "antmicro-footprints:LED_0603_1608Metric_G" (layer "F.Cu")
    (at 163.2 53.85)
    (descr "LED SMD 0603 Green")
    (tags "LED SMD 0603 Green")
    (property "Author" "Antmicro")
    (property "Color" "Green")
    (property "License" "Apache-2.0")
    (property "MPN" "LG L29K-G2J1-24-Z")
    (property "Manufacturer" "OSRAM")
    (property "Sheetfile" "d1600e-psu-breakout-board.kicad_sch")
    (property "Sheetname" "")
    (property "ki_description" "LED, Green, SMD, 0603, 20 mA, 1.7 V, 570 nm")
    (property "ki_keywords" "SMT, DIODE, SEMICONDUCTOR, LED")
    (zone_connect 1)
    (attr smd)
    (fp_text reference "D7" (at -0.9 1.65) (layer "F.SilkS")
        (effects (font (size 0.7 0.7) (thickness 0.15)) (justify left bottom))
    )
    (fp_text value "LED_G_0603_LG_L29K-G2J1-24-Z" (at -0.001 1.599) (layer "F.Fab")
        (effects (font (size 0.7 0.7) (thickness 0.15)) (justify left bottom))
    )
    (fp_text user "${REFERENCE}" (at -1.4224 5.999) (layer "F.Fab") hide
        (effects (font (size 0.7 0.7) (thickness 0.15)) (justify left bottom))
    )
    (fp_text user "License: Apache-2.0" (at -1.4224 3.599) (layer "F.Fab") hide
        (effects (font (size 0.7 0.7) (thickness 0.15)) (justify left bottom))
    )
    (fp_text user "Author: Antmicro" (at -1.4224 4.799) (layer "F.Fab") hide
        (effects (font (size 0.7 0.7) (thickness 0.15)) (justify left bottom))
    )
    (fp_line (start -1.18 -0.319) (end -1.18 0.321)
      (stroke (width 0.15) (type solid)) (layer "F.SilkS"))
    (fp_line (start -0.094672 0.001008) (end -0.24 0.001008)
      (stroke (width 0.1) (type solid)) (layer "F.SilkS"))
    (fp_line (start -0.094672 0.001008) (end 0.105328 -0.198992)
      (stroke (width 0.1) (type solid)) (layer "F.SilkS"))
    (fp_line (start -0.094672 0.201008) (end -0.094672 -0.198992)
      (stroke (width 0.1) (type solid)) (layer "F.SilkS"))
    (fp_line (start 0.105328 0.001008) (end 0.24 0.001)
      (stroke (width 0.1) (type solid)) (layer "F.SilkS"))
    (fp_line (start 0.105328 0.201008) (end -0.094672 0.001008)
      (stroke (width 0.1) (type solid)) (layer "F.SilkS"))
    (fp_line (start 0.105328 0.201008) (end 0.105328 -0.198992)
      (stroke (width 0.1) (type solid)) (layer "F.SilkS"))
    (fp_line (start 0.22 -0.35) (end -0.22 -0.35)
      (stroke (width 0.15) (type solid)) (layer "F.SilkS"))
    (fp_line (start 0.22 0.35) (end -0.22 0.35)
      (stroke (width 0.15) (type solid)) (layer "F.SilkS"))
    (fp_rect (start 1.25 0.65) (end -1.25 -0.65)
      (stroke (width 0.05) (type solid)) (fill none) (layer "F.CrtYd"))
    (fp_line (start -0.199 -0.202) (end -0.199 0.1)
      (stroke (width 0.15) (type solid)) (layer "F.Fab"))
    (fp_line (start -0.199 0) (end -0.597 0)
      (stroke (width 0.15) (type solid)) (layer "F.Fab"))
    (fp_line (start -0.199 0.2) (end -0.199 0.1)
      (stroke (width 0.15) (type solid)) (layer "F.Fab"))
    (fp_line (start -0.101 0) (end 0.201 0.2)
      (stroke (width 0.15) (type solid)) (layer "F.Fab"))
    (fp_line (start 0.201 -0.202) (end -0.101 0)
      (stroke (width 0.15) (type solid)) (layer "F.Fab"))
    (fp_line (start 0.201 0) (end 0.201 -0.202)
      (stroke (width 0.15) (type solid)) (layer "F.Fab"))
    (fp_line (start 0.201 0.2) (end 0.201 0)
      (stroke (width 0.15) (type solid)) (layer "F.Fab"))
    (fp_line (start 0.599 0) (end 0.201 0)
      (stroke (width 0.15) (type solid)) (layer "F.Fab"))
    (fp_rect (start 0.848 0.4) (end -0.85 -0.402)
      (stroke (width 0.15) (type solid)) (fill none) (layer "F.Fab"))
    (pad "1" smd roundrect (at -0.7 0 180) (size 0.8 1) (layers "F.Cu" "F.Paste" "F.Mask") (roundrect_rratio 0.2)
      (net 4 "GND") (pinfunction "C") (pintype "passive"))
    (pad "2" smd roundrect (at 0.7 0 180) (size 0.8 1) (layers "F.Cu" "F.Paste" "F.Mask") (roundrect_rratio 0.2)
      (net 52 "Net-(D7-A)") (pinfunction "A") (pintype "passive"))
  )

  (footprint "antmicro-footprints:TPD2E009DRTR" (layer "F.Cu")
    (at 182.3375 111.7 180)
    (property "Author" "Antmicro")
    (property "License" "Apache-2.0")
    (property "MPN" "PESD5V0S2BQA")
    (property "Manufacturer" "Nexperia")
    (property "Sheetfile" "ftdi-module.kicad_sch")
    (property "Sheetname" "FTDI")
    (property "ki_description" "TVS diode array, 30 kV, SOT-1215, 5V, 45 pF")
    (property "ki_keywords" "SMT, DIODE, SEMICONDUCTOR, TVS, ESD")
    (attr smd)
    (fp_text reference "D14" (at 3.2875 -0.7 180) (layer "F.SilkS")
        (effects (font (size 0.7 0.7) (thickness 0.15)) (justify left bottom))
    )
    (fp_text value "PESD5V0S2BQA" (at 5.608 1.306 180) (layer "F.Fab")
        (effects (font (size 0.7 0.7) (thickness 0.15)) (justify left bottom))
    )
    (fp_text user "License: Apache-2.0" (at -0.949 5.706 180) (layer "F.Fab") hide
        (effects (font (size 0.7 0.7) (thickness 0.15)) (justify left bottom))
    )
    (fp_text user "Author: Antmicro" (at -0.949 3.306 180) (layer "F.Fab") hide
        (effects (font (size 0.7 0.7) (thickness 0.15)) (justify left bottom))
    )
    (fp_text user "${REFERENCE}" (at -0.949 4.506 180) (layer "F.Fab") hide
        (effects (font (size 0.7 0.7) (thickness 0.15)) (justify left bottom))
    )
    (fp_line (start 0.03 -0.499) (end 0.4 -0.499)
      (stroke (width 0.15) (type solid)) (layer "F.SilkS"))
    (fp_line (start 0.03 0.499) (end 0.4 0.499)
      (stroke (width 0.15) (type solid)) (layer "F.SilkS"))
    (fp_line (start 0.4 -0.419) (end 0.4 -0.499)
      (stroke (width 0.15) (type solid)) (layer "F.SilkS"))
    (fp_line (start 0.4 0.42) (end 0.4 0.499)
      (stroke (width 0.15) (type solid)) (layer "F.SilkS"))
    (fp_circle (center -0.5 -0.6) (end -0.45 -0.6)
      (stroke (width 0.15) (type solid)) (fill solid) (layer "F.SilkS"))
    (fp_rect (start -0.8 -0.59) (end 0.8 0.59)
      (stroke (width 0.05) (type solid)) (fill none) (layer "F.CrtYd"))
    (fp_line (start -0.4 -0.499) (end 0.4 -0.499)
      (stroke (width 0.15) (type solid)) (layer "F.Fab"))
    (fp_line (start -0.4 0.499) (end -0.4 -0.499)
      (stroke (width 0.15) (type solid)) (layer "F.Fab"))
    (fp_line (start 0.4 -0.499) (end 0.4 0.499)
      (stroke (width 0.15) (type solid)) (layer "F.Fab"))
    (fp_line (start 0.4 0.499) (end -0.4 0.499)
      (stroke (width 0.15) (type solid)) (layer "F.Fab"))
    (pad "1" smd rect (at -0.52 -0.349 180) (size 0.46 0.2) (layers "F.Cu" "F.Paste" "F.Mask")
      (net 10 "VBUS") (pinfunction "IO1") (pintype "passive"))
    (pad "2" smd rect (at -0.52 0.348 180) (size 0.46 0.2) (layers "F.Cu" "F.Paste" "F.Mask")
      (net 10 "VBUS") (pinfunction "IO2") (pintype "passive"))
    (pad "3" smd rect (at 0.52 0 180) (size 0.46 0.2) (layers "F.Cu" "F.Paste" "F.Mask")
      (net 77 "GNDD") (pinfunction "GND") (pintype "passive"))
  )

  (footprint "antmicro-footprints:R_0402_1005Metric" (layer "F.Cu")
    (at 145.25 96.59)
    (descr "Resistor SMD 0402")
    (tags "resistor SMD 0402")
    (property "Author" "Antmicro")
    (property "Current" "1A")
    (property "License" "Apache-2.0")
    (property "MPN" "ERJ2GE0R00X")
    (property "Manufacturer" "Panasonic")
    (property "Sheetfile" "pow-cycl-curr-meas.kicad_sch")
    (property "Sheetname" "Power Cycling & Current Measurement")
    (property "Tolerance" "")
    (property "Val" "0R")
    (property "ki_description" "SMD Chip Resistor, Jumper, 0 ohm, 100 mW, 0402 [1005 Metric], Thick Film, General Purpose")
    (property "ki_keywords" "0402, SMT, RESISTOR, PASSIVE")
    (attr smd)
    (fp_text reference "R70" (at -1 -0.49) (layer "F.SilkS")
        (effects (font (size 0.7 0.7) (thickness 0.15)) (justify left bottom))
    )
    (fp_text value "R_0R_0402" (at -1.011843 1.772047) (layer "F.Fab")
        (effects (font (size 0.7 0.7) (thickness 0.15)) (justify left bottom))
    )
    (fp_text user "Author: Antmicro" (at -0.95 4.169) (layer "F.Fab") hide
        (effects (font (size 0.7 0.7) (thickness 0.15)) (justify left bottom))
    )
    (fp_text user "License: Apache-2.0" (at -0.95 5.169) (layer "F.Fab") hide
        (effects (font (size 0.7 0.7) (thickness 0.15)) (justify left bottom))
    )
    (fp_text user "${REFERENCE}" (at -0.95 3.168) (layer "F.Fab") hide
        (effects (font (size 0.7 0.7) (thickness 0.15)) (justify left bottom))
    )
    (fp_rect (start -0.925 -0.47) (end 0.925 0.47)
      (stroke (width 0.05) (type default)) (fill none) (layer "F.CrtYd"))
    (fp_rect (start -0.5 -0.25) (end 0.5 0.25)
      (stroke (width 0.15) (type solid)) (fill none) (layer "F.Fab"))
    (pad "1" smd roundrect (at -0.48 0) (size 0.59 0.64) (layers "F.Cu" "F.Paste" "F.Mask") (roundrect_rratio 0.25)
      (net 144 "Net-(R2-Pad1)") (pintype "passive"))
    (pad "2" smd roundrect (at 0.48 0) (size 0.59 0.64) (layers "F.Cu" "F.Paste" "F.Mask") (roundrect_rratio 0.25)
      (net 90 "/Power Cycling & Current Measurement/V_ADC1") (pintype "passive"))
  )

  (footprint "antmicro-footprints:R_0603_1608Metric" (layer "F.Cu")
    (at 131.2 53.85)
    (descr "Resistor SMD 0603")
    (tags "resistor SMD 0603")
    (property "Author" "Antmicro")
    (property "License" "Apache-2.0")
    (property "MPN" "CR0603-FX-4701ELF")
    (property "Manufacturer" "Bourns")
    (property "Sheetfile" "d1600e-psu-breakout-board.kicad_sch")
    (property "Sheetname" "")
    (property "Tolerance" "1%")
    (property "Val" "4k7")
    (property "ki_description" "SMD Chip Resistor, 4.7 kohm, ± 1%, 100 mW, 0603 [1608 Metric], Thick Film, General Purpose")
    (property "ki_keywords" "0603, SMT, RESISTOR, PASSIVE")
    (attr smd)
    (fp_text reference "R12" (at -1.1 1.65) (layer "F.SilkS")
        (effects (font (size 0.7 0.7) (thickness 0.15)) (justify left bottom))
    )
    (fp_text value "R_4k7_0603" (at 0 1.6) (layer "F.Fab")
        (effects (font (size 0.7 0.7) (thickness 0.15)) (justify left bottom))
    )
    (fp_text user "License: Apache-2.0" (at -1.25 5.9) (layer "F.Fab") hide
        (effects (font (size 0.7 0.7) (thickness 0.15)) (justify left bottom))
    )
    (fp_text user "Author: Antmicro" (at -1.25 4.9) (layer "F.Fab") hide
        (effects (font (size 0.7 0.7) (thickness 0.15)) (justify left bottom))
    )
    (fp_text user "${REFERENCE}" (at -1.25 3.898) (layer "F.Fab") hide
        (effects (font (size 0.7 0.7) (thickness 0.15)) (justify left bottom))
    )
    (fp_line (start -0.15 -0.4) (end 0.15 -0.4)
      (stroke (width 0.15) (type solid)) (layer "F.SilkS"))
    (fp_line (start -0.15 0.4) (end 0.15 0.4)
      (stroke (width 0.15) (type solid)) (layer "F.SilkS"))
    (fp_rect (start -1.25 -0.65) (end 1.25 0.65)
      (stroke (width 0.05) (type solid)) (fill none) (layer "F.CrtYd"))
    (fp_rect (start -0.8 -0.4) (end 0.8 0.4)
      (stroke (width 0.15) (type solid)) (fill none) (layer "F.Fab"))
    (pad "1" smd roundrect (at -0.7 0) (size 0.8 1) (layers "F.Cu" "F.Paste" "F.Mask") (roundrect_rratio 0.2)
      (net 37 "Net-(D4-A)") (pintype "passive"))
    (pad "2" smd roundrect (at 0.7 0) (size 0.8 1) (layers "F.Cu" "F.Paste" "F.Mask") (roundrect_rratio 0.2)
      (net 44 "LOAD_2") (pintype "passive"))
  )

  (footprint "antmicro-footprints:R_0402_1005Metric" (layer "F.Cu")
    (at 179.85 101.12)
    (descr "Resistor SMD 0402")
    (tags "resistor SMD 0402")
    (property "Author" "Antmicro")
    (property "Current" "1A")
    (property "License" "Apache-2.0")
    (property "MPN" "ERJ2GE0R00X")
    (property "Manufacturer" "Panasonic")
    (property "Sheetfile" "d1600e-psu-breakout-board.kicad_sch")
    (property "Sheetname" "")
    (property "Tolerance" "")
    (property "Val" "0R")
    (property "ki_description" "SMD Chip Resistor, Jumper, 0 ohm, 100 mW, 0402 [1005 Metric], Thick Film, General Purpose")
    (property "ki_keywords" "0402, SMT, RESISTOR, PASSIVE")
    (attr smd)
    (fp_text reference "R72" (at -1.122484 1.27) (layer "F.SilkS")
        (effects (font (size 0.7 0.7) (thickness 0.15)) (justify left bottom))
    )
    (fp_text value "R_0R_0402" (at -1.011843 1.772047) (layer "F.Fab")
        (effects (font (size 0.7 0.7) (thickness 0.15)) (justify left bottom))
    )
    (fp_text user "${REFERENCE}" (at -0.95 3.168) (layer "F.Fab") hide
        (effects (font (size 0.7 0.7) (thickness 0.15)) (justify left bottom))
    )
    (fp_text user "License: Apache-2.0" (at -0.95 5.169) (layer "F.Fab") hide
        (effects (font (size 0.7 0.7) (thickness 0.15)) (justify left bottom))
    )
    (fp_text user "Author: Antmicro" (at -0.95 4.169) (layer "F.Fab") hide
        (effects (font (size 0.7 0.7) (thickness 0.15)) (justify left bottom))
    )
    (fp_rect (start -0.925 -0.47) (end 0.925 0.47)
      (stroke (width 0.05) (type default)) (fill none) (layer "F.CrtYd"))
    (fp_rect (start -0.5 -0.25) (end 0.5 0.25)
      (stroke (width 0.15) (type solid)) (fill none) (layer "F.Fab"))
    (pad "1" smd roundrect (at -0.48 0) (size 0.59 0.64) (layers "F.Cu" "F.Paste" "F.Mask") (roundrect_rratio 0.25)
      (net 145 "LED_DATA") (pintype "passive"))
    (pad "2" smd roundrect (at 0.48 0) (size 0.59 0.64) (layers "F.Cu" "F.Paste" "F.Mask") (roundrect_rratio 0.25)
      (net 99 "SDA_CON") (pintype "passive"))
  )

  (footprint "antmicro-footprints:R_0402_1005Metric" (layer "F.Cu")
    (at 187.4 107.65 180)
    (descr "Resistor SMD 0402")
    (tags "resistor SMD 0402")
    (property "Author" "Antmicro")
    (property "License" "Apache-2.0")
    (property "MPN" "CR0402-FX-5101GLF")
    (property "Manufacturer" "Bourns")
    (property "Sheetfile" "ftdi-module.kicad_sch")
    (property "Sheetname" "FTDI")
    (property "Tolerance" "1%")
    (property "Val" "5k1")
    (property "ki_description" "SMD Chip Resistor, 5.1 kohm, ± 1%, 63 mW, 0402 [1005 Metric], Thick Film, General Purpose")
    (property "ki_keywords" "0402, SMT, RESISTOR, PASSIVE")
    (attr smd)
    (fp_text reference "R58" (at 0.05 1) (layer "F.SilkS")
        (effects (font (size 0.7 0.7) (thickness 0.15)))
    )
    (fp_text value "R_5k1_0402" (at 0 1.17) (layer "F.Fab") hide
        (effects (font (size 1 1) (thickness 0.15)))
    )
    (fp_text user "Author: Antmicro" (at -0.95 4.169 180) (layer "F.Fab") hide
        (effects (font (size 0.7 0.7) (thickness 0.15)) (justify left bottom))
    )
    (fp_text user "${REFERENCE}" (at 0 0) (layer "F.Fab")
        (effects (font (size 0.25 0.25) (thickness 0.04)))
    )
    (fp_text user "License: Apache-2.0" (at -0.95 5.169 180) (layer "F.Fab") hide
        (effects (font (size 0.7 0.7) (thickness 0.15)) (justify left bottom))
    )
    (fp_rect (start -0.925 -0.47) (end 0.925 0.47)
      (stroke (width 0.05) (type default)) (fill none) (layer "F.CrtYd"))
    (fp_rect (start -0.5 -0.25) (end 0.5 0.25)
      (stroke (width 0.15) (type solid)) (fill none) (layer "F.Fab"))
    (pad "1" smd roundrect (at -0.48 0 180) (size 0.59 0.64) (layers "F.Cu" "F.Paste" "F.Mask") (roundrect_rratio 0.25)
      (net 114 "Net-(U1-CC_{2})") (pintype "passive"))
    (pad "2" smd roundrect (at 0.48 0 180) (size 0.59 0.64) (layers "F.Cu" "F.Paste" "F.Mask") (roundrect_rratio 0.25)
      (net 77 "GNDD") (pintype "passive"))
  )

  (footprint "antmicro-footprints:R_0603_1608Metric" (layer "F.Cu")
    (at 96.9 104.4)
    (descr "Resistor SMD 0603")
    (tags "resistor SMD 0603")
    (property "Author" "Antmicro")
    (property "License" "Apache-2.0")
    (property "MPN" "CR0603-FX-2201ELF")
    (property "Manufacturer" "Bourns")
    (property "Sheetfile" "d1600e-psu-breakout-board.kicad_sch")
    (property "Sheetname" "")
    (property "Tolerance" "1%")
    (property "Val" "2k2")
    (property "ki_description" "SMD Chip Resistor, 2.2 kohm, ± 1%, 100 mW, 0603 [1608 Metric], Thick Film, General Purpose")
    (property "ki_keywords" "0603, SMT, RESISTOR, PASSIVE")
    (attr smd)
    (fp_text reference "R56" (at -1.2 -0.55) (layer "F.SilkS")
        (effects (font (size 0.7 0.7) (thickness 0.15)) (justify left bottom))
    )
    (fp_text value "R_2k2_0603" (at 0 1.6) (layer "F.Fab")
        (effects (font (size 0.7 0.7) (thickness 0.15)) (justify left bottom))
    )
    (fp_text user "License: Apache-2.0" (at -1.25 5.9) (layer "F.Fab") hide
        (effects (font (size 0.7 0.7) (thickness 0.15)) (justify left bottom))
    )
    (fp_text user "Author: Antmicro" (at -1.25 4.9) (layer "F.Fab") hide
        (effects (font (size 0.7 0.7) (thickness 0.15)) (justify left bottom))
    )
    (fp_text user "${REFERENCE}" (at -1.25 3.898) (layer "F.Fab") hide
        (effects (font (size 0.7 0.7) (thickness 0.15)) (justify left bottom))
    )
    (fp_line (start -0.15 -0.4) (end 0.15 -0.4)
      (stroke (width 0.15) (type solid)) (layer "F.SilkS"))
    (fp_line (start -0.15 0.4) (end 0.15 0.4)
      (stroke (width 0.15) (type solid)) (layer "F.SilkS"))
    (fp_rect (start -1.25 -0.65) (end 1.25 0.65)
      (stroke (width 0.05) (type solid)) (fill none) (layer "F.CrtYd"))
    (fp_rect (start -0.8 -0.4) (end 0.8 0.4)
      (stroke (width 0.15) (type solid)) (fill none) (layer "F.Fab"))
    (pad "1" smd roundrect (at -0.7 0) (size 0.8 1) (layers "F.Cu" "F.Paste" "F.Mask") (roundrect_rratio 0.2)
      (net 82 "Net-(D11-A)") (pintype "passive"))
    (pad "2" smd roundrect (at 0.7 0) (size 0.8 1) (layers "F.Cu" "F.Paste" "F.Mask") (roundrect_rratio 0.2)
      (net 11 "VCC12V0") (pintype "passive"))
  )

  (footprint "antmicro-footprints:Vishay_PowerPAK_1212-8_Single" (layer "F.Cu")
    (at 167.3 87.2 90)
    (descr "PowerPAK 1212-8 Single")
    (tags "Vishay PowerPAK 1212-8 Single")
    (property "Author" "Antmicro")
    (property "License" "Apache-2.0")
    (property "MPN" "SI7613DN-T1-GE3")
    (property "Manufacturer" "Vishay")
    (property "Sheetfile" "power-switch.kicad_sch")
    (property "Sheetname" "Power switch 4")
    (property "ki_description" "Power MOSFET, P Channel, 20 V, 35 A, 0.0072 ohm, PowerPAK 1212, Surface Mount")
    (property "ki_keywords" "SMT, TRANSISTOR, SEMICONDUCTOR, MOSFET, PMOS")
    (attr smd)
    (fp_text reference "QA4" (at -2.95 -1.05 180) (layer "F.SilkS")
        (effects (font (size 0.7 0.7) (thickness 0.15)) (justify left bottom))
    )
    (fp_text value "SI7613DN-T1-GE3" (at 0 2.7 90) (layer "F.Fab")
        (effects (font (size 0.7 0.7) (thickness 0.15)) (justify left bottom))
    )
    (fp_text user "Author: Antmicro" (at -8 5.9 90) (layer "F.Fab") hide
        (effects (font (size 0.7 0.7) (thickness 0.15)) (justify left bottom))
    )
    (fp_text user "${REFERENCE}" (at -8 4.7 90) (layer "F.Fab") hide
        (effects (font (size 0.7 0.7) (thickness 0.15)) (justify left bottom))
    )
    (fp_text user "License: Apache-2.0" (at -8 7.1 90) (layer "F.Fab") hide
        (effects (font (size 0.7 0.7) (thickness 0.15)) (justify left bottom))
    )
    (fp_line (start -1.651 -1.651) (end -1.651 -1.317)
      (stroke (width 0.15) (type solid)) (layer "F.SilkS"))
    (fp_line (start -1.651 -1.651) (end 1.648 -1.651)
      (stroke (width 0.15) (type solid)) (layer "F.SilkS"))
    (fp_line (start -1.635 1.3) (end -1.635 1.634)
      (stroke (width 0.15) (type solid)) (layer "F.SilkS"))
    (fp_line (start -1.635 1.634) (end 1.634 1.634)
      (stroke (width 0.15) (type solid)) (layer "F.SilkS"))
    (fp_line (start 1.634 1.3) (end 1.634 1.634)
      (stroke (width 0.15) (type solid)) (layer "F.SilkS"))
    (fp_line (start 1.648 -1.651) (end 1.648 -1.317)
      (stroke (width 0.15) (type solid)) (layer "F.SilkS"))
    (fp_circle (center -1.9 -1.4) (end -1.85 -1.4)
      (stroke (width 0.15) (type solid)) (fill solid) (layer "F.SilkS"))
    (fp_rect (start -2 -1.8) (end 2 1.798)
      (stroke (width 0.05) (type solid)) (fill none) (layer "F.CrtYd"))
    (fp_line (start -1.6425 -1.4175) (end -1.4175 -1.6425)
      (stroke (width 0.15) (type solid)) (layer "F.Fab"))
    (fp_rect (start -1.651 -1.651) (end 1.648 1.648)
      (stroke (width 0.15) (type solid)) (fill none) (layer "F.Fab"))
    (pad "1" smd rect (at -1.436 -0.99 90) (size 0.99 0.405) (layers "F.Cu" "F.Paste" "F.Mask")
      (net 11 "VCC12V0") (pinfunction "S") (pintype "passive"))
    (pad "2" smd rect (at -1.436 -0.332 90) (size 0.99 0.405) (layers "F.Cu" "F.Paste" "F.Mask")
      (net 11 "VCC12V0") (pinfunction "S") (pintype "passive"))
    (pad "3" smd rect (at -1.436 0.33 90) (size 0.99 0.405) (layers "F.Cu" "F.Paste" "F.Mask")
      (net 11 "VCC12V0") (pinfunction "S") (pintype "passive"))
    (pad "4" smd rect (at -1.436 0.988 90) (size 0.99 0.405) (layers "F.Cu" "F.Paste" "F.Mask")
      (net 96 "Net-(QA4-G)") (pinfunction "G") (pintype "passive"))
    (pad "5" smd custom (at 0.557 0 90) (size 1.725 2.235) (layers "F.Cu" "F.Paste" "F.Mask")
      (net 27 "C_MEAS_4") (pinfunction "D") (pintype "passive") (zone_connect 2)
      (options (clearance outline) (anchor rect))
      (primitives
        (gr_poly
          (pts
            (xy 0.8625 0.1275)
            (xy 0.8625 -0.1275)
            (xy 1.3725 -0.1275)
            (xy 1.3725 -0.5325)
            (xy 0.8625 -0.5325)
            (xy 0.8625 -0.7875)
            (xy 1.3725 -0.7875)
            (xy 1.3725 -1.195)
            (xy 0.6125 -1.195)
            (xy 0.6125 1.195)
            (xy 1.3725 1.195)
            (xy 1.3725 0.7875)
            (xy 0.8625 0.7875)
            (xy 0.8625 0.5325)
            (xy 1.3725 0.5325)
            (xy 1.3725 0.1275)
          )
          (width 0) (fill yes))
      ))
  )

  (footprint "antmicro-footprints:LED_0603_1608Metric_G" (layer "F.Cu")
    (at 145.9 53.85)
    (descr "LED SMD 0603 Green")
    (tags "LED SMD 0603 Green")
    (property "Author" "Antmicro")
    (property "Color" "Green")
    (property "License" "Apache-2.0")
    (property "MPN" "LG L29K-G2J1-24-Z")
    (property "Manufacturer" "OSRAM")
    (property "Sheetfile" "d1600e-psu-breakout-board.kicad_sch")
    (property "Sheetname" "")
    (property "ki_description" "LED, Green, SMD, 0603, 20 mA, 1.7 V, 570 nm")
    (property "ki_keywords" "SMT, DIODE, SEMICONDUCTOR, LED")
    (zone_connect 1)
    (attr smd)
    (fp_text reference "D6" (at -0.85 1.65) (layer "F.SilkS")
        (effects (font (size 0.7 0.7) (thickness 0.15)) (justify left bottom))
    )
    (fp_text value "LED_G_0603_LG_L29K-G2J1-24-Z" (at -0.001 1.599) (layer "F.Fab")
        (effects (font (size 0.7 0.7) (thickness 0.15)) (justify left bottom))
    )
    (fp_text user "License: Apache-2.0" (at -1.4224 3.599) (layer "F.Fab") hide
        (effects (font (size 0.7 0.7) (thickness 0.15)) (justify left bottom))
    )
    (fp_text user "${REFERENCE}" (at -1.4224 5.999) (layer "F.Fab") hide
        (effects (font (size 0.7 0.7) (thickness 0.15)) (justify left bottom))
    )
    (fp_text user "Author: Antmicro" (at -1.4224 4.799) (layer "F.Fab") hide
        (effects (font (size 0.7 0.7) (thickness 0.15)) (justify left bottom))
    )
    (fp_line (start -1.18 -0.319) (end -1.18 0.321)
      (stroke (width 0.15) (type solid)) (layer "F.SilkS"))
    (fp_line (start -0.094672 0.001008) (end -0.24 0.001008)
      (stroke (width 0.1) (type solid)) (layer "F.SilkS"))
    (fp_line (start -0.094672 0.001008) (end 0.105328 -0.198992)
      (stroke (width 0.1) (type solid)) (layer "F.SilkS"))
    (fp_line (start -0.094672 0.201008) (end -0.094672 -0.198992)
      (stroke (width 0.1) (type solid)) (layer "F.SilkS"))
    (fp_line (start 0.105328 0.001008) (end 0.24 0.001)
      (stroke (width 0.1) (type solid)) (layer "F.SilkS"))
    (fp_line (start 0.105328 0.201008) (end -0.094672 0.001008)
      (stroke (width 0.1) (type solid)) (layer "F.SilkS"))
    (fp_line (start 0.105328 0.201008) (end 0.105328 -0.198992)
      (stroke (width 0.1) (type solid)) (layer "F.SilkS"))
    (fp_line (start 0.22 -0.35) (end -0.22 -0.35)
      (stroke (width 0.15) (type solid)) (layer "F.SilkS"))
    (fp_line (start 0.22 0.35) (end -0.22 0.35)
      (stroke (width 0.15) (type solid)) (layer "F.SilkS"))
    (fp_rect (start 1.25 0.65) (end -1.25 -0.65)
      (stroke (width 0.05) (type solid)) (fill none) (layer "F.CrtYd"))
    (fp_line (start -0.199 -0.202) (end -0.199 0.1)
      (stroke (width 0.15) (type solid)) (layer "F.Fab"))
    (fp_line (start -0.199 0) (end -0.597 0)
      (stroke (width 0.15) (type solid)) (layer "F.Fab"))
    (fp_line (start -0.199 0.2) (end -0.199 0.1)
      (stroke (width 0.15) (type solid)) (layer "F.Fab"))
    (fp_line (start -0.101 0) (end 0.201 0.2)
      (stroke (width 0.15) (type solid)) (layer "F.Fab"))
    (fp_line (start 0.201 -0.202) (end -0.101 0)
      (stroke (width 0.15) (type solid)) (layer "F.Fab"))
    (fp_line (start 0.201 0) (end 0.201 -0.202)
      (stroke (width 0.15) (type solid)) (layer "F.Fab"))
    (fp_line (start 0.201 0.2) (end 0.201 0)
      (stroke (width 0.15) (type solid)) (layer "F.Fab"))
    (fp_line (start 0.599 0) (end 0.201 0)
      (stroke (width 0.15) (type solid)) (layer "F.Fab"))
    (fp_rect (start 0.848 0.4) (end -0.85 -0.402)
      (stroke (width 0.15) (type solid)) (fill none) (layer "F.Fab"))
    (pad "1" smd roundrect (at -0.7 0 180) (size 0.8 1) (layers "F.Cu" "F.Paste" "F.Mask") (roundrect_rratio 0.2)
      (net 4 "GND") (pinfunction "C") (pintype "passive"))
    (pad "2" smd roundrect (at 0.7 0 180) (size 0.8 1) (layers "F.Cu" "F.Paste" "F.Mask") (roundrect_rratio 0.2)
      (net 40 "Net-(D6-A)") (pinfunction "A") (pintype "passive"))
  )

  (footprint "antmicro-footprints:PinHeader_1x3_P2.54mm_Drill1.1mm" (layer "F.Cu")
    (at 105.85 81.29 90)
    (property "Author" "Antmicro")
    (property "License" "Apache-2.0")
    (property "MPN" "61300311121")
    (property "Manufacturer" "Würth Elektronik")
    (property "Sheetfile" "daughterboard-supply.kicad_sch")
    (property "Sheetname" "daughterboard-supply")
    (property "ki_description" "Pin Header, Vertical, Board-to-Board, 2.54 mm, 1 Rows, 3 Contacts, Through Hole Straight, WR-PHD")
    (property "ki_keywords" "VERTICAL, THT, HEADER, CONNECTOR, MALE")
    (attr through_hole)
    (fp_text reference "SW1" (at 0 0 90) (layer "F.SilkS") hide
        (effects (font (size 0.7 0.7) (thickness 0.15)))
    )
    (fp_text value "PinHeader_1x3_P2.54mm_Drill1.1mm" (at 0 0 90) (layer "F.SilkS") hide
        (effects (font (size 1.524 1.524) (thickness 0.05)))
    )
    (fp_text user "License: Apache-2.0" (at -1.6 6.6 90) (layer "F.Fab") hide
        (effects (font (size 0.7 0.7) (thickness 0.15)) (justify left bottom))
    )
    (fp_text user "${REFERENCE}" (at -1.6 4 90) (layer "F.Fab") hide
        (effects (font (size 0.7 0.7) (thickness 0.15)) (justify left bottom))
    )
    (fp_text user "Author: Antmicro" (at -1.6 5.2 90) (layer "F.Fab") hide
        (effects (font (size 0.7 0.7) (thickness 0.15)) (justify left bottom))
    )
    (fp_line (start -1.401 -1.401) (end -1.401 -0.902)
      (stroke (width 0.15) (type solid)) (layer "F.SilkS"))
    (fp_line (start -1.401 -1.401) (end -0.902 -1.401)
      (stroke (width 0.15) (type solid)) (layer "F.SilkS"))
    (fp_line (start -1.401 1.398) (end -1.401 0.9)
      (stroke (width 0.15) (type solid)) (layer "F.SilkS"))
    (fp_line (start -1.401 1.398) (end -0.902 1.398)
      (stroke (width 0.15) (type solid)) (layer "F.SilkS"))
    (fp_line (start 6.499 -1.401) (end 5.999 -1.401)
      (stroke (width 0.15) (type solid)) (layer "F.SilkS"))
    (fp_line (start 6.499 -1.401) (end 6.499 -0.902)
      (stroke (width 0.15) (type solid)) (layer "F.SilkS"))
    (fp_line (start 6.499 1.398) (end 5.999 1.398)
      (stroke (width 0.15) (type solid)) (layer "F.SilkS"))
    (fp_line (start 6.499 1.398) (end 6.499 0.9)
      (stroke (width 0.15) (type solid)) (layer "F.SilkS"))
    (fp_line (start -1.52 -1.52) (end -1.52 1.5)
      (stroke (width 0.05) (type solid)) (layer "F.CrtYd"))
    (fp_line (start -1.52 -1.52) (end 6.58 -1.52)
      (stroke (width 0.05) (type solid)) (layer "F.CrtYd"))
    (fp_line (start -1.52 1.5) (end 6.58 1.5)
      (stroke (width 0.05) (type solid)) (layer "F.CrtYd"))
    (fp_line (start 6.58 -1.52) (end 6.58 1.5)
      (stroke (width 0.05) (type solid)) (layer "F.CrtYd"))
    (fp_line (start -1.27 -1.27) (end -1.27 1.269)
      (stroke (width 0.15) (type solid)) (layer "F.Fab"))
    (fp_line (start -1.27 -1.27) (end 6.349 -1.27)
      (stroke (width 0.15) (type solid)) (layer "F.Fab"))
    (fp_line (start -1.27 1.269) (end 6.349 1.269)
      (stroke (width 0.15) (type solid)) (layer "F.Fab"))
    (fp_line (start 6.349 -1.27) (end 6.349 1.269)
      (stroke (width 0.15) (type solid)) (layer "F.Fab"))
    (pad "1" thru_hole rect (at 0 0 90) (size 1.7 1.7) (drill 1.1) (layers "*.Cu" "*.Mask")
      (net 2 "VCC5V0") (pintype "passive"))
    (pad "2" thru_hole circle (at 2.539 0 90) (size 1.7 1.7) (drill 1.1) (layers "*.Cu" "*.Mask")
      (net 137 "Net-(J9-Pad8)") (pintype "passive"))
    (pad "3" thru_hole circle (at 5.078 0 90) (size 1.7 1.7) (drill 1.1) (layers "*.Cu" "*.Mask")
      (net 4 "GND") (pintype "passive"))
  )

  (footprint "antmicro-footprints:TP_SMD_1mm" (layer "F.Cu")
    (at 184.2 111.15)
    (property "Author" "Antmicro")
    (property "License" "Apache-2.0")
    (property "MPN" "")
    (property "Manufacturer" "")
    (property "Sheetfile" "ftdi-module.kicad_sch")
    (property "Sheetname" "FTDI")
    (property "exclude_from_bom" "")
    (property "ki_description" "Test point 1mm SMD")
    (property "ki_keywords" "TESTPOINT")
    (attr exclude_from_pos_files exclude_from_bom)
    (fp_text reference "TP2" (at 0.65 -0.6 90) (layer "F.SilkS")
        (effects (font (size 0.7 0.7) (thickness 0.15)) (justify left bottom))
    )
    (fp_text value "TP_1mm_SMD" (at 0 1.4) (layer "F.Fab")
        (effects (font (size 0.7 0.7) (thickness 0.15)) (justify left bottom))
    )
    (fp_text user "${REFERENCE}" (at -0.5 2.8) (layer "F.Fab") hide
        (effects (font (size 0.7 0.7) (thickness 0.15)) (justify left bottom))
    )
    (fp_text user "License: Apache-2.0" (at -0.5 5.2) (layer "F.Fab") hide
        (effects (font (size 0.7 0.7) (thickness 0.15)) (justify left bottom))
    )
    (fp_text user "Author: Antmicro" (at -0.5 4) (layer "F.Fab") hide
        (effects (font (size 0.7 0.7) (thickness 0.15)) (justify left bottom))
    )
    (fp_circle (center 0 0) (end 0.6 0)
      (stroke (width 0.05) (type default)) (fill none) (layer "F.CrtYd"))
    (pad "1" smd circle (at 0 0) (size 1 1) (layers "F.Cu" "F.Mask")
      (net 117 "Net-(U1-SBU_{1})") (pinfunction "1") (pintype "passive"))
  )

  (footprint "antmicro-footprints:Conn_Molex_KK_1x4_22-27-2041" (layer "F.Cu")
    (at 134.81 53.75)
    (property "Author" "Antmicro")
    (property "License" "Apache-2.0")
    (property "MPN" "22-27-2041")
    (property "Manufacturer" "Molex")
    (property "Sheetfile" "d1600e-psu-breakout-board.kicad_sch")
    (property "Sheetname" "")
    (property "ki_description" "Rectangular connector (header, female pins)")
    (property "ki_keywords" "VERTICAL, THT, HEADER, CONNECTOR, MALE")
    (attr through_hole)
    (fp_text reference "J12" (at 4.64 4.325) (layer "F.SilkS")
        (effects (font (size 0.7 0.7) (thickness 0.15)) (justify left bottom))
    )
    (fp_text value "Molex_KK_1x4_22-27-2041" (at -0.8 4.6 180) (layer "F.Fab")
        (effects (font (size 0.7 0.7) (thickness 0.15)) (justify left bottom))
    )
    (fp_text user "${REFERENCE}" (at -2.12 9.15) (layer "F.Fab") hide
        (effects (font (size 0.7 0.7) (thickness 0.15)) (justify left bottom))
    )
    (fp_text user "License: Apache-2.0" (at -2.12 7.95) (layer "F.Fab") hide
        (effects (font (size 0.7 0.7) (thickness 0.15)) (justify left bottom))
    )
    (fp_text user "Author: Antmicro" (at -2.12 6.75) (layer "F.Fab") hide
        (effects (font (size 0.7 0.7) (thickness 0.15)) (justify left bottom))
    )
    (fp_line (start -1.39 -3.03) (end -1.39 2.99)
      (stroke (width 0.15) (type solid)) (layer "F.SilkS"))
    (fp_line (start -1.39 2.99) (end 8.99 2.99)
      (stroke (width 0.15) (type solid)) (layer "F.SilkS"))
    (fp_line (start -0.81 -3.03) (end -0.81 -2.43)
      (stroke (width 0.15) (type solid)) (layer "F.SilkS"))
    (fp_line (start -0.81 -2.43) (end 0.79 -2.43)
      (stroke (width 0.15) (type solid)) (layer "F.SilkS"))
    (fp_line (start -0.01 1.99) (end 0.24 1.46)
      (stroke (width 0.15) (type solid)) (layer "F.SilkS"))
    (fp_line (start -0.01 1.99) (end 7.61 1.99)
      (stroke (width 0.15) (type solid)) (layer "F.SilkS"))
    (fp_line (start -0.01 2.99) (end -0.01 1.99)
      (stroke (width 0.15) (type solid)) (layer "F.SilkS"))
    (fp_line (start 0.24 1.46) (end 7.36 1.46)
      (stroke (width 0.15) (type solid)) (layer "F.SilkS"))
    (fp_line (start 0.24 2.99) (end 0.24 1.99)
      (stroke (width 0.15) (type solid)) (layer "F.SilkS"))
    (fp_line (start 0.79 -2.43) (end 0.79 -3.03)
      (stroke (width 0.15) (type solid)) (layer "F.SilkS"))
    (fp_line (start 1.73 -3.03) (end 1.73 -2.43)
      (stroke (width 0.15) (type solid)) (layer "F.SilkS"))
    (fp_line (start 1.73 -2.43) (end 3.33 -2.43)
      (stroke (width 0.15) (type solid)) (layer "F.SilkS"))
    (fp_line (start 3.33 -2.43) (end 3.33 -3.03)
      (stroke (width 0.15) (type solid)) (layer "F.SilkS"))
    (fp_line (start 4.27 -3.03) (end 4.27 -2.43)
      (stroke (width 0.15) (type solid)) (layer "F.SilkS"))
    (fp_line (start 4.27 -2.43) (end 5.87 -2.43)
      (stroke (width 0.15) (type solid)) (layer "F.SilkS"))
    (fp_line (start 5.87 -2.43) (end 5.87 -3.03)
      (stroke (width 0.15) (type solid)) (layer "F.SilkS"))
    (fp_line (start 6.81 -3.03) (end 6.81 -2.43)
      (stroke (width 0.15) (type solid)) (layer "F.SilkS"))
    (fp_line (start 6.81 -2.43) (end 8.41 -2.43)
      (stroke (width 0.15) (type solid)) (layer "F.SilkS"))
    (fp_line (start 7.36 1.46) (end 7.61 1.99)
      (stroke (width 0.15) (type solid)) (layer "F.SilkS"))
    (fp_line (start 7.36 2.99) (end 7.36 1.99)
      (stroke (width 0.15) (type solid)) (layer "F.SilkS"))
    (fp_line (start 7.61 1.99) (end 7.61 2.99)
      (stroke (width 0.15) (type solid)) (layer "F.SilkS"))
    (fp_line (start 8.41 -2.43) (end 8.41 -3.03)
      (stroke (width 0.15) (type solid)) (layer "F.SilkS"))
    (fp_line (start 8.99 -3.03) (end -1.39 -3.03)
      (stroke (width 0.15) (type solid)) (layer "F.SilkS"))
    (fp_line (start 8.99 2.99) (end 8.99 -3.03)
      (stroke (width 0.15) (type solid)) (layer "F.SilkS"))
    (fp_line (start -1.79 -3.38) (end -1.79 3.42)
      (stroke (width 0.05) (type solid)) (layer "F.CrtYd"))
    (fp_line (start -1.79 3.42) (end 9.37 3.42)
      (stroke (width 0.05) (type solid)) (layer "F.CrtYd"))
    (fp_line (start 9.37 -3.38) (end -1.79 -3.38)
      (stroke (width 0.05) (type solid)) (layer "F.CrtYd"))
    (fp_line (start 9.37 3.42) (end 9.37 -3.38)
      (stroke (width 0.05) (type solid)) (layer "F.CrtYd"))
    (fp_line (start -1.29 -2.88) (end -1.29 2.92)
      (stroke (width 0.15) (type solid)) (layer "F.Fab"))
    (fp_line (start -1.29 2.92) (end 8.87 2.92)
      (stroke (width 0.15) (type solid)) (layer "F.Fab"))
    (fp_line (start 8.163 0) (end 8.87 -0.5)
      (stroke (width 0.15) (type solid)) (layer "F.Fab"))
    (fp_line (start 8.87 -2.88) (end -1.29 -2.88)
      (stroke (width 0.15) (type solid)) (layer "F.Fab"))
    (fp_line (start 8.87 0.5) (end 8.163 0)
      (stroke (width 0.15) (type solid)) (layer "F.Fab"))
    (fp_line (start 8.87 2.92) (end 8.87 -2.88)
      (stroke (width 0.15) (type solid)) (layer "F.Fab"))
    (pad "1" thru_hole roundrect (at 0 0) (size 1.74 2.19) (drill 1.19) (layers "*.Cu" "*.Mask") (roundrect_rratio 0.143678)
      (net 11 "VCC12V0") (pintype "passive"))
    (pad "2" thru_hole oval (at 2.54 0) (size 1.74 2.19) (drill 1.19) (layers "*.Cu" "*.Mask")
      (net 4 "GND") (pintype "passive"))
    (pad "3" thru_hole oval (at 5.08 0) (size 1.74 2.19) (drill 1.19) (layers "*.Cu" "*.Mask")
      (net 4 "GND") (pintype "passive"))
    (pad "4" thru_hole oval (at 7.62 0) (size 1.74 2.19) (drill 1.19) (layers "*.Cu" "*.Mask")
      (net 2 "VCC5V0") (pintype "passive"))
  )

  (footprint "antmicro-footprints:Conn_Molex_KK_1x4_22-27-2041" (layer "F.Cu")
    (at 169.12 54.01)
    (property "Author" "Antmicro")
    (property "License" "Apache-2.0")
    (property "MPN" "22-27-2041")
    (property "Manufacturer" "Molex")
    (property "Sheetfile" "d1600e-psu-breakout-board.kicad_sch")
    (property "Sheetname" "")
    (property "ki_description" "Rectangular connector (header, female pins)")
    (property "ki_keywords" "VERTICAL, THT, HEADER, CONNECTOR, MALE")
    (attr through_hole)
    (fp_text reference "J14" (at 4.48 4.14) (layer "F.SilkS")
        (effects (font (size 0.7 0.7) (thickness 0.15)) (justify left bottom))
    )
    (fp_text value "Molex_KK_1x4_22-27-2041" (at -0.8 4.6 180) (layer "F.Fab")
        (effects (font (size 0.7 0.7) (thickness 0.15)) (justify left bottom))
    )
    (fp_text user "Author: Antmicro" (at -2.12 6.75) (layer "F.Fab") hide
        (effects (font (size 0.7 0.7) (thickness 0.15)) (justify left bottom))
    )
    (fp_text user "License: Apache-2.0" (at -2.12 7.95) (layer "F.Fab") hide
        (effects (font (size 0.7 0.7) (thickness 0.15)) (justify left bottom))
    )
    (fp_text user "${REFERENCE}" (at -2.12 9.15) (layer "F.Fab") hide
        (effects (font (size 0.7 0.7) (thickness 0.15)) (justify left bottom))
    )
    (fp_line (start -1.39 -3.03) (end -1.39 2.99)
      (stroke (width 0.15) (type solid)) (layer "F.SilkS"))
    (fp_line (start -1.39 2.99) (end 8.99 2.99)
      (stroke (width 0.15) (type solid)) (layer "F.SilkS"))
    (fp_line (start -0.81 -3.03) (end -0.81 -2.43)
      (stroke (width 0.15) (type solid)) (layer "F.SilkS"))
    (fp_line (start -0.81 -2.43) (end 0.79 -2.43)
      (stroke (width 0.15) (type solid)) (layer "F.SilkS"))
    (fp_line (start -0.01 1.99) (end 0.24 1.46)
      (stroke (width 0.15) (type solid)) (layer "F.SilkS"))
    (fp_line (start -0.01 1.99) (end 7.61 1.99)
      (stroke (width 0.15) (type solid)) (layer "F.SilkS"))
    (fp_line (start -0.01 2.99) (end -0.01 1.99)
      (stroke (width 0.15) (type solid)) (layer "F.SilkS"))
    (fp_line (start 0.24 1.46) (end 7.36 1.46)
      (stroke (width 0.15) (type solid)) (layer "F.SilkS"))
    (fp_line (start 0.24 2.99) (end 0.24 1.99)
      (stroke (width 0.15) (type solid)) (layer "F.SilkS"))
    (fp_line (start 0.79 -2.43) (end 0.79 -3.03)
      (stroke (width 0.15) (type solid)) (layer "F.SilkS"))
    (fp_line (start 1.73 -3.03) (end 1.73 -2.43)
      (stroke (width 0.15) (type solid)) (layer "F.SilkS"))
    (fp_line (start 1.73 -2.43) (end 3.33 -2.43)
      (stroke (width 0.15) (type solid)) (layer "F.SilkS"))
    (fp_line (start 3.33 -2.43) (end 3.33 -3.03)
      (stroke (width 0.15) (type solid)) (layer "F.SilkS"))
    (fp_line (start 4.27 -3.03) (end 4.27 -2.43)
      (stroke (width 0.15) (type solid)) (layer "F.SilkS"))
    (fp_line (start 4.27 -2.43) (end 5.87 -2.43)
      (stroke (width 0.15) (type solid)) (layer "F.SilkS"))
    (fp_line (start 5.87 -2.43) (end 5.87 -3.03)
      (stroke (width 0.15) (type solid)) (layer "F.SilkS"))
    (fp_line (start 6.81 -3.03) (end 6.81 -2.43)
      (stroke (width 0.15) (type solid)) (layer "F.SilkS"))
    (fp_line (start 6.81 -2.43) (end 8.41 -2.43)
      (stroke (width 0.15) (type solid)) (layer "F.SilkS"))
    (fp_line (start 7.36 1.46) (end 7.61 1.99)
      (stroke (width 0.15) (type solid)) (layer "F.SilkS"))
    (fp_line (start 7.36 2.99) (end 7.36 1.99)
      (stroke (width 0.15) (type solid)) (layer "F.SilkS"))
    (fp_line (start 7.61 1.99) (end 7.61 2.99)
      (stroke (width 0.15) (type solid)) (layer "F.SilkS"))
    (fp_line (start 8.41 -2.43) (end 8.41 -3.03)
      (stroke (width 0.15) (type solid)) (layer "F.SilkS"))
    (fp_line (start 8.99 -3.03) (end -1.39 -3.03)
      (stroke (width 0.15) (type solid)) (layer "F.SilkS"))
    (fp_line (start 8.99 2.99) (end 8.99 -3.03)
      (stroke (width 0.15) (type solid)) (layer "F.SilkS"))
    (fp_line (start -1.79 -3.38) (end -1.79 3.42)
      (stroke (width 0.05) (type solid)) (layer "F.CrtYd"))
    (fp_line (start -1.79 3.42) (end 9.37 3.42)
      (stroke (width 0.05) (type solid)) (layer "F.CrtYd"))
    (fp_line (start 9.37 -3.38) (end -1.79 -3.38)
      (stroke (width 0.05) (type solid)) (layer "F.CrtYd"))
    (fp_line (start 9.37 3.42) (end 9.37 -3.38)
      (stroke (width 0.05) (type solid)) (layer "F.CrtYd"))
    (fp_line (start -1.29 -2.88) (end -1.29 2.92)
      (stroke (width 0.15) (type solid)) (layer "F.Fab"))
    (fp_line (start -1.29 2.92) (end 8.87 2.92)
      (stroke (width 0.15) (type solid)) (layer "F.Fab"))
    (fp_line (start 8.163 0) (end 8.87 -0.5)
      (stroke (width 0.15) (type solid)) (layer "F.Fab"))
    (fp_line (start 8.87 -2.88) (end -1.29 -2.88)
      (stroke (width 0.15) (type solid)) (layer "F.Fab"))
    (fp_line (start 8.87 0.5) (end 8.163 0)
      (stroke (width 0.15) (type solid)) (layer "F.Fab"))
    (fp_line (start 8.87 2.92) (end 8.87 -2.88)
      (stroke (width 0.15) (type solid)) (layer "F.Fab"))
    (pad "1" thru_hole roundrect (at 0 0) (size 1.74 2.19) (drill 1.19) (layers "*.Cu" "*.Mask") (roundrect_rratio 0.143678)
      (net 11 "VCC12V0") (pintype "passive"))
    (pad "2" thru_hole oval (at 2.54 0) (size 1.74 2.19) (drill 1.19) (layers "*.Cu" "*.Mask")
      (net 4 "GND") (pintype "passive"))
    (pad "3" thru_hole oval (at 5.08 0) (size 1.74 2.19) (drill 1.19) (layers "*.Cu" "*.Mask")
      (net 4 "GND") (pintype "passive"))
    (pad "4" thru_hole oval (at 7.62 0) (size 1.74 2.19) (drill 1.19) (layers "*.Cu" "*.Mask")
      (net 2 "VCC5V0") (pintype "passive"))
  )

  (footprint "antmicro-footprints:TP_SMD_1mm" (layer "F.Cu")
    (at 107.75 79.95)
    (property "Author" "Antmicro")
    (property "License" "Apache-2.0")
    (property "MPN" "")
    (property "Manufacturer" "")
    (property "Sheetfile" "daughterboard-supply.kicad_sch")
    (property "Sheetname" "daughterboard-supply")
    (property "exclude_from_bom" "")
    (property "ki_description" "Test point 1mm SMD")
    (property "ki_keywords" "TESTPOINT")
    (attr exclude_from_pos_files exclude_from_bom)
    (fp_text reference "TP5" (at 0.4 -0.75) (layer "F.SilkS")
        (effects (font (size 0.7 0.7) (thickness 0.15)) (justify left bottom))
    )
    (fp_text value "TP_1mm_SMD" (at 0 1.4) (layer "F.Fab")
        (effects (font (size 0.7 0.7) (thickness 0.15)) (justify left bottom))
    )
    (fp_text user "Author: Antmicro" (at -0.5 4) (layer "F.Fab") hide
        (effects (font (size 0.7 0.7) (thickness 0.15)) (justify left bottom))
    )
    (fp_text user "License: Apache-2.0" (at -0.5 5.2) (layer "F.Fab") hide
        (effects (font (size 0.7 0.7) (thickness 0.15)) (justify left bottom))
    )
    (fp_text user "${REFERENCE}" (at -0.5 2.8) (layer "F.Fab") hide
        (effects (font (size 0.7 0.7) (thickness 0.15)) (justify left bottom))
    )
    (fp_circle (center 0 0) (end 0.6 0)
      (stroke (width 0.05) (type default)) (fill none) (layer "F.CrtYd"))
    (pad "1" smd circle (at 0 0) (size 1 1) (layers "F.Cu" "F.Mask")
      (net 137 "Net-(J9-Pad8)") (pinfunction "1") (pintype "passive"))
  )

  (footprint "antmicro-footprints:R_0402_1005Metric" (layer "F.Cu")
    (at 165.1 100.85 -90)
    (descr "Resistor SMD 0402")
    (tags "resistor SMD 0402")
    (property "Author" "Antmicro")
    (property "License" "Apache-2.0")
    (property "MPN" "CR0402-FX-4701GLF")
    (property "Manufacturer" "Bourns")
    (property "Sheetfile" "ftdi-module.kicad_sch")
    (property "Sheetname" "FTDI")
    (property "Tolerance" "1%")
    (property "Val" "4k7")
    (property "ki_description" "SMD Chip Resistor, 4.7 kohm, ± 1%, 62.5 mW, 0402 [1005 Metric], Thick Film, General Purpose")
    (property "ki_keywords" "0402, SMT, RESISTOR, PASSIVE")
    (attr smd)
    (fp_text reference "R37" (at 1.75 0.55 -90) (layer "F.SilkS")
        (effects (font (size 0.7 0.7) (thickness 0.15)) (justify left bottom))
    )
    (fp_text value "R_4k7_0402" (at -1.011843 1.772047 -90) (layer "F.Fab")
        (effects (font (size 0.7 0.7) (thickness 0.15)) (justify left bottom))
    )
    (fp_text user "${REFERENCE}" (at -0.95 3.168 -90) (layer "F.Fab") hide
        (effects (font (size 0.7 0.7) (thickness 0.15)) (justify left bottom))
    )
    (fp_text user "Author: Antmicro" (at -0.95 4.169 -90) (layer "F.Fab") hide
        (effects (font (size 0.7 0.7) (thickness 0.15)) (justify left bottom))
    )
    (fp_text user "License: Apache-2.0" (at -0.95 5.169 -90) (layer "F.Fab") hide
        (effects (font (size 0.7 0.7) (thickness 0.15)) (justify left bottom))
    )
    (fp_rect (start -0.925 -0.47) (end 0.925 0.47)
      (stroke (width 0.05) (type default)) (fill none) (layer "F.CrtYd"))
    (fp_rect (start -0.5 -0.25) (end 0.5 0.25)
      (stroke (width 0.15) (type solid)) (fill none) (layer "F.Fab"))
    (pad "1" smd roundrect (at -0.48 0 270) (size 0.59 0.64) (layers "F.Cu" "F.Paste" "F.Mask") (roundrect_rratio 0.25)
      (net 18 "SDA") (pintype "passive"))
    (pad "2" smd roundrect (at 0.48 0 270) (size 0.59 0.64) (layers "F.Cu" "F.Paste" "F.Mask") (roundrect_rratio 0.25)
      (net 1 "VCC3V3") (pintype "passive"))
  )

  (footprint "antmicro-footprints:TP_SMD_1mm" (layer "F.Cu")
    (at 184.4 117.3)
    (property "Author" "Antmicro")
    (property "License" "Apache-2.0")
    (property "MPN" "")
    (property "Manufacturer" "")
    (property "Sheetfile" "ftdi-module.kicad_sch")
    (property "Sheetname" "FTDI")
    (property "exclude_from_bom" "")
    (property "ki_description" "Test point 1mm SMD")
    (property "ki_keywords" "TESTPOINT")
    (attr exclude_from_pos_files exclude_from_bom)
    (fp_text reference "TP1" (at 0.9 2.45 180) (layer "F.SilkS")
        (effects (font (size 0.7 0.7) (thickness 0.15)) (justify left bottom))
    )
    (fp_text value "TP_1mm_SMD" (at 0 1.4) (layer "F.Fab")
        (effects (font (size 0.7 0.7) (thickness 0.15)) (justify left bottom))
    )
    (fp_text user "Author: Antmicro" (at -0.5 4) (layer "F.Fab") hide
        (effects (font (size 0.7 0.7) (thickness 0.15)) (justify left bottom))
    )
    (fp_text user "${REFERENCE}" (at -0.5 2.8) (layer "F.Fab") hide
        (effects (font (size 0.7 0.7) (thickness 0.15)) (justify left bottom))
    )
    (fp_text user "License: Apache-2.0" (at -0.5 5.2) (layer "F.Fab") hide
        (effects (font (size 0.7 0.7) (thickness 0.15)) (justify left bottom))
    )
    (fp_circle (center 0 0) (end 0.6 0)
      (stroke (width 0.05) (type default)) (fill none) (layer "F.CrtYd"))
    (pad "1" smd circle (at 0 0) (size 1 1) (layers "F.Cu" "F.Mask")
      (net 113 "Net-(U1-CC_{1})") (pinfunction "1") (pintype "passive"))
  )

  (footprint "antmicro-footprints:D_SOD-323" (layer "F.Cu")
    (at 118.1 91.4 -90)
    (property "Author" "Antmicro")
    (property "License" "Apache-2.0")
    (property "MPN" "BZT52B15SV-T")
    (property "Manufacturer" "Rectron")
    (property "Sheetfile" "power-switch.kicad_sch")
    (property "Sheetname" "Power switch 1")
    (property "ki_description" "Zener Single Diode, AEC-Q101, 15 V, 500 mW, SOD-323, 2 Pins, 150 °C, Surface Mount")
    (property "ki_keywords" "SMT, DIODE, SEMICONDUCTOR, ZENER")
    (attr smd)
    (fp_text reference "D15" (at 2.7 2.6) (layer "F.SilkS")
        (effects (font (size 0.7 0.7) (thickness 0.15)) (justify left bottom))
    )
    (fp_text value "BZT52B15SV-T" (at 0 1.841 -90) (layer "F.Fab")
        (effects (font (size 0.7 0.7) (thickness 0.15)) (justify left bottom))
    )
    (fp_text user "${REFERENCE}" (at -1.4 5.041 -90) (layer "F.Fab") hide
        (effects (font (size 0.7 0.7) (thickness 0.15)) (justify left bottom))
    )
    (fp_text user "Author: Antmicro" (at -1.4 6.241 -90) (layer "F.Fab") hide
        (effects (font (size 0.7 0.7) (thickness 0.15)) (justify left bottom))
    )
    (fp_text user "License: Apache-2.0" (at -1.4 3.841 -90) (layer "F.Fab") hide
        (effects (font (size 0.7 0.7) (thickness 0.15)) (justify left bottom))
    )
    (fp_line (start -0.949 -0.749) (end -0.949 -0.499)
      (stroke (width 0.15) (type solid)) (layer "F.SilkS"))
    (fp_line (start -0.949 0.501) (end -0.949 0.751)
      (stroke (width 0.15) (type solid)) (layer "F.SilkS"))
    (fp_line (start -0.6 -0.499) (end -0.6 0.499)
      (stroke (width 0.15) (type solid)) (layer "F.SilkS"))
    (fp_line (start -0.577 -0.749) (end -0.949 -0.749)
      (stroke (width 0.15) (type solid)) (layer "F.SilkS"))
    (fp_line (start -0.577 0.751) (end -0.949 0.751)
      (stroke (width 0.15) (type solid)) (layer "F.SilkS"))
    (fp_line (start 0.625 -0.736) (end 0.949 -0.736)
      (stroke (width 0.15) (type solid)) (layer "F.SilkS"))
    (fp_line (start 0.949 -0.736) (end 0.949 -0.499)
      (stroke (width 0.15) (type solid)) (layer "F.SilkS"))
    (fp_line (start 0.95 0.501) (end 0.95 0.751)
      (stroke (width 0.15) (type solid)) (layer "F.SilkS"))
    (fp_line (start 0.95 0.751) (end 0.649 0.751)
      (stroke (width 0.15) (type solid)) (layer "F.SilkS"))
    (fp_rect (start -1.6 -0.925) (end 1.6 0.925)
      (stroke (width 0.05) (type solid)) (fill none) (layer "F.CrtYd"))
    (fp_line (start -0.902 0.699) (end -0.902 -0.699)
      (stroke (width 0.15) (type solid)) (layer "F.Fab"))
    (fp_line (start -0.902 0.699) (end 0.9 0.699)
      (stroke (width 0.15) (type solid)) (layer "F.Fab"))
    (fp_line (start 0.9 -0.699) (end -0.902 -0.699)
      (stroke (width 0.15) (type solid)) (layer "F.Fab"))
    (fp_line (start 0.9 -0.699) (end 0.9 0.699)
      (stroke (width 0.15) (type solid)) (layer "F.Fab"))
    (pad "1" smd rect (at -1.125 0.001 270) (size 0.8 0.8) (layers "F.Cu" "F.Paste" "F.Mask")
      (net 11 "VCC12V0") (pinfunction "C") (pintype "passive"))
    (pad "2" smd rect (at 1.124 0.001 270) (size 0.8 0.8) (layers "F.Cu" "F.Paste" "F.Mask")
      (net 83 "Net-(D15-A)") (pinfunction "A") (pintype "passive"))
  )

  (footprint "antmicro-footprints:R_0402_1005Metric" (layer "F.Cu")
    (at 145.9 89.5 180)
    (descr "Resistor SMD 0402")
    (tags "resistor SMD 0402")
    (property "Author" "Antmicro")
    (property "DNP" "DNP")
    (property "License" "Apache-2.0")
    (property "MPN" "CR0402-FX-1002GLF")
    (property "Manufacturer" "Bourns")
    (property "Sheetfile" "power-switch.kicad_sch")
    (property "Sheetname" "Power switch 3")
    (property "Tolerance" "1%")
    (property "Val" "10k")
    (property "dnp" "")
    (property "exclude_from_bom" "")
    (property "ki_description" "SMD Chip Resistor, 10 kohm, ± 1%, 62.5 mW, 0402 [1005 Metric], Thick Film, General Purpose")
    (property "ki_keywords" "0402, SMT, RESISTOR, PASSIVE")
    (attr smd exclude_from_bom)
    (fp_text reference "R50" (at 2 -0.1) (layer "F.SilkS")
        (effects (font (size 0.7 0.7) (thickness 0.15)))
    )
    (fp_text value "R_10k_0402" (at 0 1.17) (layer "F.Fab") hide
        (effects (font (size 1 1) (thickness 0.15)))
    )
    (fp_text user "Author: Antmicro" (at -0.95 4.169 180) (layer "F.Fab") hide
        (effects (font (size 0.7 0.7) (thickness 0.15)) (justify left bottom))
    )
    (fp_text user "${REFERENCE}" (at 0 0) (layer "F.Fab")
        (effects (font (size 0.25 0.25) (thickness 0.04)))
    )
    (fp_text user "License: Apache-2.0" (at -0.95 5.169 180) (layer "F.Fab") hide
        (effects (font (size 0.7 0.7) (thickness 0.15)) (justify left bottom))
    )
    (fp_rect (start -0.925 -0.47) (end 0.925 0.47)
      (stroke (width 0.05) (type default)) (fill none) (layer "F.CrtYd"))
    (fp_rect (start -0.5 -0.25) (end 0.5 0.25)
      (stroke (width 0.15) (type solid)) (fill none) (layer "F.Fab"))
    (pad "1" smd roundrect (at -0.48 0 180) (size 0.59 0.64) (layers "F.Cu" "F.Paste" "F.Mask") (roundrect_rratio 0.25)
      (net 30 "/Power Cycling & Current Measurement/PC_3") (pintype "passive"))
    (pad "2" smd roundrect (at 0.48 0 180) (size 0.59 0.64) (layers "F.Cu" "F.Paste" "F.Mask") (roundrect_rratio 0.25)
      (net 4 "GND") (pintype "passive"))
  )

  (footprint "antmicro-footprints:C_0402_1005Metric" (layer "F.Cu")
    (at 170.1 125.4 90)
    (descr "Capacitor SMD 0402")
    (tags "capacitor SMD 0402")
    (property "Author" "Antmicro")
    (property "Dielectric" "")
    (property "License" "Apache-2.0")
    (property "MPN" "CL05C180JB51PNC")
    (property "Manufacturer" "Samsung Electro-Mechanics")
    (property "Sheetfile" "ftdi-module.kicad_sch")
    (property "Sheetname" "FTDI")
    (property "Val" "18p")
    (property "Voltage" "")
    (property "ki_description" "SMD Multilayer Ceramic Capacitor, 18 pF, 50 V, 0402 [1005 Metric], ± 5%, C0G / NP0, MC")
    (property "ki_keywords" "0402, SMT, CAPACITOR, PASSIVE")
    (attr smd)
    (fp_text reference "C2" (at -0.65 1.5 90) (layer "F.SilkS")
        (effects (font (size 0.7 0.7) (thickness 0.15)) (justify left bottom))
    )
    (fp_text value "C_18p_0402" (at -1.022927 2.155213 90) (layer "F.Fab")
        (effects (font (size 0.7 0.7) (thickness 0.15)) (justify left bottom))
    )
    (fp_text user "Author: Antmicro" (at -0.939 3.399 90) (layer "F.Fab") hide
        (effects (font (size 0.7 0.7) (thickness 0.15)) (justify left bottom))
    )
    (fp_text user "${REFERENCE}" (at -0.939 4.599 90) (layer "F.Fab") hide
        (effects (font (size 0.7 0.7) (thickness 0.15)) (justify left bottom))
    )
    (fp_text user "License: Apache-2.0" (at -0.939 5.799 90) (layer "F.Fab") hide
        (effects (font (size 0.7 0.7) (thickness 0.15)) (justify left bottom))
    )
    (fp_rect (start -0.925 -0.47) (end 0.925 0.47)
      (stroke (width 0.05) (type default)) (fill none) (layer "F.CrtYd"))
    (fp_line (start -0.494 -0.25) (end 0.504 -0.25)
      (stroke (width 0.15) (type solid)) (layer "F.Fab"))
    (fp_line (start -0.494 0.248) (end -0.494 -0.25)
      (stroke (width 0.15) (type solid)) (layer "F.Fab"))
    (fp_line (start 0.504 -0.25) (end 0.504 0.248)
      (stroke (width 0.15) (type solid)) (layer "F.Fab"))
    (fp_line (start 0.504 0.248) (end -0.494 0.248)
      (stroke (width 0.15) (type solid)) (layer "F.Fab"))
    (pad "1" smd roundrect (at -0.48 0 90) (size 0.59 0.64) (layers "F.Cu" "F.Paste" "F.Mask") (roundrect_rratio 0.25)
      (net 77 "GNDD") (pintype "passive"))
    (pad "2" smd roundrect (at 0.48 0 90) (size 0.59 0.64) (layers "F.Cu" "F.Paste" "F.Mask") (roundrect_rratio 0.25)
      (net 5 "/FTDI/OSCI") (pintype "passive"))
  )

  (footprint "antmicro-footprints:C_0402_1005Metric" (layer "F.Cu")
    (at 165.1 123.5 90)
    (descr "Capacitor SMD 0402")
    (tags "capacitor SMD 0402")
    (property "Author" "Antmicro")
    (property "Dielectric" "X5R")
    (property "License" "Apache-2.0")
    (property "MPN" "GRM155R61H104KE14D")
    (property "Manufacturer" "Murata")
    (property "Sheetfile" "ftdi-module.kicad_sch")
    (property "Sheetname" "FTDI")
    (property "Val" "100n")
    (property "Voltage" "50V")
    (property "ki_description" "SMD Multilayer Ceramic Capacitor, 0.1 µF, 50 V, 0402 [1005 Metric], ± 10%, X5R, GRM Series")
    (property "ki_keywords" "0402, SMT, CAPACITOR, PASSIVE, CERAMIC, MLCC")
    (zone_connect 1)
    (attr smd)
    (fp_text reference "C9" (at -2.45 0.4 90) (layer "F.SilkS")
        (effects (font (size 0.7 0.7) (thickness 0.15)) (justify left bottom))
    )
    (fp_text value "C_100n_0402" (at -1.022927 2.155213 90) (layer "F.Fab")
        (effects (font (size 0.7 0.7) (thickness 0.15)) (justify left bottom))
    )
    (fp_text user "Author: Antmicro" (at -0.939 3.399 90) (layer "F.Fab") hide
        (effects (font (size 0.7 0.7) (thickness 0.15)) (justify left bottom))
    )
    (fp_text user "${REFERENCE}" (at -0.939 4.599 90) (layer "F.Fab") hide
        (effects (font (size 0.7 0.7) (thickness 0.15)) (justify left bottom))
    )
    (fp_text user "License: Apache-2.0" (at -0.939 5.799 90) (layer "F.Fab") hide
        (effects (font (size 0.7 0.7) (thickness 0.15)) (justify left bottom))
    )
    (fp_rect (start -0.925 -0.47) (end 0.925 0.47)
      (stroke (width 0.05) (type default)) (fill none) (layer "F.CrtYd"))
    (fp_line (start -0.494 -0.25) (end 0.504 -0.25)
      (stroke (width 0.15) (type solid)) (layer "F.Fab"))
    (fp_line (start -0.494 0.248) (end -0.494 -0.25)
      (stroke (width 0.15) (type solid)) (layer "F.Fab"))
    (fp_line (start 0.504 -0.25) (end 0.504 0.248)
      (stroke (width 0.15) (type solid)) (layer "F.Fab"))
    (fp_line (start 0.504 0.248) (end -0.494 0.248)
      (stroke (width 0.15) (type solid)) (layer "F.Fab"))
    (pad "1" smd roundrect (at -0.48 0 90) (size 0.59 0.64) (layers "F.Cu" "F.Paste" "F.Mask") (roundrect_rratio 0.25)
      (net 77 "GNDD") (pintype "passive"))
    (pad "2" smd roundrect (at 0.48 0 90) (size 0.59 0.64) (layers "F.Cu" "F.Paste" "F.Mask") (roundrect_rratio 0.25)
      (net 7 "1V8_FT") (pintype "passive"))
  )

  (footprint "antmicro-footprints:LED_0603_1608Metric_G" (layer "F.Cu")
    (at 110.8 53.65)
    (descr "LED SMD 0603 Green")
    (tags "LED SMD 0603 Green")
    (property "Author" "Antmicro")
    (property "Color" "Green")
    (property "License" "Apache-2.0")
    (property "MPN" "LG L29K-G2J1-24-Z")
    (property "Manufacturer" "OSRAM")
    (property "Sheetfile" "d1600e-psu-breakout-board.kicad_sch")
    (property "Sheetname" "")
    (property "ki_description" "LED, Green, SMD, 0603, 20 mA, 1.7 V, 570 nm")
    (property "ki_keywords" "SMT, DIODE, SEMICONDUCTOR, LED")
    (zone_connect 1)
    (attr smd)
    (fp_text reference "D3" (at -0.8 1.7) (layer "F.SilkS")
        (effects (font (size 0.7 0.7) (thickness 0.15)) (justify left bottom))
    )
    (fp_text value "LED_G_0603_LG_L29K-G2J1-24-Z" (at -0.001 1.599) (layer "F.Fab")
        (effects (font (size 0.7 0.7) (thickness 0.15)) (justify left bottom))
    )
    (fp_text user "${REFERENCE}" (at -1.4224 5.999) (layer "F.Fab") hide
        (effects (font (size 0.7 0.7) (thickness 0.15)) (justify left bottom))
    )
    (fp_text user "Author: Antmicro" (at -1.4224 4.799) (layer "F.Fab") hide
        (effects (font (size 0.7 0.7) (thickness 0.15)) (justify left bottom))
    )
    (fp_text user "License: Apache-2.0" (at -1.4224 3.599) (layer "F.Fab") hide
        (effects (font (size 0.7 0.7) (thickness 0.15)) (justify left bottom))
    )
    (fp_line (start -1.18 -0.319) (end -1.18 0.321)
      (stroke (width 0.15) (type solid)) (layer "F.SilkS"))
    (fp_line (start -0.094672 0.001008) (end -0.24 0.001008)
      (stroke (width 0.1) (type solid)) (layer "F.SilkS"))
    (fp_line (start -0.094672 0.001008) (end 0.105328 -0.198992)
      (stroke (width 0.1) (type solid)) (layer "F.SilkS"))
    (fp_line (start -0.094672 0.201008) (end -0.094672 -0.198992)
      (stroke (width 0.1) (type solid)) (layer "F.SilkS"))
    (fp_line (start 0.105328 0.001008) (end 0.24 0.001)
      (stroke (width 0.1) (type solid)) (layer "F.SilkS"))
    (fp_line (start 0.105328 0.201008) (end -0.094672 0.001008)
      (stroke (width 0.1) (type solid)) (layer "F.SilkS"))
    (fp_line (start 0.105328 0.201008) (end 0.105328 -0.198992)
      (stroke (width 0.1) (type solid)) (layer "F.SilkS"))
    (fp_line (start 0.22 -0.35) (end -0.22 -0.35)
      (stroke (width 0.15) (type solid)) (layer "F.SilkS"))
    (fp_line (start 0.22 0.35) (end -0.22 0.35)
      (stroke (width 0.15) (type solid)) (layer "F.SilkS"))
    (fp_rect (start 1.25 0.65) (end -1.25 -0.65)
      (stroke (width 0.05) (type solid)) (fill none) (layer "F.CrtYd"))
    (fp_line (start -0.199 -0.202) (end -0.199 0.1)
      (stroke (width 0.15) (type solid)) (layer "F.Fab"))
    (fp_line (start -0.199 0) (end -0.597 0)
      (stroke (width 0.15) (type solid)) (layer "F.Fab"))
    (fp_line (start -0.199 0.2) (end -0.199 0.1)
      (stroke (width 0.15) (type solid)) (layer "F.Fab"))
    (fp_line (start -0.101 0) (end 0.201 0.2)
      (stroke (width 0.15) (type solid)) (layer "F.Fab"))
    (fp_line (start 0.201 -0.202) (end -0.101 0)
      (stroke (width 0.15) (type solid)) (layer "F.Fab"))
    (fp_line (start 0.201 0) (end 0.201 -0.202)
      (stroke (width 0.15) (type solid)) (layer "F.Fab"))
    (fp_line (start 0.201 0.2) (end 0.201 0)
      (stroke (width 0.15) (type solid)) (layer "F.Fab"))
    (fp_line (start 0.599 0) (end 0.201 0)
      (stroke (width 0.15) (type solid)) (layer "F.Fab"))
    (fp_rect (start 0.848 0.4) (end -0.85 -0.402)
      (stroke (width 0.15) (type solid)) (fill none) (layer "F.Fab"))
    (pad "1" smd roundrect (at -0.7 0 180) (size 0.8 1) (layers "F.Cu" "F.Paste" "F.Mask") (roundrect_rratio 0.2)
      (net 4 "GND") (pinfunction "C") (pintype "passive"))
    (pad "2" smd roundrect (at 0.7 0 180) (size 0.8 1) (layers "F.Cu" "F.Paste" "F.Mask") (roundrect_rratio 0.2)
      (net 36 "Net-(D3-A)") (pinfunction "A") (pintype "passive"))
  )

  (footprint "antmicro-footprints:Vishay_PowerPAK_1212-8_Single" (layer "F.Cu")
    (at 120.25 86.1 90)
    (descr "PowerPAK 1212-8 Single")
    (tags "Vishay PowerPAK 1212-8 Single")
    (property "Author" "Antmicro")
    (property "License" "Apache-2.0")
    (property "MPN" "SI7613DN-T1-GE3")
    (property "Manufacturer" "Vishay")
    (property "Sheetfile" "power-switch.kicad_sch")
    (property "Sheetname" "Power switch 1")
    (property "ki_description" "Power MOSFET, P Channel, 20 V, 35 A, 0.0072 ohm, PowerPAK 1212, Surface Mount")
    (property "ki_keywords" "SMT, TRANSISTOR, SEMICONDUCTOR, MOSFET, PMOS")
    (attr smd)
    (fp_text reference "QA1" (at -2.85 0.5 180) (layer "F.SilkS")
        (effects (font (size 0.7 0.7) (thickness 0.15)) (justify left bottom))
    )
    (fp_text value "SI7613DN-T1-GE3" (at 0 2.7 90) (layer "F.Fab")
        (effects (font (size 0.7 0.7) (thickness 0.15)) (justify left bottom))
    )
    (fp_text user "Author: Antmicro" (at -8 5.9 90) (layer "F.Fab") hide
        (effects (font (size 0.7 0.7) (thickness 0.15)) (justify left bottom))
    )
    (fp_text user "License: Apache-2.0" (at -8 7.1 90) (layer "F.Fab") hide
        (effects (font (size 0.7 0.7) (thickness 0.15)) (justify left bottom))
    )
    (fp_text user "${REFERENCE}" (at -8 4.7 90) (layer "F.Fab") hide
        (effects (font (size 0.7 0.7) (thickness 0.15)) (justify left bottom))
    )
    (fp_line (start -1.651 -1.651) (end -1.651 -1.317)
      (stroke (width 0.15) (type solid)) (layer "F.SilkS"))
    (fp_line (start -1.651 -1.651) (end 1.648 -1.651)
      (stroke (width 0.15) (type solid)) (layer "F.SilkS"))
    (fp_line (start -1.635 1.3) (end -1.635 1.634)
      (stroke (width 0.15) (type solid)) (layer "F.SilkS"))
    (fp_line (start -1.635 1.634) (end 1.634 1.634)
      (stroke (width 0.15) (type solid)) (layer "F.SilkS"))
    (fp_line (start 1.634 1.3) (end 1.634 1.634)
      (stroke (width 0.15) (type solid)) (layer "F.SilkS"))
    (fp_line (start 1.648 -1.651) (end 1.648 -1.317)
      (stroke (width 0.15) (type solid)) (layer "F.SilkS"))
    (fp_circle (center -1.9 -1.4) (end -1.85 -1.4)
      (stroke (width 0.15) (type solid)) (fill solid) (layer "F.SilkS"))
    (fp_rect (start -2 -1.8) (end 2 1.798)
      (stroke (width 0.05) (type solid)) (fill none) (layer "F.CrtYd"))
    (fp_line (start -1.6425 -1.4175) (end -1.4175 -1.6425)
      (stroke (width 0.15) (type solid)) (layer "F.Fab"))
    (fp_rect (start -1.651 -1.651) (end 1.648 1.648)
      (stroke (width 0.15) (type solid)) (fill none) (layer "F.Fab"))
    (pad "1" smd rect (at -1.436 -0.99 90) (size 0.99 0.405) (layers "F.Cu" "F.Paste" "F.Mask")
      (net 11 "VCC12V0") (pinfunction "S") (pintype "passive"))
    (pad "2" smd rect (at -1.436 -0.332 90) (size 0.99 0.405) (layers "F.Cu" "F.Paste" "F.Mask")
      (net 11 "VCC12V0") (pinfunction "S") (pintype "passive"))
    (pad "3" smd rect (at -1.436 0.33 90) (size 0.99 0.405) (layers "F.Cu" "F.Paste" "F.Mask")
      (net 11 "VCC12V0") (pinfunction "S") (pintype "passive"))
    (pad "4" smd rect (at -1.436 0.988 90) (size 0.99 0.405) (layers "F.Cu" "F.Paste" "F.Mask")
      (net 93 "Net-(QA1-G)") (pinfunction "G") (pintype "passive"))
    (pad "5" smd custom (at 0.557 0 90) (size 1.725 2.235) (layers "F.Cu" "F.Paste" "F.Mask")
      (net 21 "C_MEAS_1") (pinfunction "D") (pintype "passive") (zone_connect 2)
      (options (clearance outline) (anchor rect))
      (primitives
        (gr_poly
          (pts
            (xy 0.8625 0.1275)
            (xy 0.8625 -0.1275)
            (xy 1.3725 -0.1275)
            (xy 1.3725 -0.5325)
            (xy 0.8625 -0.5325)
            (xy 0.8625 -0.7875)
            (xy 1.3725 -0.7875)
            (xy 1.3725 -1.195)
            (xy 0.6125 -1.195)
            (xy 0.6125 1.195)
            (xy 1.3725 1.195)
            (xy 1.3725 0.7875)
            (xy 0.8625 0.7875)
            (xy 0.8625 0.5325)
            (xy 1.3725 0.5325)
            (xy 1.3725 0.1275)
          )
          (width 0) (fill yes))
      ))
  )

  (footprint "antmicro-footprints:R_0402_1005Metric" (layer "F.Cu")
    (at 154.6 91.8 -90)
    (descr "Resistor SMD 0402")
    (tags "resistor SMD 0402")
    (property "Author" "Antmicro")
    (property "License" "Apache-2.0")
    (property "MPN" "CR0402-FX-2R00GLF")
    (property "Manufacturer" "Bourns")
    (property "Sheetfile" "power-switch.kicad_sch")
    (property "Sheetname" "Power switch 3")
    (property "Tolerance" "1%")
    (property "Val" "2R")
    (property "ki_description" "SMD Chip Resistor")
    (property "ki_keywords" "0402, SMT, RESISTOR, PASSIVE")
    (attr smd)
    (fp_text reference "R65" (at 1.75 -0.05 -180) (layer "F.SilkS")
        (effects (font (size 0.7 0.7) (thickness 0.15)) (justify right bottom))
    )
    (fp_text value "R_2R_0402" (at -1.011843 1.772047 90) (layer "F.Fab")
        (effects (font (size 0.7 0.7) (thickness 0.15)) (justify right bottom))
    )
    (fp_text user "${REFERENCE}" (at -0.95 3.168 90) (layer "F.Fab") hide
        (effects (font (size 0.7 0.7) (thickness 0.15)) (justify right bottom))
    )
    (fp_text user "License: Apache-2.0" (at -0.95 5.169 90) (layer "F.Fab") hide
        (effects (font (size 0.7 0.7) (thickness 0.15)) (justify right bottom))
    )
    (fp_text user "Author: Antmicro" (at -0.95 4.169 90) (layer "F.Fab") hide
        (effects (font (size 0.7 0.7) (thickness 0.15)) (justify right bottom))
    )
    (fp_rect (start -0.925 -0.47) (end 0.925 0.47)
      (stroke (width 0.05) (type default)) (fill none) (layer "F.CrtYd"))
    (fp_rect (start -0.5 -0.25) (end 0.5 0.25)
      (stroke (width 0.15) (type solid)) (fill none) (layer "F.Fab"))
    (pad "1" smd roundrect (at -0.48 0 270) (size 0.59 0.64) (layers "F.Cu" "F.Paste" "F.Mask") (roundrect_rratio 0.25)
      (net 101 "Net-(QB3-G)") (pintype "passive"))
    (pad "2" smd roundrect (at 0.48 0 270) (size 0.59 0.64) (layers "F.Cu" "F.Paste" "F.Mask") (roundrect_rratio 0.25)
      (net 86 "Net-(D18-A)") (pintype "passive"))
  )

  (footprint "antmicro-footprints:R_0402_1005Metric" (layer "F.Cu")
    (at 184.3 118.75 90)
    (descr "Resistor SMD 0402")
    (tags "resistor SMD 0402")
    (property "Author" "Antmicro")
    (property "License" "Apache-2.0")
    (property "MPN" "CR0402-FX-5101GLF")
    (property "Manufacturer" "Bourns")
    (property "Sheetfile" "ftdi-module.kicad_sch")
    (property "Sheetname" "FTDI")
    (property "Tolerance" "1%")
    (property "Val" "5k1")
    (property "ki_description" "SMD Chip Resistor, 5.1 kohm, ± 1%, 63 mW, 0402 [1005 Metric], Thick Film, General Purpose")
    (property "ki_keywords" "0402, SMT, RESISTOR, PASSIVE")
    (attr smd)
    (fp_text reference "R57" (at -0.95 -0.6 90) (layer "F.SilkS")
        (effects (font (size 0.7 0.7) (thickness 0.15)) (justify left bottom))
    )
    (fp_text value "R_5k1_0402" (at -1.011843 1.772047 90) (layer "F.Fab")
        (effects (font (size 0.7 0.7) (thickness 0.15)) (justify left bottom))
    )
    (fp_text user "${REFERENCE}" (at -0.95 3.168 90) (layer "F.Fab") hide
        (effects (font (size 0.7 0.7) (thickness 0.15)) (justify left bottom))
    )
    (fp_text user "License: Apache-2.0" (at -0.95 5.169 90) (layer "F.Fab") hide
        (effects (font (size 0.7 0.7) (thickness 0.15)) (justify left bottom))
    )
    (fp_text user "Author: Antmicro" (at -0.95 4.169 90) (layer "F.Fab") hide
        (effects (font (size 0.7 0.7) (thickness 0.15)) (justify left bottom))
    )
    (fp_rect (start -0.925 -0.47) (end 0.925 0.47)
      (stroke (width 0.05) (type default)) (fill none) (layer "F.CrtYd"))
    (fp_rect (start -0.5 -0.25) (end 0.5 0.25)
      (stroke (width 0.15) (type solid)) (fill none) (layer "F.Fab"))
    (pad "1" smd roundrect (at -0.48 0 90) (size 0.59 0.64) (layers "F.Cu" "F.Paste" "F.Mask") (roundrect_rratio 0.25)
      (net 77 "GNDD") (pintype "passive"))
    (pad "2" smd roundrect (at 0.48 0 90) (size 0.59 0.64) (layers "F.Cu" "F.Paste" "F.Mask") (roundrect_rratio 0.25)
      (net 113 "Net-(U1-CC_{1})") (pintype "passive"))
  )

  (footprint "antmicro-footprints:PCM12SMTR" (layer "F.Cu")
    (at 91.8 135.751 -90)
    (property "Author" "Antmicro")
    (property "License" "Apache-2.0")
    (property "MPN" "PCM12SMTR")
    (property "Manufacturer" "C&K")
    (property "Sheetfile" "d1600e-psu-breakout-board.kicad_sch")
    (property "Sheetname" "")
    (property "ki_description" "Slide switch")
    (property "ki_keywords" "VERTICAL, SMT, SWITCH, SWITCH, SLIDE")
    (attr smd)
    (fp_text reference "S1" (at 1.474 -3.65 90) (layer "F.SilkS")
        (effects (font (size 0.7 0.7) (thickness 0.15)) (justify right bottom))
    )
    (fp_text value "SW_SPDT_PCM12SMTR" (at 0 4.15 90) (layer "F.Fab")
        (effects (font (size 0.7 0.7) (thickness 0.15)) (justify right bottom))
    )
    (fp_text user "${REFERENCE}" (at -2.152 7.94 90) (layer "F.Fab") hide
        (effects (font (size 0.7 0.7) (thickness 0.15)) (justify right bottom))
    )
    (fp_text user "License: Apache-2.0" (at -2.152 10.339 90) (layer "F.Fab") hide
        (effects (font (size 0.7 0.7) (thickness 0.15)) (justify right bottom))
    )
    (fp_text user "Author: Antmicro" (at -2.152 9.14 90) (layer "F.Fab") hide
        (effects (font (size 0.7 0.7) (thickness 0.15)) (justify right bottom))
    )
    (fp_line (start -3.351 0.348) (end -3.351 -0.251)
      (stroke (width 0.15) (type solid)) (layer "F.SilkS"))
    (fp_line (start -2.901 1.348) (end 2.9 1.348)
      (stroke (width 0.15) (type solid)) (layer "F.SilkS"))
    (fp_line (start -1.601 -1.251) (end 0.1 -1.251)
      (stroke (width 0.15) (type solid)) (layer "F.SilkS"))
    (fp_line (start 3.349 -0.251) (end 3.349 0.348)
      (stroke (width 0.15) (type solid)) (layer "F.SilkS"))
    (fp_circle (center -3.15 -2.45) (end -3.1 -2.39)
      (stroke (width 0.15) (type solid)) (fill solid) (layer "F.SilkS"))
    (fp_line (start -4.42 -1.57) (end -2.86 -1.57)
      (stroke (width 0.05) (type solid)) (layer "F.CrtYd"))
    (fp_line (start -4.42 1.65) (end -4.42 -1.57)
      (stroke (width 0.05) (type solid)) (layer "F.CrtYd"))
    (fp_line (start -2.86 -2.7) (end 2.83 -2.7)
      (stroke (width 0.05) (type solid)) (layer "F.CrtYd"))
    (fp_line (start -2.86 -1.57) (end -2.86 -2.7)
      (stroke (width 0.05) (type solid)) (layer "F.CrtYd"))
    (fp_line (start -1.77 1.65) (end -4.42 1.65)
      (stroke (width 0.05) (type solid)) (layer "F.CrtYd"))
    (fp_line (start -1.77 3.08) (end -1.77 1.65)
      (stroke (width 0.05) (type solid)) (layer "F.CrtYd"))
    (fp_line (start 1.74 1.65) (end 1.74 3.08)
      (stroke (width 0.05) (type solid)) (layer "F.CrtYd"))
    (fp_line (start 1.74 3.08) (end -1.77 3.08)
      (stroke (width 0.05) (type solid)) (layer "F.CrtYd"))
    (fp_line (start 2.83 -2.7) (end 2.83 -1.57)
      (stroke (width 0.05) (type solid)) (layer "F.CrtYd"))
    (fp_line (start 2.83 -1.57) (end 4.4 -1.57)
      (stroke (width 0.05) (type solid)) (layer "F.CrtYd"))
    (fp_line (start 4.4 -1.57) (end 4.4 1.65)
      (stroke (width 0.05) (type solid)) (layer "F.CrtYd"))
    (fp_line (start 4.4 1.65) (end 1.74 1.65)
      (stroke (width 0.05) (type solid)) (layer "F.CrtYd"))
    (fp_line (start -3.351 -1.251) (end 3.349 -1.251)
      (stroke (width 0.15) (type solid)) (layer "F.Fab"))
    (fp_line (start -3.351 1.348) (end -3.351 -1.251)
      (stroke (width 0.15) (type solid)) (layer "F.Fab"))
    (fp_line (start -1.502 1.348) (end -3.351 1.348)
      (stroke (width 0.15) (type solid)) (layer "F.Fab"))
    (fp_line (start -1.502 1.348) (end -1.502 2.849)
      (stroke (width 0.15) (type solid)) (layer "F.Fab"))
    (fp_line (start -1.502 2.849) (end 1.499 2.849)
      (stroke (width 0.15) (type solid)) (layer "F.Fab"))
    (fp_line (start 1.499 1.348) (end -1.502 1.348)
      (stroke (width 0.15) (type solid)) (layer "F.Fab"))
    (fp_line (start 1.499 2.849) (end 1.499 1.348)
      (stroke (width 0.15) (type solid)) (layer "F.Fab"))
    (fp_line (start 3.349 -1.251) (end 3.349 1.348)
      (stroke (width 0.15) (type solid)) (layer "F.Fab"))
    (fp_line (start 3.349 1.348) (end 1.499 1.348)
      (stroke (width 0.15) (type solid)) (layer "F.Fab"))
    (pad "" np_thru_hole circle (at -1.502 0.049 270) (size 0.9 0.9) (drill 0.9) (layers "*.Cu" "*.Mask"))
    (pad "" np_thru_hole circle (at 1.499 0.049 270) (size 0.9 0.9) (drill 0.9) (layers "*.Cu" "*.Mask"))
    (pad "1" smd roundrect (at -2.25 -1.7 270) (size 0.7 1.5) (layers "F.Cu" "F.Paste" "F.Mask") (roundrect_rratio 0.25)
      (net 166 "unconnected-(S1-Pad1)") (pintype "passive+no_connect"))
    (pad "2" smd roundrect (at 0.749 -1.7 270) (size 0.7 1.5) (layers "F.Cu" "F.Paste" "F.Mask") (roundrect_rratio 0.25)
      (net 51 "PSU_ON") (pintype "passive"))
    (pad "3" smd roundrect (at 2.248 -1.7 270) (size 0.7 1.5) (layers "F.Cu" "F.Paste" "F.Mask") (roundrect_rratio 0.25)
      (net 4 "GND") (pintype "passive"))
    (pad "S1" smd roundrect (at -3.651 -0.915 270) (size 1 0.8) (layers "F.Cu" "F.Paste" "F.Mask") (roundrect_rratio 0.25)
      (net 167 "unconnected-(S1-SH-PadS1)") (pinfunction "SH") (pintype "passive+no_connect"))
    (pad "S2" smd roundrect (at -3.651 1.013 270) (size 1 0.8) (layers "F.Cu" "F.Paste" "F.Mask") (roundrect_rratio 0.25)
      (net 167 "unconnected-(S1-SH-PadS1)") (pinfunction "SH") (pintype "passive+no_connect"))
    (pad "S3" smd roundrect (at 3.65 1.013 270) (size 1 0.8) (layers "F.Cu" "F.Paste" "F.Mask") (roundrect_rratio 0.25)
      (net 167 "unconnected-(S1-SH-PadS1)") (pinfunction "SH") (pintype "passive+no_connect"))
    (pad "S4" smd roundrect (at 3.65 -0.915 270) (size 1 0.8) (layers "F.Cu" "F.Paste" "F.Mask") (roundrect_rratio 0.25)
      (net 167 "unconnected-(S1-SH-PadS1)") (pinfunction "SH") (pintype "passive+no_connect"))
  )

  (footprint "antmicro-footprints:R_0402_1005Metric" (layer "F.Cu")
    (at 163.9 99.085 90)
    (descr "Resistor SMD 0402")
    (tags "resistor SMD 0402")
    (property "Author" "Antmicro")
    (property "License" "Apache-2.0")
    (property "MPN" "CR0402-FX-4701GLF")
    (property "Manufacturer" "Bourns")
    (property "Sheetfile" "ftdi-module.kicad_sch")
    (property "Sheetname" "FTDI")
    (property "Tolerance" "1%")
    (property "Val" "4k7")
    (property "ki_description" "SMD Chip Resistor, 4.7 kohm, ± 1%, 62.5 mW, 0402 [1005 Metric], Thick Film, General Purpose")
    (property "ki_keywords" "0402, SMT, RESISTOR, PASSIVE")
    (attr smd)
    (fp_text reference "R36" (at -0.515 1.45 90) (layer "F.SilkS")
        (effects (font (size 0.7 0.7) (thickness 0.15)) (justify left bottom))
    )
    (fp_text value "R_4k7_0402" (at -1.011843 1.772047 90) (layer "F.Fab")
        (effects (font (size 0.7 0.7) (thickness 0.15)) (justify left bottom))
    )
    (fp_text user "Author: Antmicro" (at -0.95 4.169 90) (layer "F.Fab") hide
        (effects (font (size 0.7 0.7) (thickness 0.15)) (justify left bottom))
    )
    (fp_text user "License: Apache-2.0" (at -0.95 5.169 90) (layer "F.Fab") hide
        (effects (font (size 0.7 0.7) (thickness 0.15)) (justify left bottom))
    )
    (fp_text user "${REFERENCE}" (at -0.95 3.168 90) (layer "F.Fab") hide
        (effects (font (size 0.7 0.7) (thickness 0.15)) (justify left bottom))
    )
    (fp_rect (start -0.925 -0.47) (end 0.925 0.47)
      (stroke (width 0.05) (type default)) (fill none) (layer "F.CrtYd"))
    (fp_rect (start -0.5 -0.25) (end 0.5 0.25)
      (stroke (width 0.15) (type solid)) (fill none) (layer "F.Fab"))
    (pad "1" smd roundrect (at -0.48 0 90) (size 0.59 0.64) (layers "F.Cu" "F.Paste" "F.Mask") (roundrect_rratio 0.25)
      (net 17 "SCL") (pintype "passive"))
    (pad "2" smd roundrect (at 0.48 0 90) (size 0.59 0.64) (layers "F.Cu" "F.Paste" "F.Mask") (roundrect_rratio 0.25)
      (net 1 "VCC3V3") (pintype "passive"))
  )

  (footprint "antmicro-footprints:R_0402_1005Metric" (layer "F.Cu")
    (at 113.65 90.2 -90)
    (descr "Resistor SMD 0402")
    (tags "resistor SMD 0402")
    (property "Author" "Antmicro")
    (property "License" "Apache-2.0")
    (property "MPN" "CR0402-FX-2R00GLF")
    (property "Manufacturer" "Bourns")
    (property "Sheetfile" "power-switch.kicad_sch")
    (property "Sheetname" "Power switch 1")
    (property "Tolerance" "1%")
    (property "Val" "2R")
    (property "ki_description" "SMD Chip Resistor")
    (property "ki_keywords" "0402, SMT, RESISTOR, PASSIVE")
    (attr smd)
    (fp_text reference "R60" (at -0.15 0.75 90) (layer "F.SilkS")
        (effects (font (size 0.7 0.7) (thickness 0.15)) (justify right bottom))
    )
    (fp_text value "R_2R_0402" (at -1.011843 1.772047 90) (layer "F.Fab")
        (effects (font (size 0.7 0.7) (thickness 0.15)) (justify right bottom))
    )
    (fp_text user "${REFERENCE}" (at -0.95 3.168 90) (layer "F.Fab") hide
        (effects (font (size 0.7 0.7) (thickness 0.15)) (justify right bottom))
    )
    (fp_text user "License: Apache-2.0" (at -0.95 5.169 90) (layer "F.Fab") hide
        (effects (font (size 0.7 0.7) (thickness 0.15)) (justify right bottom))
    )
    (fp_text user "Author: Antmicro" (at -0.95 4.169 90) (layer "F.Fab") hide
        (effects (font (size 0.7 0.7) (thickness 0.15)) (justify right bottom))
    )
    (fp_rect (start -0.925 -0.47) (end 0.925 0.47)
      (stroke (width 0.05) (type default)) (fill none) (layer "F.CrtYd"))
    (fp_rect (start -0.5 -0.25) (end 0.5 0.25)
      (stroke (width 0.15) (type solid)) (fill none) (layer "F.Fab"))
    (pad "1" smd roundrect (at -0.48 0 270) (size 0.59 0.64) (layers "F.Cu" "F.Paste" "F.Mask") (roundrect_rratio 0.25)
      (net 98 "Net-(QB1-G)") (pintype "passive"))
    (pad "2" smd roundrect (at 0.48 0 270) (size 0.59 0.64) (layers "F.Cu" "F.Paste" "F.Mask") (roundrect_rratio 0.25)
      (net 83 "Net-(D15-A)") (pintype "passive"))
  )

  (footprint "antmicro-footprints:R_0402_1005Metric" (layer "F.Cu")
    (at 121.2 91.5 90)
    (descr "Resistor SMD 0402")
    (tags "resistor SMD 0402")
    (property "Author" "Antmicro")
    (property "License" "Apache-2.0")
    (property "MPN" "CR0402-FX-2R00GLF")
    (property "Manufacturer" "Bourns")
    (property "Sheetfile" "power-switch.kicad_sch")
    (property "Sheetname" "Power switch 1")
    (property "Tolerance" "1%")
    (property "Val" "2R")
    (property "ki_description" "SMD Chip Resistor")
    (property "ki_keywords" "0402, SMT, RESISTOR, PASSIVE")
    (attr smd)
    (fp_text reference "R62" (at -2.05 -0.6 90) (layer "F.SilkS")
        (effects (font (size 0.7 0.7) (thickness 0.15)) (justify left bottom))
    )
    (fp_text value "R_2R_0402" (at -1.011843 1.772047 90) (layer "F.Fab")
        (effects (font (size 0.7 0.7) (thickness 0.15)) (justify left bottom))
    )
    (fp_text user "License: Apache-2.0" (at -0.95 5.169 90) (layer "F.Fab") hide
        (effects (font (size 0.7 0.7) (thickness 0.15)) (justify left bottom))
    )
    (fp_text user "${REFERENCE}" (at -0.95 3.168 90) (layer "F.Fab") hide
        (effects (font (size 0.7 0.7) (thickness 0.15)) (justify left bottom))
    )
    (fp_text user "Author: Antmicro" (at -0.95 4.169 90) (layer "F.Fab") hide
        (effects (font (size 0.7 0.7) (thickness 0.15)) (justify left bottom))
    )
    (fp_rect (start -0.925 -0.47) (end 0.925 0.47)
      (stroke (width 0.05) (type default)) (fill none) (layer "F.CrtYd"))
    (fp_rect (start -0.5 -0.25) (end 0.5 0.25)
      (stroke (width 0.15) (type solid)) (fill none) (layer "F.Fab"))
    (pad "1" smd roundrect (at -0.48 0 90) (size 0.59 0.64) (layers "F.Cu" "F.Paste" "F.Mask") (roundrect_rratio 0.25)
      (net 83 "Net-(D15-A)") (pintype "passive"))
    (pad "2" smd roundrect (at 0.48 0 90) (size 0.59 0.64) (layers "F.Cu" "F.Paste" "F.Mask") (roundrect_rratio 0.25)
      (net 93 "Net-(QA1-G)") (pintype "passive"))
  )

  (footprint "antmicro-footprints:Vishay_PowerPAK_1212-8_Single" (layer "F.Cu")
    (at 154.1775 86.2275 90)
    (descr "PowerPAK 1212-8 Single")
    (tags "Vishay PowerPAK 1212-8 Single")
    (property "Author" "Antmicro")
    (property "License" "Apache-2.0")
    (property "MPN" "SI7613DN-T1-GE3")
    (property "Manufacturer" "Vishay")
    (property "Sheetfile" "power-switch.kicad_sch")
    (property "Sheetname" "Power switch 3")
    (property "ki_description" "Power MOSFET, P Channel, 20 V, 35 A, 0.0072 ohm, PowerPAK 1212, Surface Mount")
    (property "ki_keywords" "SMT, TRANSISTOR, SEMICONDUCTOR, MOSFET, PMOS")
    (attr smd)
    (fp_text reference "QB3" (at -3.0225 0.2225 180) (layer "F.SilkS")
        (effects (font (size 0.7 0.7) (thickness 0.15)) (justify left bottom))
    )
    (fp_text value "SI7613DN-T1-GE3" (at 0 2.7 90) (layer "F.Fab")
        (effects (font (size 0.7 0.7) (thickness 0.15)) (justify left bottom))
    )
    (fp_text user "${REFERENCE}" (at -8 4.7 90) (layer "F.Fab") hide
        (effects (font (size 0.7 0.7) (thickness 0.15)) (justify left bottom))
    )
    (fp_text user "Author: Antmicro" (at -8 5.9 90) (layer "F.Fab") hide
        (effects (font (size 0.7 0.7) (thickness 0.15)) (justify left bottom))
    )
    (fp_text user "License: Apache-2.0" (at -8 7.1 90) (layer "F.Fab") hide
        (effects (font (size 0.7 0.7) (thickness 0.15)) (justify left bottom))
    )
    (fp_line (start -1.651 -1.651) (end -1.651 -1.317)
      (stroke (width 0.15) (type solid)) (layer "F.SilkS"))
    (fp_line (start -1.651 -1.651) (end 1.648 -1.651)
      (stroke (width 0.15) (type solid)) (layer "F.SilkS"))
    (fp_line (start -1.635 1.3) (end -1.635 1.634)
      (stroke (width 0.15) (type solid)) (layer "F.SilkS"))
    (fp_line (start -1.635 1.634) (end 1.634 1.634)
      (stroke (width 0.15) (type solid)) (layer "F.SilkS"))
    (fp_line (start 1.634 1.3) (end 1.634 1.634)
      (stroke (width 0.15) (type solid)) (layer "F.SilkS"))
    (fp_line (start 1.648 -1.651) (end 1.648 -1.317)
      (stroke (width 0.15) (type solid)) (layer "F.SilkS"))
    (fp_circle (center -1.9 -1.4) (end -1.85 -1.4)
      (stroke (width 0.15) (type solid)) (fill solid) (layer "F.SilkS"))
    (fp_rect (start -2 -1.8) (end 2 1.798)
      (stroke (width 0.05) (type solid)) (fill none) (layer "F.CrtYd"))
    (fp_line (start -1.6425 -1.4175) (end -1.4175 -1.6425)
      (stroke (width 0.15) (type solid)) (layer "F.Fab"))
    (fp_rect (start -1.651 -1.651) (end 1.648 1.648)
      (stroke (width 0.15) (type solid)) (fill none) (layer "F.Fab"))
    (pad "1" smd rect (at -1.436 -0.99 90) (size 0.99 0.405) (layers "F.Cu" "F.Paste" "F.Mask")
      (net 11 "VCC12V0") (pinfunction "S") (pintype "passive"))
    (pad "2" smd rect (at -1.436 -0.332 90) (size 0.99 0.405) (layers "F.Cu" "F.Paste" "F.Mask")
      (net 11 "VCC12V0") (pinfunction "S") (pintype "passive"))
    (pad "3" smd rect (at -1.436 0.33 90) (size 0.99 0.405) (layers "F.Cu" "F.Paste" "F.Mask")
      (net 11 "VCC12V0") (pinfunction "S") (pintype "passive"))
    (pad "4" smd rect (at -1.436 0.988 90) (size 0.99 0.405) (layers "F.Cu" "F.Paste" "F.Mask")
      (net 101 "Net-(QB3-G)") (pinfunction "G") (pintype "passive"))
    (pad "5" smd custom (at 0.557 0 90) (size 1.725 2.235) (layers "F.Cu" "F.Paste" "F.Mask")
      (net 28 "C_MEAS_3") (pinfunction "D") (pintype "passive") (zone_connect 2)
      (options (clearance outline) (anchor rect))
      (primitives
        (gr_poly
          (pts
            (xy 0.8625 0.1275)
            (xy 0.8625 -0.1275)
            (xy 1.3725 -0.1275)
            (xy 1.3725 -0.5325)
            (xy 0.8625 -0.5325)
            (xy 0.8625 -0.7875)
            (xy 1.3725 -0.7875)
            (xy 1.3725 -1.195)
            (xy 0.6125 -1.195)
            (xy 0.6125 1.195)
            (xy 1.3725 1.195)
            (xy 1.3725 0.7875)
            (xy 0.8625 0.7875)
            (xy 0.8625 0.5325)
            (xy 1.3725 0.5325)
            (xy 1.3725 0.1275)
          )
          (width 0) (fill yes))
      ))
  )

  (footprint "antmicro-footprints:TPD2E009DRTR" (layer "F.Cu")
    (at 181.1 103.25 180)
    (property "Author" "Antmicro")
    (property "License" "Apache-2.0")
    (property "MPN" "PESD5V0S2BQA")
    (property "Manufacturer" "Nexperia")
    (property "Sheetfile" "d1600e-psu-breakout-board.kicad_sch")
    (property "Sheetname" "")
    (property "ki_description" "TVS diode array, 30 kV, SOT-1215, 5V, 45 pF")
    (property "ki_keywords" "SMT, DIODE, SEMICONDUCTOR, TVS, ESD")
    (attr smd)
    (fp_text reference "D12" (at -0.76 1.22) (layer "F.SilkS")
        (effects (font (size 0.7 0.7) (thickness 0.15)))
    )
    (fp_text value "PESD5V0S2BQA" (at 5.6088 1.3064) (layer "F.Fab") hide
        (effects (font (size 0.64 0.64) (thickness 0.015)))
    )
    (fp_text user "License: Apache-2.0" (at -0.949 5.706 180) (layer "F.Fab") hide
        (effects (font (size 0.7 0.7) (thickness 0.15)) (justify left bottom))
    )
    (fp_text user "${REFERENCE}" (at -0.949 4.506 180) (layer "F.Fab") hide
        (effects (font (size 0.7 0.7) (thickness 0.15)) (justify left bottom))
    )
    (fp_text user "Author: Antmicro" (at -0.949 3.306 180) (layer "F.Fab") hide
        (effects (font (size 0.7 0.7) (thickness 0.15)) (justify left bottom))
    )
    (fp_line (start 0.03 -0.499) (end 0.4 -0.499)
      (stroke (width 0.15) (type solid)) (layer "F.SilkS"))
    (fp_line (start 0.03 0.499) (end 0.4 0.499)
      (stroke (width 0.15) (type solid)) (layer "F.SilkS"))
    (fp_line (start 0.4 -0.419) (end 0.4 -0.499)
      (stroke (width 0.15) (type solid)) (layer "F.SilkS"))
    (fp_line (start 0.4 0.42) (end 0.4 0.499)
      (stroke (width 0.15) (type solid)) (layer "F.SilkS"))
    (fp_circle (center -0.5 -0.6) (end -0.45 -0.6)
      (stroke (width 0.15) (type solid)) (fill solid) (layer "F.SilkS"))
    (fp_rect (start -0.8 -0.59) (end 0.8 0.59)
      (stroke (width 0.05) (type solid)) (fill none) (layer "F.CrtYd"))
    (fp_line (start -0.4 -0.499) (end 0.4 -0.499)
      (stroke (width 0.15) (type solid)) (layer "F.Fab"))
    (fp_line (start -0.4 0.499) (end -0.4 -0.499)
      (stroke (width 0.15) (type solid)) (layer "F.Fab"))
    (fp_line (start 0.4 -0.499) (end 0.4 0.499)
      (stroke (width 0.15) (type solid)) (layer "F.Fab"))
    (fp_line (start 0.4 0.499) (end -0.4 0.499)
      (stroke (width 0.15) (type solid)) (layer "F.Fab"))
    (pad "1" smd rect (at -0.52 -0.349 180) (size 0.46 0.2) (layers "F.Cu" "F.Paste" "F.Mask")
      (net 17 "SCL") (pinfunction "IO1") (pintype "passive"))
    (pad "2" smd rect (at -0.52 0.348 180) (size 0.46 0.2) (layers "F.Cu" "F.Paste" "F.Mask")
      (net 99 "SDA_CON") (pinfunction "IO2") (pintype "passive"))
    (pad "3" smd rect (at 0.52 0 180) (size 0.46 0.2) (layers "F.Cu" "F.Paste" "F.Mask")
      (net 4 "GND") (pinfunction "GND") (pintype "passive"))
  )

  (footprint "antmicro-footprints:R_0402_1005Metric" (layer "F.Cu")
    (at 142.2 96.6 180)
    (descr "Resistor SMD 0402")
    (tags "resistor SMD 0402")
    (property "Author" "Antmicro")
    (property "License" "Apache-2.0")
    (property "MPN" "RC0402BR-07100KL")
    (property "Manufacturer" "Yageo")
    (property "Sheetfile" "pow-cycl-curr-meas.kicad_sch")
    (property "Sheetname" "Power Cycling & Current Measurement")
    (property "Tolerance" "0.1%")
    (property "Val" "100k")
    (property "ki_description" "SMD Chip Resistor, 100 kohm, ± 0.1%, 63 mW, 0402 [1005 Metric], Thin Film")
    (property "ki_keywords" "0402, SMT, RESISTOR, PASSIVE")
    (attr smd)
    (fp_text reference "R2" (at 3 -0.45 180) (layer "F.SilkS")
        (effects (font (size 0.7 0.7) (thickness 0.15)) (justify left bottom))
    )
    (fp_text value "R_100k_0.1%_0402" (at -1.011843 1.772047 180) (layer "F.Fab")
        (effects (font (size 0.7 0.7) (thickness 0.15)) (justify left bottom))
    )
    (fp_text user "Author: Antmicro" (at -0.95 4.169 180) (layer "F.Fab") hide
        (effects (font (size 0.7 0.7) (thickness 0.15)) (justify left bottom))
    )
    (fp_text user "${REFERENCE}" (at -0.95 3.168 180) (layer "F.Fab") hide
        (effects (font (size 0.7 0.7) (thickness 0.15)) (justify left bottom))
    )
    (fp_text user "License: Apache-2.0" (at -0.95 5.169 180) (layer "F.Fab") hide
        (effects (font (size 0.7 0.7) (thickness 0.15)) (justify left bottom))
    )
    (fp_rect (start -0.925 -0.47) (end 0.925 0.47)
      (stroke (width 0.05) (type default)) (fill none) (layer "F.CrtYd"))
    (fp_rect (start -0.5 -0.25) (end 0.5 0.25)
      (stroke (width 0.15) (type solid)) (fill none) (layer "F.Fab"))
    (pad "1" smd roundrect (at -0.48 0 180) (size 0.59 0.64) (layers "F.Cu" "F.Paste" "F.Mask") (roundrect_rratio 0.25)
      (net 144 "Net-(R2-Pad1)") (pintype "passive"))
    (pad "2" smd roundrect (at 0.48 0 180) (size 0.59 0.64) (layers "F.Cu" "F.Paste" "F.Mask") (roundrect_rratio 0.25)
      (net 11 "VCC12V0") (pintype "passive"))
  )

  (footprint "antmicro-footprints:R_0402_1005Metric" (layer "F.Cu")
    (at 128.9 89.4 180)
    (descr "Resistor SMD 0402")
    (tags "resistor SMD 0402")
    (property "Author" "Antmicro")
    (property "DNP" "DNP")
    (property "License" "Apache-2.0")
    (property "MPN" "CR0402-FX-1002GLF")
    (property "Manufacturer" "Bourns")
    (property "Sheetfile" "power-switch.kicad_sch")
    (property "Sheetname" "Power switch 2")
    (property "Tolerance" "1%")
    (property "Val" "10k")
    (property "dnp" "")
    (property "exclude_from_bom" "")
    (property "ki_description" "SMD Chip Resistor, 10 kohm, ± 1%, 62.5 mW, 0402 [1005 Metric], Thick Film, General Purpose")
    (property "ki_keywords" "0402, SMT, RESISTOR, PASSIVE")
    (attr smd exclude_from_bom)
    (fp_text reference "R47" (at 3.15 -0.45 180) (layer "F.SilkS")
        (effects (font (size 0.7 0.7) (thickness 0.15)) (justify left bottom))
    )
    (fp_text value "R_10k_0402" (at -1.011843 1.772047 180) (layer "F.Fab")
        (effects (font (size 0.7 0.7) (thickness 0.15)) (justify left bottom))
    )
    (fp_text user "License: Apache-2.0" (at -0.95 5.169 180) (layer "F.Fab") hide
        (effects (font (size 0.7 0.7) (thickness 0.15)) (justify left bottom))
    )
    (fp_text user "${REFERENCE}" (at -0.95 3.168 180) (layer "F.Fab") hide
        (effects (font (size 0.7 0.7) (thickness 0.15)) (justify left bottom))
    )
    (fp_text user "Author: Antmicro" (at -0.95 4.169 180) (layer "F.Fab") hide
        (effects (font (size 0.7 0.7) (thickness 0.15)) (justify left bottom))
    )
    (fp_rect (start -0.925 -0.47) (end 0.925 0.47)
      (stroke (width 0.05) (type default)) (fill none) (layer "F.CrtYd"))
    (fp_rect (start -0.5 -0.25) (end 0.5 0.25)
      (stroke (width 0.15) (type solid)) (fill none) (layer "F.Fab"))
    (pad "1" smd roundrect (at -0.48 0 180) (size 0.59 0.64) (layers "F.Cu" "F.Paste" "F.Mask") (roundrect_rratio 0.25)
      (net 24 "/Power Cycling & Current Measurement/PC_2") (pintype "passive"))
    (pad "2" smd roundrect (at 0.48 0 180) (size 0.59 0.64) (layers "F.Cu" "F.Paste" "F.Mask") (roundrect_rratio 0.25)
      (net 4 "GND") (pintype "passive"))
  )

  (footprint "antmicro-footprints:R_0402_1005Metric" (layer "F.Cu")
    (at 172.1 91.7 -90)
    (descr "Resistor SMD 0402")
    (tags "resistor SMD 0402")
    (property "Author" "Antmicro")
    (property "License" "Apache-2.0")
    (property "MPN" "CR0402-FX-2R00GLF")
    (property "Manufacturer" "Bourns")
    (property "Sheetfile" "power-switch.kicad_sch")
    (property "Sheetname" "Power switch 4")
    (property "Tolerance" "1%")
    (property "Val" "2R")
    (property "ki_description" "SMD Chip Resistor")
    (property "ki_keywords" "0402, SMT, RESISTOR, PASSIVE")
    (attr smd)
    (fp_text reference "R64" (at 1.35 -0.35) (layer "F.SilkS")
        (effects (font (size 0.7 0.7) (thickness 0.15)) (justify left bottom))
    )
    (fp_text value "R_2R_0402" (at -1.011843 1.772047 -90) (layer "F.Fab")
        (effects (font (size 0.7 0.7) (thickness 0.15)) (justify left bottom))
    )
    (fp_text user "License: Apache-2.0" (at -0.95 5.169 -90) (layer "F.Fab") hide
        (effects (font (size 0.7 0.7) (thickness 0.15)) (justify left bottom))
    )
    (fp_text user "${REFERENCE}" (at -0.95 3.168 -90) (layer "F.Fab") hide
        (effects (font (size 0.7 0.7) (thickness 0.15)) (justify left bottom))
    )
    (fp_text user "Author: Antmicro" (at -0.95 4.169 -90) (layer "F.Fab") hide
        (effects (font (size 0.7 0.7) (thickness 0.15)) (justify left bottom))
    )
    (fp_rect (start -0.925 -0.47) (end 0.925 0.47)
      (stroke (width 0.05) (type default)) (fill none) (layer "F.CrtYd"))
    (fp_rect (start -0.5 -0.25) (end 0.5 0.25)
      (stroke (width 0.15) (type solid)) (fill none) (layer "F.Fab"))
    (pad "1" smd roundrect (at -0.48 0 270) (size 0.59 0.64) (layers "F.Cu" "F.Paste" "F.Mask") (roundrect_rratio 0.25)
      (net 102 "Net-(QB4-G)") (pintype "passive"))
    (pad "2" smd roundrect (at 0.48 0 270) (size 0.59 0.64) (layers "F.Cu" "F.Paste" "F.Mask") (roundrect_rratio 0.25)
      (net 85 "Net-(D17-A)") (pintype "passive"))
  )

  (footprint "antmicro-footprints:FB_0603_1608Metric" (layer "F.Cu")
    (at 149.625 105.05)
    (property "Author" "Antmicro")
    (property "Current" "")
    (property "License" "Apache-2.0")
    (property "MPN" "BLM18AG601SN1D")
    (property "Manufacturer" "Murata")
    (property "Sheetfile" "pow-cycl-curr-meas.kicad_sch")
    (property "Sheetname" "Power Cycling & Current Measurement")
    (property "Val" "600Z/0.5A")
    (property "ki_description" "Ferrite Bead, 0603 [1608 Metric], 600 ohm, 500 mA, BLM18A, 0.38 ohm, ± 25%, General use")
    (property "ki_keywords" "0603, SMT, FERRITE BEAD, PASSIVE")
    (attr smd)
    (fp_text reference "FB4" (at -1.025 1.65) (layer "F.SilkS")
        (effects (font (size 0.7 0.7) (thickness 0.15)) (justify left bottom))
    )
    (fp_text value "FB_600Z_0.5A_Murata-BLM18AG_0603" (at 0 1.5) (layer "F.Fab")
        (effects (font (size 0.7 0.7) (thickness 0.15)) (justify left bottom))
    )
    (fp_text user "License: Apache-2.0" (at -1.653 5.9) (layer "F.Fab") hide
        (effects (font (size 0.7 0.7) (thickness 0.15)) (justify left bottom))
    )
    (fp_text user "Author: Antmicro" (at -1.653 3.162) (layer "F.Fab") hide
        (effects (font (size 0.7 0.7) (thickness 0.15)) (justify left bottom))
    )
    (fp_text user "${REFERENCE}" (at -1.653 4.6) (layer "F.Fab") hide
        (effects (font (size 0.7 0.7) (thickness 0.15)) (justify left bottom))
    )
    (fp_line (start -0.15 -0.4) (end 0.15 -0.4)
      (stroke (width 0.15) (type solid)) (layer "F.SilkS"))
    (fp_line (start -0.15 0.4) (end 0.15 0.4)
      (stroke (width 0.15) (type solid)) (layer "F.SilkS"))
    (fp_rect (start -1.25 -0.65) (end 1.25 0.65)
      (stroke (width 0.05) (type solid)) (fill none) (layer "F.CrtYd"))
    (fp_line (start -0.803 0.406) (end -0.803 -0.408)
      (stroke (width 0.15) (type solid)) (layer "F.Fab"))
    (fp_line (start 0.8 -0.408) (end -0.803 -0.408)
      (stroke (width 0.15) (type solid)) (layer "F.Fab"))
    (fp_line (start 0.8 -0.408) (end 0.8 0.406)
      (stroke (width 0.15) (type solid)) (layer "F.Fab"))
    (fp_line (start 0.8 0.406) (end -0.803 0.406)
      (stroke (width 0.15) (type solid)) (layer "F.Fab"))
    (pad "1" smd roundrect (at -0.7 0) (size 0.8 1) (layers "F.Cu" "F.Paste" "F.Mask") (roundrect_rratio 0.2)
      (net 1 "VCC3V3") (pintype "passive"))
    (pad "2" smd roundrect (at 0.7 0) (size 0.8 1) (layers "F.Cu" "F.Paste" "F.Mask") (roundrect_rratio 0.2)
      (net 34 "Net-(U14-REF)") (pintype "passive"))
  )

  (footprint "antmicro-footprints:LED_0603_1608Metric_G" (layer "F.Cu")
    (at 94.2 104.4)
    (descr "LED SMD 0603 Green")
    (tags "LED SMD 0603 Green")
    (property "Author" "Antmicro")
    (property "Color" "Green")
    (property "License" "Apache-2.0")
    (property "MPN" "LG L29K-G2J1-24-Z")
    (property "Manufacturer" "OSRAM")
    (property "Sheetfile" "d1600e-psu-breakout-board.kicad_sch")
    (property "Sheetname" "")
    (property "ki_description" "LED, Green, SMD, 0603, 20 mA, 1.7 V, 570 nm")
    (property "ki_keywords" "SMT, DIODE, SEMICONDUCTOR, LED")
    (zone_connect 1)
    (attr smd)
    (fp_text reference "D11" (at -1.1 -0.6) (layer "F.SilkS")
        (effects (font (size 0.7 0.7) (thickness 0.15)) (justify left bottom))
    )
    (fp_text value "LED_G_0603_LG_L29K-G2J1-24-Z" (at -0.001 1.599) (layer "F.Fab")
        (effects (font (size 0.7 0.7) (thickness 0.15)) (justify left bottom))
    )
    (fp_text user "License: Apache-2.0" (at -1.4224 3.599) (layer "F.Fab") hide
        (effects (font (size 0.7 0.7) (thickness 0.15)) (justify left bottom))
    )
    (fp_text user "Author: Antmicro" (at -1.4224 4.799) (layer "F.Fab") hide
        (effects (font (size 0.7 0.7) (thickness 0.15)) (justify left bottom))
    )
    (fp_text user "${REFERENCE}" (at -1.4224 5.999) (layer "F.Fab") hide
        (effects (font (size 0.7 0.7) (thickness 0.15)) (justify left bottom))
    )
    (fp_line (start -1.18 -0.319) (end -1.18 0.321)
      (stroke (width 0.15) (type solid)) (layer "F.SilkS"))
    (fp_line (start -0.094672 0.001008) (end -0.24 0.001008)
      (stroke (width 0.1) (type solid)) (layer "F.SilkS"))
    (fp_line (start -0.094672 0.001008) (end 0.105328 -0.198992)
      (stroke (width 0.1) (type solid)) (layer "F.SilkS"))
    (fp_line (start -0.094672 0.201008) (end -0.094672 -0.198992)
      (stroke (width 0.1) (type solid)) (layer "F.SilkS"))
    (fp_line (start 0.105328 0.001008) (end 0.24 0.001)
      (stroke (width 0.1) (type solid)) (layer "F.SilkS"))
    (fp_line (start 0.105328 0.201008) (end -0.094672 0.001008)
      (stroke (width 0.1) (type solid)) (layer "F.SilkS"))
    (fp_line (start 0.105328 0.201008) (end 0.105328 -0.198992)
      (stroke (width 0.1) (type solid)) (layer "F.SilkS"))
    (fp_line (start 0.22 -0.35) (end -0.22 -0.35)
      (stroke (width 0.15) (type solid)) (layer "F.SilkS"))
    (fp_line (start 0.22 0.35) (end -0.22 0.35)
      (stroke (width 0.15) (type solid)) (layer "F.SilkS"))
    (fp_rect (start 1.25 0.65) (end -1.25 -0.65)
      (stroke (width 0.05) (type solid)) (fill none) (layer "F.CrtYd"))
    (fp_line (start -0.199 -0.202) (end -0.199 0.1)
      (stroke (width 0.15) (type solid)) (layer "F.Fab"))
    (fp_line (start -0.199 0) (end -0.597 0)
      (stroke (width 0.15) (type solid)) (layer "F.Fab"))
    (fp_line (start -0.199 0.2) (end -0.199 0.1)
      (stroke (width 0.15) (type solid)) (layer "F.Fab"))
    (fp_line (start -0.101 0) (end 0.201 0.2)
      (stroke (width 0.15) (type solid)) (layer "F.Fab"))
    (fp_line (start 0.201 -0.202) (end -0.101 0)
      (stroke (width 0.15) (type solid)) (layer "F.Fab"))
    (fp_line (start 0.201 0) (end 0.201 -0.202)
      (stroke (width 0.15) (type solid)) (layer "F.Fab"))
    (fp_line (start 0.201 0.2) (end 0.201 0)
      (stroke (width 0.15) (type solid)) (layer "F.Fab"))
    (fp_line (start 0.599 0) (end 0.201 0)
      (stroke (width 0.15) (type solid)) (layer "F.Fab"))
    (fp_rect (start 0.848 0.4) (end -0.85 -0.402)
      (stroke (width 0.15) (type solid)) (fill none) (layer "F.Fab"))
    (pad "1" smd roundrect (at -0.7 0 180) (size 0.8 1) (layers "F.Cu" "F.Paste" "F.Mask") (roundrect_rratio 0.2)
      (net 4 "GND") (pinfunction "C") (pintype "passive"))
    (pad "2" smd roundrect (at 0.7 0 180) (size 0.8 1) (layers "F.Cu" "F.Paste" "F.Mask") (roundrect_rratio 0.2)
      (net 82 "Net-(D11-A)") (pinfunction "A") (pintype "passive"))
  )

  (footprint "antmicro-footprints:R_0402_1005Metric" (layer "F.Cu")
    (at 142.2 97.6 180)
    (descr "Resistor SMD 0402")
    (tags "resistor SMD 0402")
    (property "Author" "Antmicro")
    (property "License" "Apache-2.0")
    (property "MPN" "ERA-2AEB1542X")
    (property "Manufacturer" "Panasonic")
    (property "Sheetfile" "pow-cycl-curr-meas.kicad_sch")
    (property "Sheetname" "Power Cycling & Current Measurement")
    (property "Tolerance" "0.1%")
    (property "Val" "15k4")
    (property "ki_description" "SMD Chip Resistor, 15.4 kohm, ± 0.1%, 63 mW, 0402 [1005 Metric], Thin Film")
    (property "ki_keywords" "0402, SMT, RESISTOR, PASSIVE")
    (attr smd)
    (fp_text reference "R59" (at 3.05 -0.45 180) (layer "F.SilkS")
        (effects (font (size 0.7 0.7) (thickness 0.15)) (justify left bottom))
    )
    (fp_text value "R_15k4_0.1%_0402" (at -1.011843 1.772047 180) (layer "F.Fab")
        (effects (font (size 0.7 0.7) (thickness 0.15)) (justify left bottom))
    )
    (fp_text user "${REFERENCE}" (at -0.95 3.168 180) (layer "F.Fab") hide
        (effects (font (size 0.7 0.7) (thickness 0.15)) (justify left bottom))
    )
    (fp_text user "Author: Antmicro" (at -0.95 4.169 180) (layer "F.Fab") hide
        (effects (font (size 0.7 0.7) (thickness 0.15)) (justify left bottom))
    )
    (fp_text user "License: Apache-2.0" (at -0.95 5.169 180) (layer "F.Fab") hide
        (effects (font (size 0.7 0.7) (thickness 0.15)) (justify left bottom))
    )
    (fp_rect (start -0.925 -0.47) (end 0.925 0.47)
      (stroke (width 0.05) (type default)) (fill none) (layer "F.CrtYd"))
    (fp_rect (start -0.5 -0.25) (end 0.5 0.25)
      (stroke (width 0.15) (type solid)) (fill none) (layer "F.Fab"))
    (pad "1" smd roundrect (at -0.48 0 180) (size 0.59 0.64) (layers "F.Cu" "F.Paste" "F.Mask") (roundrect_rratio 0.25)
      (net 144 "Net-(R2-Pad1)") (pintype "passive"))
    (pad "2" smd roundrect (at 0.48 0 180) (size 0.59 0.64) (layers "F.Cu" "F.Paste" "F.Mask") (roundrect_rratio 0.25)
      (net 4 "GND") (pintype "passive"))
  )

  (footprint "antmicro-footprints:TPD2E009DRTR" (layer "F.Cu")
    (at 147.9 96.9)
    (property "Author" "Antmicro")
    (property "License" "Apache-2.0")
    (property "MPN" "PESD5V0S2BQA")
    (property "Manufacturer" "Nexperia")
    (property "Sheetfile" "pow-cycl-curr-meas.kicad_sch")
    (property "Sheetname" "Power Cycling & Current Measurement")
    (property "ki_description" "TVS diode array, 30 kV, SOT-1215, 5V, 45 pF")
    (property "ki_keywords" "SMT, DIODE, SEMICONDUCTOR, TVS, ESD")
    (attr smd)
    (fp_text reference "D20" (at -0.8 -0.85) (layer "F.SilkS")
        (effects (font (size 0.7 0.7) (thickness 0.15)) (justify left bottom))
    )
    (fp_text value "PESD5V0S2BQA" (at 5.608 1.306) (layer "F.Fab")
        (effects (font (size 0.7 0.7) (thickness 0.15)) (justify left bottom))
    )
    (fp_text user "${REFERENCE}" (at -0.949 4.506) (layer "F.Fab") hide
        (effects (font (size 0.7 0.7) (thickness 0.15)) (justify left bottom))
    )
    (fp_text user "Author: Antmicro" (at -0.949 3.306) (layer "F.Fab") hide
        (effects (font (size 0.7 0.7) (thickness 0.15)) (justify left bottom))
    )
    (fp_text user "License: Apache-2.0" (at -0.949 5.706) (layer "F.Fab") hide
        (effects (font (size 0.7 0.7) (thickness 0.15)) (justify left bottom))
    )
    (fp_line (start 0.03 -0.499) (end 0.4 -0.499)
      (stroke (width 0.15) (type solid)) (layer "F.SilkS"))
    (fp_line (start 0.03 0.499) (end 0.4 0.499)
      (stroke (width 0.15) (type solid)) (layer "F.SilkS"))
    (fp_line (start 0.4 -0.419) (end 0.4 -0.499)
      (stroke (width 0.15) (type solid)) (layer "F.SilkS"))
    (fp_line (start 0.4 0.42) (end 0.4 0.499)
      (stroke (width 0.15) (type solid)) (layer "F.SilkS"))
    (fp_circle (center -0.5 -0.6) (end -0.45 -0.6)
      (stroke (width 0.15) (type solid)) (fill solid) (layer "F.SilkS"))
    (fp_rect (start -0.8 -0.59) (end 0.8 0.59)
      (stroke (width 0.05) (type solid)) (fill none) (layer "F.CrtYd"))
    (fp_line (start -0.4 -0.499) (end 0.4 -0.499)
      (stroke (width 0.15) (type solid)) (layer "F.Fab"))
    (fp_line (start -0.4 0.499) (end -0.4 -0.499)
      (stroke (width 0.15) (type solid)) (layer "F.Fab"))
    (fp_line (start 0.4 -0.499) (end 0.4 0.499)
      (stroke (width 0.15) (type solid)) (layer "F.Fab"))
    (fp_line (start 0.4 0.499) (end -0.4 0.499)
      (stroke (width 0.15) (type solid)) (layer "F.Fab"))
    (pad "1" smd rect (at -0.52 -0.349) (size 0.46 0.2) (layers "F.Cu" "F.Paste" "F.Mask")
      (net 90 "/Power Cycling & Current Measurement/V_ADC1") (pinfunction "IO1") (pintype "passive"))
    (pad "2" smd rect (at -0.52 0.348) (size 0.46 0.2) (layers "F.Cu" "F.Paste" "F.Mask")
      (net 88 "unconnected-(D20-IO2-Pad2)") (pinfunction "IO2") (pintype "passive+no_connect"))
    (pad "3" smd rect (at 0.52 0) (size 0.46 0.2) (layers "F.Cu" "F.Paste" "F.Mask")
      (net 4 "GND") (pinfunction "GND") (pintype "passive"))
  )

  (footprint "antmicro-footprints:Vishay_PowerPAK_1212-8_Single" (layer "F.Cu")
    (at 137.5 86.3 90)
    (descr "PowerPAK 1212-8 Single")
    (tags "Vishay PowerPAK 1212-8 Single")
    (property "Author" "Antmicro")
    (property "License" "Apache-2.0")
    (property "MPN" "SI7613DN-T1-GE3")
    (property "Manufacturer" "Vishay")
    (property "Sheetfile" "power-switch.kicad_sch")
    (property "Sheetname" "Power switch 2")
    (property "ki_description" "Power MOSFET, P Channel, 20 V, 35 A, 0.0072 ohm, PowerPAK 1212, Surface Mount")
    (property "ki_keywords" "SMT, TRANSISTOR, SEMICONDUCTOR, MOSFET, PMOS")
    (attr smd)
    (fp_text reference "QB2" (at -2.9 0.4 180) (layer "F.SilkS")
        (effects (font (size 0.7 0.7) (thickness 0.15)) (justify left bottom))
    )
    (fp_text value "SI7613DN-T1-GE3" (at 0 2.7 90) (layer "F.Fab")
        (effects (font (size 0.7 0.7) (thickness 0.15)) (justify left bottom))
    )
    (fp_text user "License: Apache-2.0" (at -8 7.1 90) (layer "F.Fab") hide
        (effects (font (size 0.7 0.7) (thickness 0.15)) (justify left bottom))
    )
    (fp_text user "Author: Antmicro" (at -8 5.9 90) (layer "F.Fab") hide
        (effects (font (size 0.7 0.7) (thickness 0.15)) (justify left bottom))
    )
    (fp_text user "${REFERENCE}" (at -8 4.7 90) (layer "F.Fab") hide
        (effects (font (size 0.7 0.7) (thickness 0.15)) (justify left bottom))
    )
    (fp_line (start -1.651 -1.651) (end -1.651 -1.317)
      (stroke (width 0.15) (type solid)) (layer "F.SilkS"))
    (fp_line (start -1.651 -1.651) (end 1.648 -1.651)
      (stroke (width 0.15) (type solid)) (layer "F.SilkS"))
    (fp_line (start -1.635 1.3) (end -1.635 1.634)
      (stroke (width 0.15) (type solid)) (layer "F.SilkS"))
    (fp_line (start -1.635 1.634) (end 1.634 1.634)
      (stroke (width 0.15) (type solid)) (layer "F.SilkS"))
    (fp_line (start 1.634 1.3) (end 1.634 1.634)
      (stroke (width 0.15) (type solid)) (layer "F.SilkS"))
    (fp_line (start 1.648 -1.651) (end 1.648 -1.317)
      (stroke (width 0.15) (type solid)) (layer "F.SilkS"))
    (fp_circle (center -1.9 -1.4) (end -1.85 -1.4)
      (stroke (width 0.15) (type solid)) (fill solid) (layer "F.SilkS"))
    (fp_rect (start -2 -1.8) (end 2 1.798)
      (stroke (width 0.05) (type solid)) (fill none) (layer "F.CrtYd"))
    (fp_line (start -1.6425 -1.4175) (end -1.4175 -1.6425)
      (stroke (width 0.15) (type solid)) (layer "F.Fab"))
    (fp_rect (start -1.651 -1.651) (end 1.648 1.648)
      (stroke (width 0.15) (type solid)) (fill none) (layer "F.Fab"))
    (pad "1" smd rect (at -1.436 -0.99 90) (size 0.99 0.405) (layers "F.Cu" "F.Paste" "F.Mask")
      (net 11 "VCC12V0") (pinfunction "S") (pintype "passive"))
    (pad "2" smd rect (at -1.436 -0.332 90) (size 0.99 0.405) (layers "F.Cu" "F.Paste" "F.Mask")
      (net 11 "VCC12V0") (pinfunction "S") (pintype "passive"))
    (pad "3" smd rect (at -1.436 0.33 90) (size 0.99 0.405) (layers "F.Cu" "F.Paste" "F.Mask")
      (net 11 "VCC12V0") (pinfunction "S") (pintype "passive"))
    (pad "4" smd rect (at -1.436 0.988 90) (size 0.99 0.405) (layers "F.Cu" "F.Paste" "F.Mask")
      (net 100 "Net-(QB2-G)") (pinfunction "G") (pintype "passive"))
    (pad "5" smd custom (at 0.557 0 90) (size 1.725 2.235) (layers "F.Cu" "F.Paste" "F.Mask")
      (net 22 "C_MEAS_2") (pinfunction "D") (pintype "passive") (zone_connect 2)
      (options (clearance outline) (anchor rect))
      (primitives
        (gr_poly
          (pts
            (xy 0.8625 0.1275)
            (xy 0.8625 -0.1275)
            (xy 1.3725 -0.1275)
            (xy 1.3725 -0.5325)
            (xy 0.8625 -0.5325)
            (xy 0.8625 -0.7875)
            (xy 1.3725 -0.7875)
            (xy 1.3725 -1.195)
            (xy 0.6125 -1.195)
            (xy 0.6125 1.195)
            (xy 1.3725 1.195)
            (xy 1.3725 0.7875)
            (xy 0.8625 0.7875)
            (xy 0.8625 0.5325)
            (xy 1.3725 0.5325)
            (xy 1.3725 0.1275)
          )
          (width 0) (fill yes))
      ))
  )

  (footprint "antmicro-footprints:R_0603_1608Metric" (layer "F.Cu")
    (at 166 53.85)
    (descr "Resistor SMD 0603")
    (tags "resistor SMD 0603")
    (property "Author" "Antmicro")
    (property "License" "Apache-2.0")
    (property "MPN" "CR0603-FX-4701ELF")
    (property "Manufacturer" "Bourns")
    (property "Sheetfile" "d1600e-psu-breakout-board.kicad_sch")
    (property "Sheetname" "")
    (property "Tolerance" "1%")
    (property "Val" "4k7")
    (property "ki_description" "SMD Chip Resistor, 4.7 kohm, ± 1%, 100 mW, 0603 [1608 Metric], Thick Film, General Purpose")
    (property "ki_keywords" "0603, SMT, RESISTOR, PASSIVE")
    (attr smd)
    (fp_text reference "R52" (at -1.1 1.6) (layer "F.SilkS")
        (effects (font (size 0.7 0.7) (thickness 0.15)) (justify left bottom))
    )
    (fp_text value "R_4k7_0603" (at 0 1.6) (layer "F.Fab")
        (effects (font (size 0.7 0.7) (thickness 0.15)) (justify left bottom))
    )
    (fp_text user "${REFERENCE}" (at -1.25 3.898) (layer "F.Fab") hide
        (effects (font (size 0.7 0.7) (thickness 0.15)) (justify left bottom))
    )
    (fp_text user "License: Apache-2.0" (at -1.25 5.9) (layer "F.Fab") hide
        (effects (font (size 0.7 0.7) (thickness 0.15)) (justify left bottom))
    )
    (fp_text user "Author: Antmicro" (at -1.25 4.9) (layer "F.Fab") hide
        (effects (font (size 0.7 0.7) (thickness 0.15)) (justify left bottom))
    )
    (fp_line (start -0.15 -0.4) (end 0.15 -0.4)
      (stroke (width 0.15) (type solid)) (layer "F.SilkS"))
    (fp_line (start -0.15 0.4) (end 0.15 0.4)
      (stroke (width 0.15) (type solid)) (layer "F.SilkS"))
    (fp_rect (start -1.25 -0.65) (end 1.25 0.65)
      (stroke (width 0.05) (type solid)) (fill none) (layer "F.CrtYd"))
    (fp_rect (start -0.8 -0.4) (end 0.8 0.4)
      (stroke (width 0.15) (type solid)) (fill none) (layer "F.Fab"))
    (pad "1" smd roundrect (at -0.7 0) (size 0.8 1) (layers "F.Cu" "F.Paste" "F.Mask") (roundrect_rratio 0.2)
      (net 52 "Net-(D7-A)") (pintype "passive"))
    (pad "2" smd roundrect (at 0.7 0) (size 0.8 1) (layers "F.Cu" "F.Paste" "F.Mask") (roundrect_rratio 0.2)
      (net 45 "LOAD_4") (pintype "passive"))
  )

  (footprint "antmicro-footprints:R_0402_1005Metric" (layer "F.Cu")
    (at 130.95 90.4 90)
    (descr "Resistor SMD 0402")
    (tags "resistor SMD 0402")
    (property "Author" "Antmicro")
    (property "License" "Apache-2.0")
    (property "MPN" "CR0402-FX-2R00GLF")
    (property "Manufacturer" "Bourns")
    (property "Sheetfile" "power-switch.kicad_sch")
    (property "Sheetname" "Power switch 2")
    (property "Tolerance" "1%")
    (property "Val" "2R")
    (property "ki_description" "SMD Chip Resistor")
    (property "ki_keywords" "0402, SMT, RESISTOR, PASSIVE")
    (attr smd)
    (fp_text reference "R63" (at -1.75 -0.65 90) (layer "F.SilkS")
        (effects (font (size 0.7 0.7) (thickness 0.15)) (justify left bottom))
    )
    (fp_text value "R_2R_0402" (at -1.011843 1.772047 90) (layer "F.Fab")
        (effects (font (size 0.7 0.7) (thickness 0.15)) (justify left bottom))
    )
    (fp_text user "License: Apache-2.0" (at -0.95 5.169 90) (layer "F.Fab") hide
        (effects (font (size 0.7 0.7) (thickness 0.15)) (justify left bottom))
    )
    (fp_text user "Author: Antmicro" (at -0.95 4.169 90) (layer "F.Fab") hide
        (effects (font (size 0.7 0.7) (thickness 0.15)) (justify left bottom))
    )
    (fp_text user "${REFERENCE}" (at -0.95 3.168 90) (layer "F.Fab") hide
        (effects (font (size 0.7 0.7) (thickness 0.15)) (justify left bottom))
    )
    (fp_rect (start -0.925 -0.47) (end 0.925 0.47)
      (stroke (width 0.05) (type default)) (fill none) (layer "F.CrtYd"))
    (fp_rect (start -0.5 -0.25) (end 0.5 0.25)
      (stroke (width 0.15) (type solid)) (fill none) (layer "F.Fab"))
    (pad "1" smd roundrect (at -0.48 0 90) (size 0.59 0.64) (layers "F.Cu" "F.Paste" "F.Mask") (roundrect_rratio 0.25)
      (net 84 "Net-(D16-A)") (pintype "passive"))
    (pad "2" smd roundrect (at 0.48 0 90) (size 0.59 0.64) (layers "F.Cu" "F.Paste" "F.Mask") (roundrect_rratio 0.25)
      (net 94 "Net-(QA2-G)") (pintype "passive"))
  )

  (footprint "antmicro-footprints:R_0402_1005Metric" (layer "F.Cu")
    (at 166.65 113.5 90)
    (descr "Resistor SMD 0402")
    (tags "resistor SMD 0402")
    (property "Author" "Antmicro")
    (property "License" "Apache-2.0")
    (property "MPN" "CR0402-FX-4701GLF")
    (property "Manufacturer" "Bourns")
    (property "Sheetfile" "ftdi-module.kicad_sch")
    (property "Sheetname" "FTDI")
    (property "Tolerance" "1%")
    (property "Val" "4k7")
    (property "ki_description" "SMD Chip Resistor, 4.7 kohm, ± 1%, 62.5 mW, 0402 [1005 Metric], Thick Film, General Purpose")
    (property "ki_keywords" "0402, SMT, RESISTOR, PASSIVE")
    (attr smd)
    (fp_text reference "R6" (at 0.9 0.4 90) (layer "F.SilkS")
        (effects (font (size 0.7 0.7) (thickness 0.15)) (justify left bottom))
    )
    (fp_text value "R_4k7_0402" (at -1.011843 1.772047 90) (layer "F.Fab")
        (effects (font (size 0.7 0.7) (thickness 0.15)) (justify left bottom))
    )
    (fp_text user "License: Apache-2.0" (at -0.95 5.169 90) (layer "F.Fab") hide
        (effects (font (size 0.7 0.7) (thickness 0.15)) (justify left bottom))
    )
    (fp_text user "${REFERENCE}" (at -0.95 3.168 90) (layer "F.Fab") hide
        (effects (font (size 0.7 0.7) (thickness 0.15)) (justify left bottom))
    )
    (fp_text user "Author: Antmicro" (at -0.95 4.169 90) (layer "F.Fab") hide
        (effects (font (size 0.7 0.7) (thickness 0.15)) (justify left bottom))
    )
    (fp_rect (start -0.925 -0.47) (end 0.925 0.47)
      (stroke (width 0.05) (type default)) (fill none) (layer "F.CrtYd"))
    (fp_rect (start -0.5 -0.25) (end 0.5 0.25)
      (stroke (width 0.15) (type solid)) (fill none) (layer "F.Fab"))
    (pad "1" smd roundrect (at -0.48 0 90) (size 0.59 0.64) (layers "F.Cu" "F.Paste" "F.Mask") (roundrect_rratio 0.25)
      (net 80 "SDA_FTDI") (pintype "passive"))
    (pad "2" smd roundrect (at 0.48 0 90) (size 0.59 0.64) (layers "F.Cu" "F.Paste" "F.Mask") (roundrect_rratio 0.25)
      (net 76 "VCC3V3_USB") (pintype "passive"))
  )

  (footprint "antmicro-footprints:C_0402_1005Metric" (layer "F.Cu")
    (at 172.1 101.82 90)
    (descr "Capacitor SMD 0402")
    (tags "capacitor SMD 0402")
    (property "Author" "Antmicro")
    (property "Dielectric" "X5R")
    (property "License" "Apache-2.0")
    (property "MPN" "GRM155R61H104KE14D")
    (property "Manufacturer" "Murata")
    (property "Sheetfile" "ftdi-module.kicad_sch")
    (property "Sheetname" "FTDI")
    (property "Val" "100n")
    (property "Voltage" "50V")
    (property "ki_description" "SMD Multilayer Ceramic Capacitor, 0.1 µF, 50 V, 0402 [1005 Metric], ± 10%, X5R, GRM Series")
    (property "ki_keywords" "0402, SMT, CAPACITOR, PASSIVE, CERAMIC, MLCC")
    (attr smd)
    (fp_text reference "C5" (at 1.695 0 90) (layer "F.SilkS")
        (effects (font (size 0.7 0.7) (thickness 0.15)))
    )
    (fp_text value "C_100n_0402" (at 0 1.17 90) (layer "F.Fab")
        (effects (font (size 1 1) (thickness 0.15)))
    )
    (fp_text user "${REFERENCE}" (at 0 0 90) (layer "F.Fab")
        (effects (font (size 0.25 0.25) (thickness 0.04)))
    )
    (fp_text user "Author: Antmicro" (at -0.939 3.399 90) (layer "F.Fab") hide
        (effects (font (size 0.7 0.7) (thickness 0.15)) (justify left bottom))
    )
    (fp_text user "License: Apache-2.0" (at -0.939 5.799 90) (layer "F.Fab") hide
        (effects (font (size 0.7 0.7) (thickness 0.15)) (justify left bottom))
    )
    (fp_rect (start -0.925 -0.47) (end 0.925 0.47)
      (stroke (width 0.05) (type default)) (fill none) (layer "F.CrtYd"))
    (fp_line (start -0.494 -0.25) (end 0.504 -0.25)
      (stroke (width 0.15) (type solid)) (layer "F.Fab"))
    (fp_line (start -0.494 0.248) (end -0.494 -0.25)
      (stroke (width 0.15) (type solid)) (layer "F.Fab"))
    (fp_line (start 0.504 -0.25) (end 0.504 0.248)
      (stroke (width 0.15) (type solid)) (layer "F.Fab"))
    (fp_line (start 0.504 0.248) (end -0.494 0.248)
      (stroke (width 0.15) (type solid)) (layer "F.Fab"))
    (pad "1" smd roundrect (at -0.48 0 90) (size 0.59 0.64) (layers "F.Cu" "F.Paste" "F.Mask") (roundrect_rratio 0.25)
      (net 4 "GND") (pintype "passive"))
    (pad "2" smd roundrect (at 0.48 0 90) (size 0.59 0.64) (layers "F.Cu" "F.Paste" "F.Mask") (roundrect_rratio 0.25)
      (net 1 "VCC3V3") (pintype "passive"))
  )

  (footprint "antmicro-footprints:R_0402_1005Metric" (layer "F.Cu")
    (at 166.315 101.6 -90)
    (descr "Resistor SMD 0402")
    (tags "resistor SMD 0402")
    (property "Author" "Antmicro")
    (property "License" "Apache-2.0")
    (property "MPN" "CR0402-FX-1002GLF")
    (property "Manufacturer" "Bourns")
    (property "Sheetfile" "ftdi-module.kicad_sch")
    (property "Sheetname" "FTDI")
    (property "Tolerance" "1%")
    (property "Val" "10k")
    (property "ki_description" "SMD Chip Resistor, 10 kohm, ± 1%, 62.5 mW, 0402 [1005 Metric], Thick Film, General Purpose")
    (property "ki_keywords" "0402, SMT, RESISTOR, PASSIVE")
    (attr smd)
    (fp_text reference "R73" (at 1.1 -1.485 -90) (layer "F.SilkS")
        (effects (font (size 0.7 0.7) (thickness 0.15)) (justify left bottom))
    )
    (fp_text value "R_10k_0402" (at -1.011843 1.772047 -90) (layer "F.Fab")
        (effects (font (size 0.7 0.7) (thickness 0.15)) (justify left bottom))
    )
    (fp_text user "Author: Antmicro" (at -0.95 4.169 -90) (layer "F.Fab") hide
        (effects (font (size 0.7 0.7) (thickness 0.15)) (justify left bottom))
    )
    (fp_text user "License: Apache-2.0" (at -0.95 5.169 -90) (layer "F.Fab") hide
        (effects (font (size 0.7 0.7) (thickness 0.15)) (justify left bottom))
    )
    (fp_text user "${REFERENCE}" (at -0.95 3.168 -90) (layer "F.Fab") hide
        (effects (font (size 0.7 0.7) (thickness 0.15)) (justify left bottom))
    )
    (fp_rect (start -0.925 -0.47) (end 0.925 0.47)
      (stroke (width 0.05) (type default)) (fill none) (layer "F.CrtYd"))
    (fp_rect (start -0.5 -0.25) (end 0.5 0.25)
      (stroke (width 0.15) (type solid)) (fill none) (layer "F.Fab"))
    (pad "1" smd roundrect (at -0.48 0 270) (size 0.59 0.64) (layers "F.Cu" "F.Paste" "F.Mask") (roundrect_rratio 0.25)
      (net 1 "VCC3V3") (pintype "passive"))
    (pad "2" smd roundrect (at 0.48 0 270) (size 0.59 0.64) (layers "F.Cu" "F.Paste" "F.Mask") (roundrect_rratio 0.25)
      (net 115 "Net-(U6-A)") (pintype "passive"))
  )

  (footprint "antmicro-footprints:R_0603_1608Metric" (layer "F.Cu")
    (at 181.6 55.75 -90)
    (descr "Resistor SMD 0603")
    (tags "resistor SMD 0603")
    (property "Author" "Antmicro")
    (property "License" "Apache-2.0")
    (property "MPN" "CR0603-FX-4701ELF")
    (property "Manufacturer" "Bourns")
    (property "Sheetfile" "d1600e-psu-breakout-board.kicad_sch")
    (property "Sheetname" "")
    (property "Tolerance" "1%")
    (property "Val" "4k7")
    (property "ki_description" "SMD Chip Resistor, 4.7 kohm, ± 1%, 100 mW, 0603 [1608 Metric], Thick Film, General Purpose")
    (property "ki_keywords" "0603, SMT, RESISTOR, PASSIVE")
    (attr smd)
    (fp_text reference "R53" (at 0.95 0.8 -90) (layer "F.SilkS")
        (effects (font (size 0.7 0.7) (thickness 0.15)) (justify left bottom))
    )
    (fp_text value "R_4k7_0603" (at 0 1.6 -90) (layer "F.Fab")
        (effects (font (size 0.7 0.7) (thickness 0.15)) (justify left bottom))
    )
    (fp_text user "License: Apache-2.0" (at -1.25 5.9 -90) (layer "F.Fab") hide
        (effects (font (size 0.7 0.7) (thickness 0.15)) (justify left bottom))
    )
    (fp_text user "Author: Antmicro" (at -1.25 4.9 -90) (layer "F.Fab") hide
        (effects (font (size 0.7 0.7) (thickness 0.15)) (justify left bottom))
    )
    (fp_text user "${REFERENCE}" (at -1.25 3.898 -90) (layer "F.Fab") hide
        (effects (font (size 0.7 0.7) (thickness 0.15)) (justify left bottom))
    )
    (fp_line (start -0.15 -0.4) (end 0.15 -0.4)
      (stroke (width 0.15) (type solid)) (layer "F.SilkS"))
    (fp_line (start -0.15 0.4) (end 0.15 0.4)
      (stroke (width 0.15) (type solid)) (layer "F.SilkS"))
    (fp_rect (start -1.25 -0.65) (end 1.25 0.65)
      (stroke (width 0.05) (type solid)) (fill none) (layer "F.CrtYd"))
    (fp_rect (start -0.8 -0.4) (end 0.8 0.4)
      (stroke (width 0.15) (type solid)) (fill none) (layer "F.Fab"))
    (pad "1" smd roundrect (at -0.7 0 270) (size 0.8 1) (layers "F.Cu" "F.Paste" "F.Mask") (roundrect_rratio 0.2)
      (net 53 "Net-(D8-A)") (pintype "passive"))
    (pad "2" smd roundrect (at 0.7 0 270) (size 0.8 1) (layers "F.Cu" "F.Paste" "F.Mask") (roundrect_rratio 0.2)
      (net 43 "LOAD_5") (pintype "passive"))
  )

  (footprint "antmicro-footprints:R_0402_1005Metric" (layer "F.Cu")
    (at 164.3 90.6 90)
    (descr "Resistor SMD 0402")
    (tags "resistor SMD 0402")
    (property "Author" "Antmicro")
    (property "License" "Apache-2.0")
    (property "MPN" "CR0402-FX-2R00GLF")
    (property "Manufacturer" "Bourns")
    (property "Sheetfile" "power-switch.kicad_sch")
    (property "Sheetname" "Power switch 4")
    (property "Tolerance" "1%")
    (property "Val" "2R")
    (property "ki_description" "SMD Chip Resistor")
    (property "ki_keywords" "0402, SMT, RESISTOR, PASSIVE")
    (attr smd)
    (fp_text reference "R66" (at -1.45 -0.55 90) (layer "F.SilkS")
        (effects (font (size 0.7 0.7) (thickness 0.15)) (justify left bottom))
    )
    (fp_text value "R_2R_0402" (at -1.011843 1.772047 90) (layer "F.Fab")
        (effects (font (size 0.7 0.7) (thickness 0.15)) (justify left bottom))
    )
    (fp_text user "${REFERENCE}" (at -0.95 3.168 90) (layer "F.Fab") hide
        (effects (font (size 0.7 0.7) (thickness 0.15)) (justify left bottom))
    )
    (fp_text user "Author: Antmicro" (at -0.95 4.169 90) (layer "F.Fab") hide
        (effects (font (size 0.7 0.7) (thickness 0.15)) (justify left bottom))
    )
    (fp_text user "License: Apache-2.0" (at -0.95 5.169 90) (layer "F.Fab") hide
        (effects (font (size 0.7 0.7) (thickness 0.15)) (justify left bottom))
    )
    (fp_rect (start -0.925 -0.47) (end 0.925 0.47)
      (stroke (width 0.05) (type default)) (fill none) (layer "F.CrtYd"))
    (fp_rect (start -0.5 -0.25) (end 0.5 0.25)
      (stroke (width 0.15) (type solid)) (fill none) (layer "F.Fab"))
    (pad "1" smd roundrect (at -0.48 0 90) (size 0.59 0.64) (layers "F.Cu" "F.Paste" "F.Mask") (roundrect_rratio 0.25)
      (net 85 "Net-(D17-A)") (pintype "passive"))
    (pad "2" smd roundrect (at 0.48 0 90) (size 0.59 0.64) (layers "F.Cu" "F.Paste" "F.Mask") (roundrect_rratio 0.25)
      (net 96 "Net-(QA4-G)") (pintype "passive"))
  )

  (footprint "antmicro-footprints:D_SOD-323" (layer "F.Cu")
    (at 135.3 91.6 -90)
    (property "Author" "Antmicro")
    (property "License" "Apache-2.0")
    (property "MPN" "BZT52B15SV-T")
    (property "Manufacturer" "Rectron")
    (property "Sheetfile" "power-switch.kicad_sch")
    (property "Sheetname" "Power switch 2")
    (property "ki_description" "Zener Single Diode, AEC-Q101, 15 V, 500 mW, SOD-323, 2 Pins, 150 °C, Surface Mount")
    (property "ki_keywords" "SMT, DIODE, SEMICONDUCTOR, ZENER")
    (attr smd)
    (fp_text reference "D16" (at 2.75 1.45) (layer "F.SilkS")
        (effects (font (size 0.7 0.7) (thickness 0.15)) (justify left bottom))
    )
    (fp_text value "BZT52B15SV-T" (at 0 1.841 -90) (layer "F.Fab")
        (effects (font (size 0.7 0.7) (thickness 0.15)) (justify left bottom))
    )
    (fp_text user "Author: Antmicro" (at -1.4 6.241 -90) (layer "F.Fab") hide
        (effects (font (size 0.7 0.7) (thickness 0.15)) (justify left bottom))
    )
    (fp_text user "${REFERENCE}" (at -1.4 5.041 -90) (layer "F.Fab") hide
        (effects (font (size 0.7 0.7) (thickness 0.15)) (justify left bottom))
    )
    (fp_text user "License: Apache-2.0" (at -1.4 3.841 -90) (layer "F.Fab") hide
        (effects (font (size 0.7 0.7) (thickness 0.15)) (justify left bottom))
    )
    (fp_line (start -0.949 -0.749) (end -0.949 -0.499)
      (stroke (width 0.15) (type solid)) (layer "F.SilkS"))
    (fp_line (start -0.949 0.501) (end -0.949 0.751)
      (stroke (width 0.15) (type solid)) (layer "F.SilkS"))
    (fp_line (start -0.6 -0.499) (end -0.6 0.499)
      (stroke (width 0.15) (type solid)) (layer "F.SilkS"))
    (fp_line (start -0.577 -0.749) (end -0.949 -0.749)
      (stroke (width 0.15) (type solid)) (layer "F.SilkS"))
    (fp_line (start -0.577 0.751) (end -0.949 0.751)
      (stroke (width 0.15) (type solid)) (layer "F.SilkS"))
    (fp_line (start 0.625 -0.736) (end 0.949 -0.736)
      (stroke (width 0.15) (type solid)) (layer "F.SilkS"))
    (fp_line (start 0.949 -0.736) (end 0.949 -0.499)
      (stroke (width 0.15) (type solid)) (layer "F.SilkS"))
    (fp_line (start 0.95 0.501) (end 0.95 0.751)
      (stroke (width 0.15) (type solid)) (layer "F.SilkS"))
    (fp_line (start 0.95 0.751) (end 0.649 0.751)
      (stroke (width 0.15) (type solid)) (layer "F.SilkS"))
    (fp_rect (start -1.6 -0.925) (end 1.6 0.925)
      (stroke (width 0.05) (type solid)) (fill none) (layer "F.CrtYd"))
    (fp_line (start -0.902 0.699) (end -0.902 -0.699)
      (stroke (width 0.15) (type solid)) (layer "F.Fab"))
    (fp_line (start -0.902 0.699) (end 0.9 0.699)
      (stroke (width 0.15) (type solid)) (layer "F.Fab"))
    (fp_line (start 0.9 -0.699) (end -0.902 -0.699)
      (stroke (width 0.15) (type solid)) (layer "F.Fab"))
    (fp_line (start 0.9 -0.699) (end 0.9 0.699)
      (stroke (width 0.15) (type solid)) (layer "F.Fab"))
    (pad "1" smd rect (at -1.125 0.001 270) (size 0.8 0.8) (layers "F.Cu" "F.Paste" "F.Mask")
      (net 11 "VCC12V0") (pinfunction "C") (pintype "passive"))
    (pad "2" smd rect (at 1.124 0.001 270) (size 0.8 0.8) (layers "F.Cu" "F.Paste" "F.Mask")
      (net 84 "Net-(D16-A)") (pinfunction "A") (pintype "passive"))
  )

  (footprint "antmicro-footprints:R_0402_1005Metric" (layer "F.Cu")
    (at 147.65 90.6 90)
    (descr "Resistor SMD 0402")
    (tags "resistor SMD 0402")
    (property "Author" "Antmicro")
    (property "License" "Apache-2.0")
    (property "MPN" "CR0402-FX-2R00GLF")
    (property "Manufacturer" "Bourns")
    (property "Sheetfile" "power-switch.kicad_sch")
    (property "Sheetname" "Power switch 3")
    (property "Tolerance" "1%")
    (property "Val" "2R")
    (property "ki_description" "SMD Chip Resistor")
    (property "ki_keywords" "0402, SMT, RESISTOR, PASSIVE")
    (attr smd)
    (fp_text reference "R67" (at -1.6 -0.7 90) (layer "F.SilkS")
        (effects (font (size 0.7 0.7) (thickness 0.15)) (justify left bottom))
    )
    (fp_text value "R_2R_0402" (at -1.011843 1.772047 90) (layer "F.Fab")
        (effects (font (size 0.7 0.7) (thickness 0.15)) (justify left bottom))
    )
    (fp_text user "${REFERENCE}" (at -0.95 3.168 90) (layer "F.Fab") hide
        (effects (font (size 0.7 0.7) (thickness 0.15)) (justify left bottom))
    )
    (fp_text user "License: Apache-2.0" (at -0.95 5.169 90) (layer "F.Fab") hide
        (effects (font (size 0.7 0.7) (thickness 0.15)) (justify left bottom))
    )
    (fp_text user "Author: Antmicro" (at -0.95 4.169 90) (layer "F.Fab") hide
        (effects (font (size 0.7 0.7) (thickness 0.15)) (justify left bottom))
    )
    (fp_rect (start -0.925 -0.47) (end 0.925 0.47)
      (stroke (width 0.05) (type default)) (fill none) (layer "F.CrtYd"))
    (fp_rect (start -0.5 -0.25) (end 0.5 0.25)
      (stroke (width 0.15) (type solid)) (fill none) (layer "F.Fab"))
    (pad "1" smd roundrect (at -0.48 0 90) (size 0.59 0.64) (layers "F.Cu" "F.Paste" "F.Mask") (roundrect_rratio 0.25)
      (net 86 "Net-(D18-A)") (pintype "passive"))
    (pad "2" smd roundrect (at 0.48 0 90) (size 0.59 0.64) (layers "F.Cu" "F.Paste" "F.Mask") (roundrect_rratio 0.25)
      (net 95 "Net-(QA3-G)") (pintype "passive"))
  )

  (footprint "antmicro-footprints:SC-70-5" (layer "F.Cu")
    (at 170.2 102.091 -90)
    (descr "5-lead Small Outline SMT package (aka SC-70-5, SC-88A or TSSOP5): reflow soldering footprint")
    (tags "SOT-353 sot353 SC-70-5 sc70 SC-88A sc88a TSSOP5")
    (property "Author" "Antmicro")
    (property "License" "Apache-2.0")
    (property "MPN" "SN74AUP1G17DCKR")
    (property "Manufacturer" "Texas Instruments")
    (property "Sheetfile" "ftdi-module.kicad_sch")
    (property "Sheetname" "FTDI")
    (property "ki_description" "Buffer, 74AUP1G17, 0.8 V to 3.6 V, TSSOP-5")
    (property "ki_keywords" "SMT, LOGIC, IC, BUFFER, TRANSCEIVER")
    (attr smd)
    (fp_text reference "U6" (at -1.421 0.71) (layer "F.SilkS")
        (effects (font (size 0.7 0.7) (thickness 0.15)) (justify left bottom))
    )
    (fp_text value "SN74AUP1G17_SC70" (at 0 2.4 90) (layer "F.Fab")
        (effects (font (size 0.7 0.7) (thickness 0.15)) (justify right bottom))
    )
    (fp_text user "License: Apache-2.0" (at -1.206 6.427 90) (layer "F.Fab") hide
        (effects (font (size 0.7 0.7) (thickness 0.15)) (justify right bottom))
    )
    (fp_text user "Author: Antmicro" (at -1.206 5.227 90) (layer "F.Fab") hide
        (effects (font (size 0.7 0.7) (thickness 0.15)) (justify right bottom))
    )
    (fp_text user "${REFERENCE}" (at -1.206 4.027 90) (layer "F.Fab") hide
        (effects (font (size 0.7 0.7) (thickness 0.15)) (justify right bottom))
    )
    (fp_line (start -1.156 0.694) (end -1.156 -0.705)
      (stroke (width 0.15) (type solid)) (layer "F.SilkS"))
    (fp_line (start 1.144 0.694) (end 1.144 -0.705)
      (stroke (width 0.15) (type solid)) (layer "F.SilkS"))
    (fp_circle (center -1.25 0.95) (end -1.19 1)
      (stroke (width 0.15) (type solid)) (fill solid) (layer "F.SilkS"))
    (fp_rect (start 1.25 -1.31) (end -1.25 1.3)
      (stroke (width 0.05) (type solid)) (fill none) (layer "F.CrtYd"))
    (fp_line (start -1.006 -0.657) (end 0.993 -0.657)
      (stroke (width 0.15) (type solid)) (layer "F.Fab"))
    (fp_line (start -1.006 0.293) (end -1.006 -0.657)
      (stroke (width 0.15) (type solid)) (layer "F.Fab"))
    (fp_line (start -1.006 0.293) (end -0.706 0.593)
      (stroke (width 0.15) (type solid)) (layer "F.Fab"))
    (fp_line (start 0.993 -0.657) (end 0.993 0.593)
      (stroke (width 0.15) (type solid)) (layer "F.Fab"))
    (fp_line (start 0.993 0.593) (end -0.706 0.593)
      (stroke (width 0.15) (type solid)) (layer "F.Fab"))
    (pad "1" smd roundrect (at -0.756 0.893) (size 0.6 0.6) (layers "F.Cu" "F.Paste" "F.Mask") (roundrect_rratio 0.25)
      (net 159 "unconnected-(U6-NC-Pad1)") (pinfunction "NC") (pintype "no_connect"))
    (pad "2" smd roundrect (at -0.006 0.893) (size 0.6 0.4) (layers "F.Cu" "F.Paste" "F.Mask") (roundrect_rratio 0.25)
      (net 115 "Net-(U6-A)") (pinfunction "A") (pintype "input"))
    (pad "3" smd roundrect (at 0.743 0.893) (size 0.6 0.6) (layers "F.Cu" "F.Paste" "F.Mask") (roundrect_rratio 0.25)
      (net 4 "GND") (pinfunction "GND") (pintype "power_in"))
    (pad "4" smd roundrect (at 0.743 -0.907) (size 0.6 0.6) (layers "F.Cu" "F.Paste" "F.Mask") (roundrect_rratio 0.25)
      (net 145 "LED_DATA") (pinfunction "Y") (pintype "output"))
    (pad "5" smd roundrect (at -0.756 -0.907) (size 0.6 0.6) (layers "F.Cu" "F.Paste" "F.Mask") (roundrect_rratio 0.25)
      (net 1 "VCC3V3") (pinfunction "VCC") (pintype "power_in"))
  )

  (footprint "antmicro-footprints:LED_0603_1608Metric_G" (layer "F.Cu")
    (at 94.2 99)
    (descr "LED SMD 0603 Green")
    (tags "LED SMD 0603 Green")
    (property "Author" "Antmicro")
    (property "Color" "Green")
    (property "License" "Apache-2.0")
    (property "MPN" "LG L29K-G2J1-24-Z")
    (property "Manufacturer" "OSRAM")
    (property "Sheetfile" "d1600e-psu-breakout-board.kicad_sch")
    (property "Sheetname" "")
    (property "ki_description" "LED, Green, SMD, 0603, 20 mA, 1.7 V, 570 nm")
    (property "ki_keywords" "SMT, DIODE, SEMICONDUCTOR, LED")
    (zone_connect 1)
    (attr smd)
    (fp_text reference "D10" (at -1.2 -0.7) (layer "F.SilkS")
        (effects (font (size 0.7 0.7) (thickness 0.15)) (justify left bottom))
    )
    (fp_text value "LED_G_0603_LG_L29K-G2J1-24-Z" (at -0.001 1.599) (layer "F.Fab")
        (effects (font (size 0.7 0.7) (thickness 0.15)) (justify left bottom))
    )
    (fp_text user "License: Apache-2.0" (at -1.4224 3.599) (layer "F.Fab") hide
        (effects (font (size 0.7 0.7) (thickness 0.15)) (justify left bottom))
    )
    (fp_text user "${REFERENCE}" (at -1.4224 5.999) (layer "F.Fab") hide
        (effects (font (size 0.7 0.7) (thickness 0.15)) (justify left bottom))
    )
    (fp_text user "Author: Antmicro" (at -1.4224 4.799) (layer "F.Fab") hide
        (effects (font (size 0.7 0.7) (thickness 0.15)) (justify left bottom))
    )
    (fp_line (start -1.18 -0.319) (end -1.18 0.321)
      (stroke (width 0.15) (type solid)) (layer "F.SilkS"))
    (fp_line (start -0.094672 0.001008) (end -0.24 0.001008)
      (stroke (width 0.1) (type solid)) (layer "F.SilkS"))
    (fp_line (start -0.094672 0.001008) (end 0.105328 -0.198992)
      (stroke (width 0.1) (type solid)) (layer "F.SilkS"))
    (fp_line (start -0.094672 0.201008) (end -0.094672 -0.198992)
      (stroke (width 0.1) (type solid)) (layer "F.SilkS"))
    (fp_line (start 0.105328 0.001008) (end 0.24 0.001)
      (stroke (width 0.1) (type solid)) (layer "F.SilkS"))
    (fp_line (start 0.105328 0.201008) (end -0.094672 0.001008)
      (stroke (width 0.1) (type solid)) (layer "F.SilkS"))
    (fp_line (start 0.105328 0.201008) (end 0.105328 -0.198992)
      (stroke (width 0.1) (type solid)) (layer "F.SilkS"))
    (fp_line (start 0.22 -0.35) (end -0.22 -0.35)
      (stroke (width 0.15) (type solid)) (layer "F.SilkS"))
    (fp_line (start 0.22 0.35) (end -0.22 0.35)
      (stroke (width 0.15) (type solid)) (layer "F.SilkS"))
    (fp_rect (start 1.25 0.65) (end -1.25 -0.65)
      (stroke (width 0.05) (type solid)) (fill none) (layer "F.CrtYd"))
    (fp_line (start -0.199 -0.202) (end -0.199 0.1)
      (stroke (width 0.15) (type solid)) (layer "F.Fab"))
    (fp_line (start -0.199 0) (end -0.597 0)
      (stroke (width 0.15) (type solid)) (layer "F.Fab"))
    (fp_line (start -0.199 0.2) (end -0.199 0.1)
      (stroke (width 0.15) (type solid)) (layer "F.Fab"))
    (fp_line (start -0.101 0) (end 0.201 0.2)
      (stroke (width 0.15) (type solid)) (layer "F.Fab"))
    (fp_line (start 0.201 -0.202) (end -0.101 0)
      (stroke (width 0.15) (type solid)) (layer "F.Fab"))
    (fp_line (start 0.201 0) (end 0.201 -0.202)
      (stroke (width 0.15) (type solid)) (layer "F.Fab"))
    (fp_line (start 0.201 0.2) (end 0.201 0)
      (stroke (width 0.15) (type solid)) (layer "F.Fab"))
    (fp_line (start 0.599 0) (end 0.201 0)
      (stroke (width 0.15) (type solid)) (layer "F.Fab"))
    (fp_rect (start 0.848 0.4) (end -0.85 -0.402)
      (stroke (width 0.15) (type solid)) (fill none) (layer "F.Fab"))
    (pad "1" smd roundrect (at -0.7 0 180) (size 0.8 1) (layers "F.Cu" "F.Paste" "F.Mask") (roundrect_rratio 0.2)
      (net 4 "GND") (pinfunction "C") (pintype "passive"))
    (pad "2" smd roundrect (at 0.7 0 180) (size 0.8 1) (layers "F.Cu" "F.Paste" "F.Mask") (roundrect_rratio 0.2)
      (net 79 "Net-(D10-A)") (pinfunction "A") (pintype "passive"))
  )

  (footprint "antmicro-footprints:R_0402_1005Metric" (layer "F.Cu")
    (at 162.3 89.5 180)
    (descr "Resistor SMD 0402")
    (tags "resistor SMD 0402")
    (property "Author" "Antmicro")
    (property "DNP" "DNP")
    (property "License" "Apache-2.0")
    (property "MPN" "CR0402-FX-1002GLF")
    (property "Manufacturer" "Bourns")
    (property "Sheetfile" "power-switch.kicad_sch")
    (property "Sheetname" "Power switch 4")
    (property "Tolerance" "1%")
    (property "Val" "10k")
    (property "dnp" "")
    (property "exclude_from_bom" "")
    (property "ki_description" "SMD Chip Resistor, 10 kohm, ± 1%, 62.5 mW, 0402 [1005 Metric], Thick Film, General Purpose")
    (property "ki_keywords" "0402, SMT, RESISTOR, PASSIVE")
    (attr smd exclude_from_bom)
    (fp_text reference "R49" (at 2.1 0) (layer "F.SilkS")
        (effects (font (size 0.7 0.7) (thickness 0.15)))
    )
    (fp_text value "R_10k_0402" (at 0 1.17) (layer "F.Fab") hide
        (effects (font (size 1 1) (thickness 0.15)))
    )
    (fp_text user "Author: Antmicro" (at -0.95 4.169 180) (layer "F.Fab") hide
        (effects (font (size 0.7 0.7) (thickness 0.15)) (justify left bottom))
    )
    (fp_text user "${REFERENCE}" (at 0 0) (layer "F.Fab")
        (effects (font (size 0.25 0.25) (thickness 0.04)))
    )
    (fp_text user "License: Apache-2.0" (at -0.95 5.169 180) (layer "F.Fab") hide
        (effects (font (size 0.7 0.7) (thickness 0.15)) (justify left bottom))
    )
    (fp_rect (start -0.925 -0.47) (end 0.925 0.47)
      (stroke (width 0.05) (type default)) (fill none) (layer "F.CrtYd"))
    (fp_rect (start -0.5 -0.25) (end 0.5 0.25)
      (stroke (width 0.15) (type solid)) (fill none) (layer "F.Fab"))
    (pad "1" smd roundrect (at -0.48 0 180) (size 0.59 0.64) (layers "F.Cu" "F.Paste" "F.Mask") (roundrect_rratio 0.25)
      (net 29 "/Power Cycling & Current Measurement/PC_4") (pintype "passive"))
    (pad "2" smd roundrect (at 0.48 0 180) (size 0.59 0.64) (layers "F.Cu" "F.Paste" "F.Mask") (roundrect_rratio 0.25)
      (net 4 "GND") (pintype "passive"))
  )

  (footprint "antmicro-footprints:R_0603_1608Metric" (layer "F.Cu")
    (at 96.9 101.6)
    (descr "Resistor SMD 0603")
    (tags "resistor SMD 0603")
    (property "Author" "Antmicro")
    (property "License" "Apache-2.0")
    (property "MPN" "CR0603-FX-1001ELF")
    (property "Manufacturer" "Bourns")
    (property "Sheetfile" "d1600e-psu-breakout-board.kicad_sch")
    (property "Sheetname" "")
    (property "Tolerance" "1%")
    (property "Val" "1k")
    (property "ki_description" "SMD Chip Resistor, 1 kohm, ± 1%, 100 mW, 0603 [1608 Metric], Thick Film, General Purpose")
    (property "ki_keywords" "0603, SMT, RESISTOR, PASSIVE")
    (attr smd)
    (fp_text reference "R54" (at -1.15 -0.65) (layer "F.SilkS")
        (effects (font (size 0.7 0.7) (thickness 0.15)) (justify left bottom))
    )
    (fp_text value "R_1k_0603" (at 0 1.6) (layer "F.Fab")
        (effects (font (size 0.7 0.7) (thickness 0.15)) (justify left bottom))
    )
    (fp_text user "License: Apache-2.0" (at -1.25 5.9) (layer "F.Fab") hide
        (effects (font (size 0.7 0.7) (thickness 0.15)) (justify left bottom))
    )
    (fp_text user "Author: Antmicro" (at -1.25 4.9) (layer "F.Fab") hide
        (effects (font (size 0.7 0.7) (thickness 0.15)) (justify left bottom))
    )
    (fp_text user "${REFERENCE}" (at -1.25 3.898) (layer "F.Fab") hide
        (effects (font (size 0.7 0.7) (thickness 0.15)) (justify left bottom))
    )
    (fp_line (start -0.15 -0.4) (end 0.15 -0.4)
      (stroke (width 0.15) (type solid)) (layer "F.SilkS"))
    (fp_line (start -0.15 0.4) (end 0.15 0.4)
      (stroke (width 0.15) (type solid)) (layer "F.SilkS"))
    (fp_rect (start -1.25 -0.65) (end 1.25 0.65)
      (stroke (width 0.05) (type solid)) (fill none) (layer "F.CrtYd"))
    (fp_rect (start -0.8 -0.4) (end 0.8 0.4)
      (stroke (width 0.15) (type solid)) (fill none) (layer "F.Fab"))
    (pad "1" smd roundrect (at -0.7 0) (size 0.8 1) (layers "F.Cu" "F.Paste" "F.Mask") (roundrect_rratio 0.2)
      (net 78 "Net-(D9-A)") (pintype "passive"))
    (pad "2" smd roundrect (at 0.7 0) (size 0.8 1) (layers "F.Cu" "F.Paste" "F.Mask") (roundrect_rratio 0.2)
      (net 1 "VCC3V3") (pintype "passive"))
  )

  (footprint "antmicro-footprints:R_0402_1005Metric" (layer "F.Cu")
    (at 180 90.7 90)
    (descr "Resistor SMD 0402")
    (tags "resistor SMD 0402")
    (property "Author" "Antmicro")
    (property "License" "Apache-2.0")
    (property "MPN" "CR0402-FX-2R00GLF")
    (property "Manufacturer" "Bourns")
    (property "Sheetfile" "power-switch.kicad_sch")
    (property "Sheetname" "Power switch 5")
    (property "Tolerance" "1%")
    (property "Val" "2R")
    (property "ki_description" "SMD Chip Resistor")
    (property "ki_keywords" "0402, SMT, RESISTOR, PASSIVE")
    (attr smd)
    (fp_text reference "R69" (at -2 -0.772697 90) (layer "F.SilkS")
        (effects (font (size 0.7 0.7) (thickness 0.15)) (justify left bottom))
    )
    (fp_text value "R_2R_0402" (at -1.011843 1.772047 90) (layer "F.Fab")
        (effects (font (size 0.7 0.7) (thickness 0.15)) (justify left bottom))
    )
    (fp_text user "Author: Antmicro" (at -0.95 4.169 90) (layer "F.Fab") hide
        (effects (font (size 0.7 0.7) (thickness 0.15)) (justify left bottom))
    )
    (fp_text user "License: Apache-2.0" (at -0.95 5.169 90) (layer "F.Fab") hide
        (effects (font (size 0.7 0.7) (thickness 0.15)) (justify left bottom))
    )
    (fp_text user "${REFERENCE}" (at -0.95 3.168 90) (layer "F.Fab") hide
        (effects (font (size 0.7 0.7) (thickness 0.15)) (justify left bottom))
    )
    (fp_rect (start -0.925 -0.47) (end 0.925 0.47)
      (stroke (width 0.05) (type default)) (fill none) (layer "F.CrtYd"))
    (fp_rect (start -0.5 -0.25) (end 0.5 0.25)
      (stroke (width 0.15) (type solid)) (fill none) (layer "F.Fab"))
    (pad "1" smd roundrect (at -0.48 0 90) (size 0.59 0.64) (layers "F.Cu" "F.Paste" "F.Mask") (roundrect_rratio 0.25)
      (net 87 "Net-(D19-A)") (pintype "passive"))
    (pad "2" smd roundrect (at 0.48 0 90) (size 0.59 0.64) (layers "F.Cu" "F.Paste" "F.Mask") (roundrect_rratio 0.25)
      (net 97 "Net-(QA5-G)") (pintype "passive"))
  )

  (footprint "antmicro-footprints:Vishay_PowerPAK_1212-8_Single" (layer "F.Cu")
    (at 116.5 86.95 90)
    (descr "PowerPAK 1212-8 Single")
    (tags "Vishay PowerPAK 1212-8 Single")
    (property "Author" "Antmicro")
    (property "License" "Apache-2.0")
    (property "MPN" "SI7613DN-T1-GE3")
    (property "Manufacturer" "Vishay")
    (property "Sheetfile" "power-switch.kicad_sch")
    (property "Sheetname" "Power switch 1")
    (property "ki_description" "Power MOSFET, P Channel, 20 V, 35 A, 0.0072 ohm, PowerPAK 1212, Surface Mount")
    (property "ki_keywords" "SMT, TRANSISTOR, SEMICONDUCTOR, MOSFET, PMOS")
    (attr smd)
    (fp_text reference "QB1" (at -2.9 -1.05 180) (layer "F.SilkS")
        (effects (font (size 0.7 0.7) (thickness 0.15)) (justify left bottom))
    )
    (fp_text value "SI7613DN-T1-GE3" (at 0 2.7 90) (layer "F.Fab")
        (effects (font (size 0.7 0.7) (thickness 0.15)) (justify left bottom))
    )
    (fp_text user "${REFERENCE}" (at -8 4.7 90) (layer "F.Fab") hide
        (effects (font (size 0.7 0.7) (thickness 0.15)) (justify left bottom))
    )
    (fp_text user "License: Apache-2.0" (at -8 7.1 90) (layer "F.Fab") hide
        (effects (font (size 0.7 0.7) (thickness 0.15)) (justify left bottom))
    )
    (fp_text user "Author: Antmicro" (at -8 5.9 90) (layer "F.Fab") hide
        (effects (font (size 0.7 0.7) (thickness 0.15)) (justify left bottom))
    )
    (fp_line (start -1.651 -1.651) (end -1.651 -1.317)
      (stroke (width 0.15) (type solid)) (layer "F.SilkS"))
    (fp_line (start -1.651 -1.651) (end 1.648 -1.651)
      (stroke (width 0.15) (type solid)) (layer "F.SilkS"))
    (fp_line (start -1.635 1.3) (end -1.635 1.634)
      (stroke (width 0.15) (type solid)) (layer "F.SilkS"))
    (fp_line (start -1.635 1.634) (end 1.634 1.634)
      (stroke (width 0.15) (type solid)) (layer "F.SilkS"))
    (fp_line (start 1.634 1.3) (end 1.634 1.634)
      (stroke (width 0.15) (type solid)) (layer "F.SilkS"))
    (fp_line (start 1.648 -1.651) (end 1.648 -1.317)
      (stroke (width 0.15) (type solid)) (layer "F.SilkS"))
    (fp_circle (center -1.9 -1.4) (end -1.85 -1.4)
      (stroke (width 0.15) (type solid)) (fill solid) (layer "F.SilkS"))
    (fp_rect (start -2 -1.8) (end 2 1.798)
      (stroke (width 0.05) (type solid)) (fill none) (layer "F.CrtYd"))
    (fp_line (start -1.6425 -1.4175) (end -1.4175 -1.6425)
      (stroke (width 0.15) (type solid)) (layer "F.Fab"))
    (fp_rect (start -1.651 -1.651) (end 1.648 1.648)
      (stroke (width 0.15) (type solid)) (fill none) (layer "F.Fab"))
    (pad "1" smd rect (at -1.436 -0.99 90) (size 0.99 0.405) (layers "F.Cu" "F.Paste" "F.Mask")
      (net 11 "VCC12V0") (pinfunction "S") (pintype "passive"))
    (pad "2" smd rect (at -1.436 -0.332 90) (size 0.99 0.405) (layers "F.Cu" "F.Paste" "F.Mask")
      (net 11 "VCC12V0") (pinfunction "S") (pintype "passive"))
    (pad "3" smd rect (at -1.436 0.33 90) (size 0.99 0.405) (layers "F.Cu" "F.Paste" "F.Mask")
      (net 11 "VCC12V0") (pinfunction "S") (pintype "passive"))
    (pad "4" smd rect (at -1.436 0.988 90) (size 0.99 0.405) (layers "F.Cu" "F.Paste" "F.Mask")
      (net 98 "Net-(QB1-G)") (pinfunction "G") (pintype "passive"))
    (pad "5" smd custom (at 0.557 0 90) (size 1.725 2.235) (layers "F.Cu" "F.Paste" "F.Mask")
      (net 21 "C_MEAS_1") (pinfunction "D") (pintype "passive") (zone_connect 2)
      (options (clearance outline) (anchor rect))
      (primitives
        (gr_poly
          (pts
            (xy 0.8625 0.1275)
            (xy 0.8625 -0.1275)
            (xy 1.3725 -0.1275)
            (xy 1.3725 -0.5325)
            (xy 0.8625 -0.5325)
            (xy 0.8625 -0.7875)
            (xy 1.3725 -0.7875)
            (xy 1.3725 -1.195)
            (xy 0.6125 -1.195)
            (xy 0.6125 1.195)
            (xy 1.3725 1.195)
            (xy 1.3725 0.7875)
            (xy 0.8625 0.7875)
            (xy 0.8625 0.5325)
            (xy 1.3725 0.5325)
            (xy 1.3725 0.1275)
          )
          (width 0) (fill yes))
      ))
  )

  (footprint "antmicro-footprints:Vishay_PowerPAK_1212-8_Single" (layer "F.Cu")
    (at 150.2275 87.2 90)
    (descr "PowerPAK 1212-8 Single")
    (tags "Vishay PowerPAK 1212-8 Single")
    (property "Author" "Antmicro")
    (property "License" "Apache-2.0")
    (property "MPN" "SI7613DN-T1-GE3")
    (property "Manufacturer" "Vishay")
    (property "Sheetfile" "power-switch.kicad_sch")
    (property "Sheetname" "Power switch 3")
    (property "ki_description" "Power MOSFET, P Channel, 20 V, 35 A, 0.0072 ohm, PowerPAK 1212, Surface Mount")
    (property "ki_keywords" "SMT, TRANSISTOR, SEMICONDUCTOR, MOSFET, PMOS")
    (attr smd)
    (fp_text reference "QA3" (at -2.95 -1.0275 180) (layer "F.SilkS")
        (effects (font (size 0.7 0.7) (thickness 0.15)) (justify left bottom))
    )
    (fp_text value "SI7613DN-T1-GE3" (at 0 2.7 90) (layer "F.Fab")
        (effects (font (size 0.7 0.7) (thickness 0.15)) (justify left bottom))
    )
    (fp_text user "License: Apache-2.0" (at -8 7.1 90) (layer "F.Fab") hide
        (effects (font (size 0.7 0.7) (thickness 0.15)) (justify left bottom))
    )
    (fp_text user "${REFERENCE}" (at -8 4.7 90) (layer "F.Fab") hide
        (effects (font (size 0.7 0.7) (thickness 0.15)) (justify left bottom))
    )
    (fp_text user "Author: Antmicro" (at -8 5.9 90) (layer "F.Fab") hide
        (effects (font (size 0.7 0.7) (thickness 0.15)) (justify left bottom))
    )
    (fp_line (start -1.651 -1.651) (end -1.651 -1.317)
      (stroke (width 0.15) (type solid)) (layer "F.SilkS"))
    (fp_line (start -1.651 -1.651) (end 1.648 -1.651)
      (stroke (width 0.15) (type solid)) (layer "F.SilkS"))
    (fp_line (start -1.635 1.3) (end -1.635 1.634)
      (stroke (width 0.15) (type solid)) (layer "F.SilkS"))
    (fp_line (start -1.635 1.634) (end 1.634 1.634)
      (stroke (width 0.15) (type solid)) (layer "F.SilkS"))
    (fp_line (start 1.634 1.3) (end 1.634 1.634)
      (stroke (width 0.15) (type solid)) (layer "F.SilkS"))
    (fp_line (start 1.648 -1.651) (end 1.648 -1.317)
      (stroke (width 0.15) (type solid)) (layer "F.SilkS"))
    (fp_circle (center -1.9 -1.4) (end -1.85 -1.4)
      (stroke (width 0.15) (type solid)) (fill solid) (layer "F.SilkS"))
    (fp_rect (start -2 -1.8) (end 2 1.798)
      (stroke (width 0.05) (type solid)) (fill none) (layer "F.CrtYd"))
    (fp_line (start -1.6425 -1.4175) (end -1.4175 -1.6425)
      (stroke (width 0.15) (type solid)) (layer "F.Fab"))
    (fp_rect (start -1.651 -1.651) (end 1.648 1.648)
      (stroke (width 0.15) (type solid)) (fill none) (layer "F.Fab"))
    (pad "1" smd rect (at -1.436 -0.99 90) (size 0.99 0.405) (layers "F.Cu" "F.Paste" "F.Mask")
      (net 11 "VCC12V0") (pinfunction "S") (pintype "passive"))
    (pad "2" smd rect (at -1.436 -0.332 90) (size 0.99 0.405) (layers "F.Cu" "F.Paste" "F.Mask")
      (net 11 "VCC12V0") (pinfunction "S") (pintype "passive"))
    (pad "3" smd rect (at -1.436 0.33 90) (size 0.99 0.405) (layers "F.Cu" "F.Paste" "F.Mask")
      (net 11 "VCC12V0") (pinfunction "S") (pintype "passive"))
    (pad "4" smd rect (at -1.436 0.988 90) (size 0.99 0.405) (layers "F.Cu" "F.Paste" "F.Mask")
      (net 95 "Net-(QA3-G)") (pinfunction "G") (pintype "passive"))
    (pad "5" smd custom (at 0.557 0 90) (size 1.725 2.235) (layers "F.Cu" "F.Paste" "F.Mask")
      (net 28 "C_MEAS_3") (pinfunction "D") (pintype "passive") (zone_connect 2)
      (options (clearance outline) (anchor rect))
      (primitives
        (gr_poly
          (pts
            (xy 0.8625 0.1275)
            (xy 0.8625 -0.1275)
            (xy 1.3725 -0.1275)
            (xy 1.3725 -0.5325)
            (xy 0.8625 -0.5325)
            (xy 0.8625 -0.7875)
            (xy 1.3725 -0.7875)
            (xy 1.3725 -1.195)
            (xy 0.6125 -1.195)
            (xy 0.6125 1.195)
            (xy 1.3725 1.195)
            (xy 1.3725 0.7875)
            (xy 0.8625 0.7875)
            (xy 0.8625 0.5325)
            (xy 1.3725 0.5325)
            (xy 1.3725 0.1275)
          )
          (width 0) (fill yes))
      ))
  )

  (footprint "antmicro-footprints:C_0402_1005Metric" (layer "F.Cu")
    (at 149.935 103.7)
    (descr "Capacitor SMD 0402")
    (tags "capacitor SMD 0402")
    (property "Author" "Antmicro")
    (property "Dielectric" "X5R")
    (property "License" "Apache-2.0")
    (property "MPN" "GRM155R61H104KE14D")
    (property "Manufacturer" "Murata")
    (property "Sheetfile" "pow-cycl-curr-meas.kicad_sch")
    (property "Sheetname" "Power Cycling & Current Measurement")
    (property "Val" "100n")
    (property "Voltage" "50V")
    (property "ki_description" "SMD Multilayer Ceramic Capacitor, 0.1 µF, 50 V, 0402 [1005 Metric], ± 10%, X5R, GRM Series")
    (property "ki_keywords" "0402, SMT, CAPACITOR, PASSIVE, CERAMIC, MLCC")
    (attr smd)
    (fp_text reference "C37" (at 2.065 0.15) (layer "F.SilkS")
        (effects (font (size 0.7 0.7) (thickness 0.15)))
    )
    (fp_text value "C_100n_0402" (at 0 1.17) (layer "F.Fab") hide
        (effects (font (size 1 1) (thickness 0.15)))
    )
    (fp_text user "License: Apache-2.0" (at -0.939 5.799) (layer "F.Fab") hide
        (effects (font (size 0.7 0.7) (thickness 0.15)) (justify left bottom))
    )
    (fp_text user "Author: Antmicro" (at -0.939 3.399) (layer "F.Fab") hide
        (effects (font (size 0.7 0.7) (thickness 0.15)) (justify left bottom))
    )
    (fp_text user "${REFERENCE}" (at 0 0) (layer "F.Fab")
        (effects (font (size 0.25 0.25) (thickness 0.04)))
    )
    (fp_rect (start -0.925 -0.47) (end 0.925 0.47)
      (stroke (width 0.05) (type default)) (fill none) (layer "F.CrtYd"))
    (fp_line (start -0.494 -0.25) (end 0.504 -0.25)
      (stroke (width 0.15) (type solid)) (layer "F.Fab"))
    (fp_line (start -0.494 0.248) (end -0.494 -0.25)
      (stroke (width 0.15) (type solid)) (layer "F.Fab"))
    (fp_line (start 0.504 -0.25) (end 0.504 0.248)
      (stroke (width 0.15) (type solid)) (layer "F.Fab"))
    (fp_line (start 0.504 0.248) (end -0.494 0.248)
      (stroke (width 0.15) (type solid)) (layer "F.Fab"))
    (pad "1" smd roundrect (at -0.48 0) (size 0.59 0.64) (layers "F.Cu" "F.Paste" "F.Mask") (roundrect_rratio 0.25)
      (net 4 "GND") (pintype "passive"))
    (pad "2" smd roundrect (at 0.48 0) (size 0.59 0.64) (layers "F.Cu" "F.Paste" "F.Mask") (roundrect_rratio 0.25)
      (net 34 "Net-(U14-REF)") (pintype "passive"))
  )

  (footprint "antmicro-footprints:QFN-56-1EP_8x8mm_P0.5mm" (layer "F.Cu")
    (at 160 119.2 180)
    (descr "QFN 56 Pin")
    (tags "QFN")
    (property "Author" "Antmicro")
    (property "License" "Apache-2.0")
    (property "MPN" "FT4232H-56Q-REEL")
    (property "Manufacturer" "FTDI Chip")
    (property "Sheetfile" "ftdi-module.kicad_sch")
    (property "Sheetname" "FTDI")
    (property "ki_description" "Interface Bridges, USB to UART, MPSSE, 1.62 V, 1.98 V, VQFN, 56 Pins, -40 °C")
    (property "ki_keywords" "SMT, INTERFACE, IC, CONTROLLER, USB, UART, I2C, SPI, JTAG")
    (attr smd)
    (fp_text reference "U5" (at 4.55 4.45 180) (layer "F.SilkS")
        (effects (font (size 0.7 0.7) (thickness 0.15)) (justify left bottom))
    )
    (fp_text value "FT4232H_VQFN" (at 0 5.32 180) (layer "F.Fab")
        (effects (font (size 0.7 0.7) (thickness 0.15)) (justify left bottom))
    )
    (fp_text user "Author: Antmicro" (at -4.4 8.519 180) (layer "F.Fab") hide
        (effects (font (size 0.7 0.7) (thickness 0.15)) (justify left bottom))
    )
    (fp_text user "${REFERENCE}" (at -4.4 7.32 180) (layer "F.Fab") hide
        (effects (font (size 0.7 0.7) (thickness 0.15)) (justify left bottom))
    )
    (fp_text user "License: Apache-2.0" (at -4.4 9.719 180) (layer "F.Fab") hide
        (effects (font (size 0.7 0.7) (thickness 0.15)) (justify left bottom))
    )
    (fp_line (start -4.111 -3.635) (end -4.111 -4.111)
      (stroke (width 0.15) (type solid)) (layer "F.SilkS"))
    (fp_line (start -4.111 4.11) (end -4.111 3.634)
      (stroke (width 0.15) (type solid)) (layer "F.SilkS"))
    (fp_line (start -3.635 -4.111) (end -4.111 -4.111)
      (stroke (width 0.15) (type solid)) (layer "F.SilkS"))
    (fp_line (start -3.635 4.11) (end -4.111 4.11)
      (stroke (width 0.15) (type solid)) (layer "F.SilkS"))
    (fp_line (start 3.634 -4.111) (end 4.11 -4.111)
      (stroke (width 0.15) (type solid)) (layer "F.SilkS"))
    (fp_line (start 3.634 4.11) (end 4.11 4.11)
      (stroke (width 0.15) (type solid)) (layer "F.SilkS"))
    (fp_line (start 4.11 -4.111) (end 4.11 -3.635)
      (stroke (width 0.15) (type solid)) (layer "F.SilkS"))
    (fp_line (start 4.11 4.11) (end 4.11 3.634)
      (stroke (width 0.15) (type solid)) (layer "F.SilkS"))
    (fp_circle (center -4.35 -3.6) (end -4.3 -3.6)
      (stroke (width 0.15) (type solid)) (fill solid) (layer "F.SilkS"))
    (fp_rect (start 4.4 4.4) (end -4.4 -4.4)
      (stroke (width 0.05) (type solid)) (fill none) (layer "F.CrtYd"))
    (fp_line (start -4 -3) (end -3 -4)
      (stroke (width 0.15) (type solid)) (layer "F.Fab"))
    (fp_rect (start 4 4) (end -4 -4)
      (stroke (width 0.15) (type solid)) (fill none) (layer "F.Fab"))
    (pad "" smd roundrect (at -2.101 -2.101 180) (size 1.13 1.13) (layers "F.Paste") (roundrect_rratio 0.221239))
    (pad "" smd roundrect (at -2.101 -0.7 180) (size 1.13 1.13) (layers "F.Paste") (roundrect_rratio 0.221239))
    (pad "" smd roundrect (at -2.101 0.699 180) (size 1.13 1.13) (layers "F.Paste") (roundrect_rratio 0.221239))
    (pad "" smd roundrect (at -2.101 2.1 180) (size 1.13 1.13) (layers "F.Paste") (roundrect_rratio 0.221239))
    (pad "" smd roundrect (at -0.7 -2.101 180) (size 1.13 1.13) (layers "F.Paste") (roundrect_rratio 0.221239))
    (pad "" smd roundrect (at -0.7 -0.7 180) (size 1.13 1.13) (layers "F.Paste") (roundrect_rratio 0.221239))
    (pad "" smd roundrect (at -0.7 0.699 180) (size 1.13 1.13) (layers "F.Paste") (roundrect_rratio 0.221239))
    (pad "" smd roundrect (at -0.7 2.1 180) (size 1.13 1.13) (layers "F.Paste") (roundrect_rratio 0.221239))
    (pad "" smd roundrect (at 0.699 -2.101 180) (size 1.13 1.13) (layers "F.Paste") (roundrect_rratio 0.221239))
    (pad "" smd roundrect (at 0.699 -0.7 180) (size 1.13 1.13) (layers "F.Paste") (roundrect_rratio 0.221239))
    (pad "" smd roundrect (at 0.699 0.699 180) (size 1.13 1.13) (layers "F.Paste") (roundrect_rratio 0.221239))
    (pad "" smd roundrect (at 0.699 2.1 180) (size 1.13 1.13) (layers "F.Paste") (roundrect_rratio 0.221239))
    (pad "" smd roundrect (at 2.1 -2.101 180) (size 1.13 1.13) (layers "F.Paste") (roundrect_rratio 0.221239))
    (pad "" smd roundrect (at 2.1 -0.7 180) (size 1.13 1.13) (layers "F.Paste") (roundrect_rratio 0.221239))
    (pad "" smd roundrect (at 2.1 0.699 180) (size 1.13 1.13) (layers "F.Paste") (roundrect_rratio 0.221239))
    (pad "" smd roundrect (at 2.1 2.1 180) (size 1.13 1.13) (layers "F.Paste") (roundrect_rratio 0.221239))
    (pad "1" smd roundrect (at -3.938 -3.25 180) (size 0.875 0.3) (layers "F.Cu" "F.Paste" "F.Mask") (roundrect_rratio 0.25)
      (net 121 "unconnected-(U5-EECS-Pad1)") (pinfunction "EECS") (pintype "bidirectional+no_connect"))
    (pad "2" smd roundrect (at -3.938 -2.75 180) (size 0.875 0.3) (layers "F.Cu" "F.Paste" "F.Mask") (roundrect_rratio 0.25)
      (net 7 "1V8_FT") (pinfunction "V_{CORE}") (pintype "power_in"))
    (pad "3" smd roundrect (at -3.938 -2.25 180) (size 0.875 0.3) (layers "F.Cu" "F.Paste" "F.Mask") (roundrect_rratio 0.25)
      (net 5 "/FTDI/OSCI") (pinfunction "OSCI") (pintype "input"))
    (pad "4" smd roundrect (at -3.938 -1.75 180) (size 0.875 0.3) (layers "F.Cu" "F.Paste" "F.Mask") (roundrect_rratio 0.25)
      (net 125 "/FTDI/OSCO") (pinfunction "OSCO") (pintype "output"))
    (pad "5" smd roundrect (at -3.938 -1.25 180) (size 0.875 0.3) (layers "F.Cu" "F.Paste" "F.Mask") (roundrect_rratio 0.25)
      (net 8 "/FTDI/FTDI_VPHY") (pinfunction "V_{PHY}") (pintype "power_in"))
    (pad "6" smd roundrect (at -3.938 -0.75 180) (size 0.875 0.3) (layers "F.Cu" "F.Paste" "F.Mask") (roundrect_rratio 0.25)
      (net 104 "Net-(U5-REF)") (pinfunction "REF") (pintype "input"))
    (pad "7" smd roundrect (at -3.938 -0.25 180) (size 0.875 0.3) (layers "F.Cu" "F.Paste" "F.Mask") (roundrect_rratio 0.25)
      (net 15 "/FTDI/USB_D-") (pinfunction "D-") (pintype "bidirectional"))
    (pad "8" smd roundrect (at -3.938 0.249 180) (size 0.875 0.3) (layers "F.Cu" "F.Paste" "F.Mask") (roundrect_rratio 0.25)
      (net 14 "/FTDI/USB_D+") (pinfunction "D+") (pintype "bidirectional"))
    (pad "9" smd roundrect (at -3.938 0.749 180) (size 0.875 0.3) (layers "F.Cu" "F.Paste" "F.Mask") (roundrect_rratio 0.25)
      (net 6 "/FTDI/FTDI_VPLL") (pinfunction "V_{PLL}") (pintype "power_in"))
    (pad "10" smd roundrect (at -3.938 1.249 180) (size 0.875 0.3) (layers "F.Cu" "F.Paste" "F.Mask") (roundrect_rratio 0.25)
      (net 77 "GNDD") (pinfunction "TEST") (pintype "input"))
    (pad "11" smd roundrect (at -3.938 1.749 180) (size 0.875 0.3) (layers "F.Cu" "F.Paste" "F.Mask") (roundrect_rratio 0.25)
      (net 31 "/FTDI/FTDI_RST") (pinfunction "~{RESET}") (pintype "input"))
    (pad "12" smd roundrect (at -3.938 2.249 180) (size 0.875 0.3) (layers "F.Cu" "F.Paste" "F.Mask") (roundrect_rratio 0.25)
      (net 81 "SCL_FTDI") (pinfunction "ADBUS0") (pintype "bidirectional"))
    (pad "13" smd roundrect (at -3.938 2.749 180) (size 0.875 0.3) (layers "F.Cu" "F.Paste" "F.Mask") (roundrect_rratio 0.25)
      (net 9 "/FTDI/SDA_FTDI_2") (pinfunction "ADBUS1") (pintype "bidirectional"))
    (pad "14" smd roundrect (at -3.938 3.249 180) (size 0.875 0.3) (layers "F.Cu" "F.Paste" "F.Mask") (roundrect_rratio 0.25)
      (net 80 "SDA_FTDI") (pinfunction "ADBUS2") (pintype "bidirectional"))
    (pad "15" smd roundrect (at -3.25 3.937 270) (size 0.875 0.3) (layers "F.Cu" "F.Paste" "F.Mask") (roundrect_rratio 0.25)
      (net 33 "/FTDI/WP") (pinfunction "ADBUS3") (pintype "bidirectional"))
    (pad "16" smd roundrect (at -2.75 3.937 270) (size 0.875 0.3) (layers "F.Cu" "F.Paste" "F.Mask") (roundrect_rratio 0.25)
      (net 76 "VCC3V3_USB") (pinfunction "V_{CCIO}") (pintype "power_in"))
    (pad "17" smd roundrect (at -2.25 3.937 270) (size 0.875 0.3) (layers "F.Cu" "F.Paste" "F.Mask") (roundrect_rratio 0.25)
      (net 122 "unconnected-(U5-ADBUS4-Pad17)") (pinfunction "ADBUS4") (pintype "bidirectional+no_connect"))
    (pad "18" smd roundrect (at -1.75 3.937 270) (size 0.875 0.3) (layers "F.Cu" "F.Paste" "F.Mask") (roundrect_rratio 0.25)
      (net 123 "unconnected-(U5-ADBUS5-Pad18)") (pinfunction "ADBUS5") (pintype "bidirectional+no_connect"))
    (pad "19" smd roundrect (at -1.25 3.937 270) (size 0.875 0.3) (layers "F.Cu" "F.Paste" "F.Mask") (roundrect_rratio 0.25)
      (net 124 "unconnected-(U5-ADBUS6-Pad19)") (pinfunction "ADBUS6") (pintype "bidirectional+no_connect"))
    (pad "20" smd roundrect (at -0.75 3.937 270) (size 0.875 0.3) (layers "F.Cu" "F.Paste" "F.Mask") (roundrect_rratio 0.25)
      (net 126 "unconnected-(U5-ADBUS7-Pad20)") (pinfunction "ADBUS7") (pintype "bidirectional+no_connect"))
    (pad "21" smd roundrect (at -0.25 3.937 270) (size 0.875 0.3) (layers "F.Cu" "F.Paste" "F.Mask") (roundrect_rratio 0.25)
      (net 77 "GNDD") (pinfunction "GND") (pintype "power_in"))
    (pad "22" smd roundrect (at 0.249 3.937 270) (size 0.875 0.3) (layers "F.Cu" "F.Paste" "F.Mask") (roundrect_rratio 0.25)
      (net 127 "unconnected-(U5-BDBUS0-Pad22)") (pinfunction "BDBUS0") (pintype "bidirectional+no_connect"))
    (pad "23" smd roundrect (at 0.749 3.937 270) (size 0.875 0.3) (layers "F.Cu" "F.Paste" "F.Mask") (roundrect_rratio 0.25)
      (net 116 "Net-(U5-BDBUS1)") (pinfunction "BDBUS1") (pintype "bidirectional"))
    (pad "24" smd roundrect (at 1.249 3.937 270) (size 0.875 0.3) (layers "F.Cu" "F.Paste" "F.Mask") (roundrect_rratio 0.25)
      (net 128 "unconnected-(U5-BDBUS2-Pad24)") (pinfunction "BDBUS2") (pintype "bidirectional+no_connect"))
    (pad "25" smd roundrect (at 1.749 3.937 270) (size 0.875 0.3) (layers "F.Cu" "F.Paste" "F.Mask") (roundrect_rratio 0.25)
      (net 129 "unconnected-(U5-BDBUS3-Pad25)") (pinfunction "BDBUS3") (pintype "bidirectional+no_connect"))
    (pad "26" smd roundrect (at 2.249 3.937 270) (size 0.875 0.3) (layers "F.Cu" "F.Paste" "F.Mask") (roundrect_rratio 0.25)
      (net 130 "unconnected-(U5-BDBUS4-Pad26)") (pinfunction "BDBUS4") (pintype "bidirectional+no_connect"))
    (pad "27" smd roundrect (at 2.749 3.937 270) (size 0.875 0.3) (layers "F.Cu" "F.Paste" "F.Mask") (roundrect_rratio 0.25)
      (net 131 "unconnected-(U5-BDBUS5-Pad27)") (pinfunction "BDBUS5") (pintype "bidirectional+no_connect"))
    (pad "28" smd roundrect (at 3.249 3.937 270) (size 0.875 0.3) (layers "F.Cu" "F.Paste" "F.Mask") (roundrect_rratio 0.25)
      (net 132 "unconnected-(U5-BDBUS6-Pad28)") (pinfunction "BDBUS6") (pintype "bidirectional+no_connect"))
    (pad "29" smd roundrect (at 3.937 3.249 180) (size 0.875 0.3) (layers "F.Cu" "F.Paste" "F.Mask") (roundrect_rratio 0.25)
      (net 133 "unconnected-(U5-BDBUS7-Pad29)") (pinfunction "BDBUS7") (pintype "bidirectional+no_connect"))
    (pad "30" smd roundrect (at 3.937 2.749 180) (size 0.875 0.3) (layers "F.Cu" "F.Paste" "F.Mask") (roundrect_rratio 0.25)
      (net 134 "unconnected-(U5-~{SUSPEND}-Pad30)") (pinfunction "~{SUSPEND}") (pintype "output+no_connect"))
    (pad "31" smd roundrect (at 3.937 2.249 180) (size 0.875 0.3) (layers "F.Cu" "F.Paste" "F.Mask") (roundrect_rratio 0.25)
      (net 7 "1V8_FT") (pinfunction "V_{CORE}") (pintype "passive"))
    (pad "32" smd roundrect (at 3.937 1.749 180) (size 0.875 0.3) (layers "F.Cu" "F.Paste" "F.Mask") (roundrect_rratio 0.25)
      (net 135 "unconnected-(U5-CDBUS0-Pad32)") (pinfunction "CDBUS0") (pintype "bidirectional+no_connect"))
    (pad "33" smd roundrect (at 3.937 1.249 180) (size 0.875 0.3) (layers "F.Cu" "F.Paste" "F.Mask") (roundrect_rratio 0.25)
      (net 138 "unconnected-(U5-CDBUS1-Pad33)") (pinfunction "CDBUS1") (pintype "bidirectional+no_connect"))
    (pad "34" smd roundrect (at 3.937 0.749 180) (size 0.875 0.3) (layers "F.Cu" "F.Paste" "F.Mask") (roundrect_rratio 0.25)
      (net 139 "unconnected-(U5-CDBUS2-Pad34)") (pinfunction "CDBUS2") (pintype "bidirectional+no_connect"))
    (pad "35" smd roundrect (at 3.937 0.249 180) (size 0.875 0.3) (layers "F.Cu" "F.Paste" "F.Mask") (roundrect_rratio 0.25)
      (net 140 "unconnected-(U5-CDBUS3-Pad35)") (pinfunction "CDBUS3") (pintype "bidirectional+no_connect"))
    (pad "36" smd roundrect (at 3.937 -0.25 180) (size 0.875 0.3) (layers "F.Cu" "F.Paste" "F.Mask") (roundrect_rratio 0.25)
      (net 76 "VCC3V3_USB") (pinfunction "V_{CCIO}") (pintype "passive"))
    (pad "37" smd roundrect (at 3.937 -0.75 180) (size 0.875 0.3) (layers "F.Cu" "F.Paste" "F.Mask") (roundrect_rratio 0.25)
      (net 141 "unconnected-(U5-CDBUS4-Pad37)") (pinfunction "CDBUS4") (pintype "bidirectional+no_connect"))
    (pad "38" smd roundrect (at 3.937 -1.25 180) (size 0.875 0.3) (layers "F.Cu" "F.Paste" "F.Mask") (roundrect_rratio 0.25)
      (net 142 "unconnected-(U5-CDBUS5-Pad38)") (pinfunction "CDBUS5") (pintype "bidirectional+no_connect"))
    (pad "39" smd roundrect (at 3.937 -1.75 180) (size 0.875 0.3) (layers "F.Cu" "F.Paste" "F.Mask") (roundrect_rratio 0.25)
      (net 143 "unconnected-(U5-CDBUS6-Pad39)") (pinfunction "CDBUS6") (pintype "bidirectional+no_connect"))
    (pad "40" smd roundrect (at 3.937 -2.25 180) (size 0.875 0.3) (layers "F.Cu" "F.Paste" "F.Mask") (roundrect_rratio 0.25)
      (net 146 "unconnected-(U5-CDBUS7-Pad40)") (pinfunction "CDBUS7") (pintype "bidirectional+no_connect"))
    (pad "41" smd roundrect (at 3.937 -2.75 180) (size 0.875 0.3) (layers "F.Cu" "F.Paste" "F.Mask") (roundrect_rratio 0.25)
      (net 77 "GNDD") (pinfunction "GND") (pintype "passive"))
    (pad "42" smd roundrect (at 3.937 -3.25 180) (size 0.875 0.3) (layers "F.Cu" "F.Paste" "F.Mask") (roundrect_rratio 0.25)
      (net 148 "unconnected-(U5-DDBUS0-Pad42)") (pinfunction "DDBUS0") (pintype "bidirectional+no_connect"))
    (pad "43" smd roundrect (at 3.249 -3.938 270) (size 0.875 0.3) (layers "F.Cu" "F.Paste" "F.Mask") (roundrect_rratio 0.25)
      (net 7 "1V8_FT") (pinfunction "V_{REGOUT}") (pintype "power_out"))
    (pad "44" smd roundrect (at 2.749 -3.938 270) (size 0.875 0.3) (layers "F.Cu" "F.Paste" "F.Mask") (roundrect_rratio 0.25)
      (net 76 "VCC3V3_USB") (pinfunction "V_{REGIN}") (pintype "power_in"))
    (pad "45" smd roundrect (at 2.249 -3.938 270) (size 0.875 0.3) (layers "F.Cu" "F.Paste" "F.Mask") (roundrect_rratio 0.25)
      (net 77 "GNDD") (pinfunction "GND") (pintype "passive"))
    (pad "46" smd roundrect (at 1.749 -3.938 270) (size 0.875 0.3) (layers "F.Cu" "F.Paste" "F.Mask") (roundrect_rratio 0.25)
      (net 149 "unconnected-(U5-DDBUS1-Pad46)") (pinfunction "DDBUS1") (pintype "bidirectional+no_connect"))
    (pad "47" smd roundrect (at 1.249 -3.938 270) (size 0.875 0.3) (layers "F.Cu" "F.Paste" "F.Mask") (roundrect_rratio 0.25)
      (net 150 "unconnected-(U5-DDBUS2-Pad47)") (pinfunction "DDBUS2") (pintype "bidirectional+no_connect"))
    (pad "48" smd roundrect (at 0.749 -3.938 270) (size 0.875 0.3) (layers "F.Cu" "F.Paste" "F.Mask") (roundrect_rratio 0.25)
      (net 151 "unconnected-(U5-DDBUS3-Pad48)") (pinfunction "DDBUS3") (pintype "bidirectional+no_connect"))
    (pad "49" smd roundrect (at 0.249 -3.938 270) (size 0.875 0.3) (layers "F.Cu" "F.Paste" "F.Mask") (roundrect_rratio 0.25)
      (net 152 "unconnected-(U5-DDBUS4-Pad49)") (pinfunction "DDBUS4") (pintype "bidirectional+no_connect"))
    (pad "50" smd roundrect (at -0.25 -3.938 270) (size 0.875 0.3) (layers "F.Cu" "F.Paste" "F.Mask") (roundrect_rratio 0.25)
      (net 76 "VCC3V3_USB") (pinfunction "V_{CCIO}") (pintype "passive"))
    (pad "51" smd roundrect (at -0.75 -3.938 270) (size 0.875 0.3) (layers "F.Cu" "F.Paste" "F.Mask") (roundrect_rratio 0.25)
      (net 153 "unconnected-(U5-DDBUS5-Pad51)") (pinfunction "DDBUS5") (pintype "bidirectional+no_connect"))
    (pad "52" smd roundrect (at -1.25 -3.938 270) (size 0.875 0.3) (layers "F.Cu" "F.Paste" "F.Mask") (roundrect_rratio 0.25)
      (net 154 "unconnected-(U5-DDBUS6-Pad52)") (pinfunction "DDBUS6") (pintype "bidirectional+no_connect"))
    (pad "53" smd roundrect (at -1.75 -3.938 270) (size 0.875 0.3) (layers "F.Cu" "F.Paste" "F.Mask") (roundrect_rratio 0.25)
      (net 155 "unconnected-(U5-DDBUS7-Pad53)") (pinfunction "DDBUS7") (pintype "bidirectional+no_connect"))
    (pad "54" smd roundrect (at -2.25 -3.938 270) (size 0.875 0.3) (layers "F.Cu" "F.Paste" "F.Mask") (roundrect_rratio 0.25)
      (net 156 "unconnected-(U5-~{PWR_{EN}}-Pad54)") (pinfunction "~{PWR_{EN}}") (pintype "output+no_connect"))
    (pad "55" smd roundrect (at -2.75 -3.938 270) (size 0.875 0.3) (layers "F.Cu" "F.Paste" "F.Mask") (roundrect_rratio 0.25)
      (net 157 "unconnected-(U5-EEDATA-Pad55)") (pinfunction "EEDATA") (pintype "bidirectional+no_connect"))
    (pad "56" smd roundrect (at -3.25 -3.938 270) (size 0.875 0.3) (layers "F.Cu" "F.Paste" "F.Mask") (roundrect_rratio 0.25)
      (net 158 "unconnected-(U5-EECLK-Pad56)") (pinfunction "EECLK") (pintype "output+no_connect"))
    (pad "57" smd rect (at 0 0 180) (size 5.9 5.9) (layers "F.Cu" "F.Mask")
      (net 77 "GNDD") (pinfunction "GND") (pintype "passive"))
  )

  (footprint "antmicro-footprints:D_SOD-323" (layer "F.Cu")
    (at 182.1 91.35 -90)
    (property "Author" "Antmicro")
    (property "License" "Apache-2.0")
    (property "MPN" "BZT52B15SV-T")
    (property "Manufacturer" "Rectron")
    (property "Sheetfile" "power-switch.kicad_sch")
    (property "Sheetname" "Power switch 5")
    (property "ki_description" "Zener Single Diode, AEC-Q101, 15 V, 500 mW, SOD-323, 2 Pins, 150 °C, Surface Mount")
    (property "ki_keywords" "SMT, DIODE, SEMICONDUCTOR, ZENER")
    (attr smd)
    (fp_text reference "D19" (at -0.85 -1.15) (layer "F.SilkS")
        (effects (font (size 0.7 0.7) (thickness 0.15)) (justify left bottom))
    )
    (fp_text value "BZT52B15SV-T" (at 0 1.841 -90) (layer "F.Fab")
        (effects (font (size 0.7 0.7) (thickness 0.15)) (justify left bottom))
    )
    (fp_text user "License: Apache-2.0" (at -1.4 3.841 -90) (layer "F.Fab") hide
        (effects (font (size 0.7 0.7) (thickness 0.15)) (justify left bottom))
    )
    (fp_text user "${REFERENCE}" (at -1.4 5.041 -90) (layer "F.Fab") hide
        (effects (font (size 0.7 0.7) (thickness 0.15)) (justify left bottom))
    )
    (fp_text user "Author: Antmicro" (at -1.4 6.241 -90) (layer "F.Fab") hide
        (effects (font (size 0.7 0.7) (thickness 0.15)) (justify left bottom))
    )
    (fp_line (start -0.949 -0.749) (end -0.949 -0.499)
      (stroke (width 0.15) (type solid)) (layer "F.SilkS"))
    (fp_line (start -0.949 0.501) (end -0.949 0.751)
      (stroke (width 0.15) (type solid)) (layer "F.SilkS"))
    (fp_line (start -0.6 -0.499) (end -0.6 0.499)
      (stroke (width 0.15) (type solid)) (layer "F.SilkS"))
    (fp_line (start -0.577 -0.749) (end -0.949 -0.749)
      (stroke (width 0.15) (type solid)) (layer "F.SilkS"))
    (fp_line (start -0.577 0.751) (end -0.949 0.751)
      (stroke (width 0.15) (type solid)) (layer "F.SilkS"))
    (fp_line (start 0.625 -0.736) (end 0.949 -0.736)
      (stroke (width 0.15) (type solid)) (layer "F.SilkS"))
    (fp_line (start 0.949 -0.736) (end 0.949 -0.499)
      (stroke (width 0.15) (type solid)) (layer "F.SilkS"))
    (fp_line (start 0.95 0.501) (end 0.95 0.751)
      (stroke (width 0.15) (type solid)) (layer "F.SilkS"))
    (fp_line (start 0.95 0.751) (end 0.649 0.751)
      (stroke (width 0.15) (type solid)) (layer "F.SilkS"))
    (fp_rect (start -1.6 -0.925) (end 1.6 0.925)
      (stroke (width 0.05) (type solid)) (fill none) (layer "F.CrtYd"))
    (fp_line (start -0.902 0.699) (end -0.902 -0.699)
      (stroke (width 0.15) (type solid)) (layer "F.Fab"))
    (fp_line (start -0.902 0.699) (end 0.9 0.699)
      (stroke (width 0.15) (type solid)) (layer "F.Fab"))
    (fp_line (start 0.9 -0.699) (end -0.902 -0.699)
      (stroke (width 0.15) (type solid)) (layer "F.Fab"))
    (fp_line (start 0.9 -0.699) (end 0.9 0.699)
      (stroke (width 0.15) (type solid)) (layer "F.Fab"))
    (pad "1" smd rect (at -1.125 0.001 270) (size 0.8 0.8) (layers "F.Cu" "F.Paste" "F.Mask")
      (net 11 "VCC12V0") (pinfunction "C") (pintype "passive"))
    (pad "2" smd rect (at 1.124 0.001 270) (size 0.8 0.8) (layers "F.Cu" "F.Paste" "F.Mask")
      (net 87 "Net-(D19-A)") (pinfunction "A") (pintype "passive"))
  )

  (footprint "antmicro-footprints:USB-C_Receptacle_GCT_USB4145-03-0070-C" (layer "F.Cu")
    (at 186.99 113.55 90)
    (property "Author" "Antmicro")
    (property "License" "Apache-2.0")
    (property "MPN" "USB4145-03-0070-C")
    (property "Manufacturer" "GCT")
    (property "Sheetfile" "ftdi-module.kicad_sch")
    (property "Sheetname" "FTDI")
    (property "ki_description" "USB-C (USB TYPE-C) USB 2.0 Receptacle Connector 24 (16+8 Dummy) Postion  Surface Mount, Vertical")
    (property "ki_keywords" "USB, CONNECTOR, SMT, VERTICAL")
    (attr smd)
    (fp_text reference "U1" (at 0.85 0.81 90) (layer "F.SilkS")
        (effects (font (size 0.7 0.7) (thickness 0.15)) (justify left bottom))
    )
    (fp_text value "USB-C_GCT_USB4145-03-0070-C" (at 11.365 3.465 90) (layer "F.Fab")
        (effects (font (size 0.7 0.7) (thickness 0.15)) (justify left bottom))
    )
    (fp_text user "${REFERENCE}" (at -4.72 6.665 90) (layer "F.Fab") hide
        (effects (font (size 0.7 0.7) (thickness 0.15)) (justify left bottom))
    )
    (fp_text user "Author: Antmicro" (at -4.72 7.865 90) (layer "F.Fab") hide
        (effects (font (size 0.7 0.7) (thickness 0.15)) (justify left bottom))
    )
    (fp_text user "License: Apache-2.0" (at -4.72 5.465 90) (layer "F.Fab") hide
        (effects (font (size 0.7 0.7) (thickness 0.15)) (justify left bottom))
    )
    (fp_line (start -2.28 -1.47) (end -1.72 -1.47)
      (stroke (width 0.15) (type solid)) (layer "F.SilkS"))
    (fp_line (start -2.28 1.69) (end -1.72 1.69)
      (stroke (width 0.15) (type solid)) (layer "F.SilkS"))
    (fp_line (start 1.72 -1.47) (end 2.28 -1.47)
      (stroke (width 0.15) (type solid)) (layer "F.SilkS"))
    (fp_line (start 1.72 1.69) (end 2.28 1.69)
      (stroke (width 0.15) (type solid)) (layer "F.SilkS"))
    (fp_circle (center -2.75 -2.39) (end -2.7 -2.39)
      (stroke (width 0.15) (type solid)) (fill solid) (layer "F.SilkS"))
    (fp_rect (start -4.9 -2.1) (end 4.9 2.1)
      (stroke (width 0.05) (type solid)) (fill none) (layer "F.CrtYd"))
    (fp_rect (start -4.5 -1.9) (end 4.5 1.9)
      (stroke (width 0.15) (type solid)) (fill none) (layer "F.Fab"))
    (pad "" np_thru_hole circle (at -4 0.11 90) (size 0.66 0.66) (drill 0.66) (layers "*.Cu" "*.Mask"))
    (pad "" np_thru_hole circle (at 4 0.11 90) (size 0.66 0.66) (drill 0.66) (layers "*.Cu" "*.Mask"))
    (pad "A1" smd rect (at -2.75 -1.375 90) (size 0.3 1.15) (layers "F.Cu" "F.Paste" "F.Mask")
      (net 77 "GNDD") (pinfunction "GND") (pintype "power_in"))
    (pad "A4" smd rect (at -1.25 -1.375 90) (size 0.3 1.15) (layers "F.Cu" "F.Paste" "F.Mask")
      (net 10 "VBUS") (pinfunction "VBUS") (pintype "passive"))
    (pad "A5" smd rect (at -0.75 -1.375 90) (size 0.3 1.15) (layers "F.Cu" "F.Paste" "F.Mask")
      (net 113 "Net-(U1-CC_{1})") (pinfunction "CC_{1}") (pintype "bidirectional"))
    (pad "A6" smd rect (at -0.25 -1.375 90) (size 0.3 1.15) (layers "F.Cu" "F.Paste" "F.Mask")
      (net 14 "/FTDI/USB_D+") (pinfunction "D_{A}+") (pintype "bidirectional"))
    (pad "A7" smd rect (at 0.25 -1.375 90) (size 0.3 1.15) (layers "F.Cu" "F.Paste" "F.Mask")
      (net 15 "/FTDI/USB_D-") (pinfunction "D_{A}-") (pintype "bidirectional"))
    (pad "A8" smd rect (at 0.75 -1.375 90) (size 0.3 1.15) (layers "F.Cu" "F.Paste" "F.Mask")
      (net 117 "Net-(U1-SBU_{1})") (pinfunction "SBU_{1}") (pintype "bidirectional"))
    (pad "A9" smd rect (at 1.25 -1.375 90) (size 0.3 1.15) (layers "F.Cu" "F.Paste" "F.Mask")
      (net 10 "VBUS") (pinfunction "VBUS") (pintype "passive"))
    (pad "A12" smd rect (at 2.75 -1.375 90) (size 0.3 1.15) (layers "F.Cu" "F.Paste" "F.Mask")
      (net 77 "GNDD") (pinfunction "GND") (pintype "passive"))
    (pad "B1" smd rect (at 2.75 1.595 90) (size 0.3 1.15) (layers "F.Cu" "F.Paste" "F.Mask")
      (net 77 "GNDD") (pinfunction "GND") (pintype "passive"))
    (pad "B4" smd rect (at 1.25 1.595 90) (size 0.3 1.15) (layers "F.Cu" "F.Paste" "F.Mask")
      (net 10 "VBUS") (pinfunction "VBUS") (pintype "passive"))
    (pad "B5" smd rect (at 0.75 1.595 90) (size 0.3 1.15) (layers "F.Cu" "F.Paste" "F.Mask")
      (net 114 "Net-(U1-CC_{2})") (pinfunction "CC_{2}") (pintype "bidirectional"))
    (pad "B6" smd rect (at 0.25 1.595 90) (size 0.3 1.15) (layers "F.Cu" "F.Paste" "F.Mask")
      (net 14 "/FTDI/USB_D+") (pinfunction "D_{B}+") (pintype "bidirectional"))
    (pad "B7" smd rect (at -0.25 1.595 90) (size 0.3 1.15) (layers "F.Cu" "F.Paste" "F.Mask")
      (net 15 "/FTDI/USB_D-") (pinfunction "D_{B}-") (pintype "bidirectional"))
    (pad "B8" smd rect (at -0.75 1.595 90) (size 0.3 1.15) (layers "F.Cu" "F.Paste" "F.Mask")
      (net 118 "Net-(U1-SBU_{2})") (pinfunction "SBU_{2}") (pintype "bidirectional"))
    (pad "B9" smd rect (at -1.25 1.595 90) (size 0.3 1.15) (layers "F.Cu" "F.Paste" "F.Mask")
      (net 10 "VBUS") (pinfunction "VBUS") (pintype "passive"))
    (pad "B12" smd rect (at -2.75 1.595 90) (size 0.3 1.15) (layers "F.Cu" "F.Paste" "F.Mask")
      (net 77 "GNDD") (pinfunction "GND") (pintype "passive"))
    (pad "SH" thru_hole oval (at -4 -1.32 90) (size 1.6 1.1) (drill oval 1.1 0.6) (layers "*.Cu" "*.Mask")
      (net 136 "Net-(FB3-Pad1)") (pinfunction "SH") (pintype "passive"))
    (pad "SH" thru_hole oval (at -4 1.54 90) (size 1.6 1.1) (drill oval 1.1 0.6) (layers "*.Cu" "*.Mask")
      (net 136 "Net-(FB3-Pad1)") (pinfunction "SH") (pintype "passive"))
    (pad "SH" thru_hole oval (at 4 -1.32 90) (size 1.6 1.1) (drill oval 1.1 0.6) (layers "*.Cu" "*.Mask")
      (net 136 "Net-(FB3-Pad1)") (pinfunction "SH") (pintype "passive"))
    (pad "SH" thru_hole oval (at 4 1.54 90) (size 1.6 1.1) (drill oval 1.1 0.6) (layers "*.Cu" "*.Mask")
      (net 136 "Net-(FB3-Pad1)") (pinfunction "SH") (pintype "passive"))
  )

  (footprint "antmicro-footprints:R_0402_1005Metric" (layer "F.Cu")
    (at 169.8 109.975 180)
    (descr "Resistor SMD 0402")
    (tags "resistor SMD 0402")
    (property "Author" "Antmicro")
    (property "License" "Apache-2.0")
    (property "MPN" "CR0402-FX-2200GLF")
    (property "Manufacturer" "Bourns")
    (property "Sheetfile" "ftdi-module.kicad_sch")
    (property "Sheetname" "FTDI")
    (property "Tolerance" "1%")
    (property "Val" "220R")
    (property "ki_description" "SMD Chip Resistor, 220 ohm, ± 1%, 62.5 mW, 0402 [1005 Metric], Thick Film, General Purpose")
    (property "ki_keywords" "0402, SMT, RESISTOR, PASSIVE")
    (attr smd)
    (fp_text reference "R74" (at -1.2 -1.35) (layer "F.SilkS")
        (effects (font (size 0.7 0.7) (thickness 0.15)) (justify right bottom))
    )
    (fp_text value "R_220R_0402" (at -1.011843 1.772047) (layer "F.Fab")
        (effects (font (size 0.7 0.7) (thickness 0.15)) (justify right bottom))
    )
    (fp_text user "License: Apache-2.0" (at -0.95 5.169) (layer "F.Fab") hide
        (effects (font (size 0.7 0.7) (thickness 0.15)) (justify right bottom))
    )
    (fp_text user "Author: Antmicro" (at -0.95 4.169) (layer "F.Fab") hide
        (effects (font (size 0.7 0.7) (thickness 0.15)) (justify right bottom))
    )
    (fp_text user "${REFERENCE}" (at -0.95 3.168) (layer "F.Fab") hide
        (effects (font (size 0.7 0.7) (thickness 0.15)) (justify right bottom))
    )
    (fp_rect (start -0.925 -0.47) (end 0.925 0.47)
      (stroke (width 0.05) (type default)) (fill none) (layer "F.CrtYd"))
    (fp_rect (start -0.5 -0.25) (end 0.5 0.25)
      (stroke (width 0.15) (type solid)) (fill none) (layer "F.Fab"))
    (pad "1" smd roundrect (at -0.48 0 180) (size 0.59 0.64) (layers "F.Cu" "F.Paste" "F.Mask") (roundrect_rratio 0.25)
      (net 77 "GNDD") (pintype "passive"))
    (pad "2" smd roundrect (at 0.48 0 180) (size 0.59 0.64) (layers "F.Cu" "F.Paste" "F.Mask") (roundrect_rratio 0.25)
      (net 147 "Net-(R74-Pad2)") (pintype "passive"))
  )

  (footprint "antmicro-footprints:LED_0603_1608Metric_G" (layer "F.Cu")
    (at 128.4 53.85)
    (descr "LED SMD 0603 Green")
    (tags "LED SMD 0603 Green")
    (property "Author" "Antmicro")
    (property "Color" "Green")
    (property "License" "Apache-2.0")
    (property "MPN" "LG L29K-G2J1-24-Z")
    (property "Manufacturer" "OSRAM")
    (property "Sheetfile" "d1600e-psu-breakout-board.kicad_sch")
    (property "Sheetname" "")
    (property "ki_description" "LED, Green, SMD, 0603, 20 mA, 1.7 V, 570 nm")
    (property "ki_keywords" "SMT, DIODE, SEMICONDUCTOR, LED")
    (zone_connect 1)
    (attr smd)
    (fp_text reference "D4" (at -0.8 1.65) (layer "F.SilkS")
        (effects (font (size 0.7 0.7) (thickness 0.15)) (justify left bottom))
    )
    (fp_text value "LED_G_0603_LG_L29K-G2J1-24-Z" (at -0.001 1.599) (layer "F.Fab")
        (effects (font (size 0.7 0.7) (thickness 0.15)) (justify left bottom))
    )
    (fp_text user "License: Apache-2.0" (at -1.4224 3.599) (layer "F.Fab") hide
        (effects (font (size 0.7 0.7) (thickness 0.15)) (justify left bottom))
    )
    (fp_text user "${REFERENCE}" (at -1.4224 5.999) (layer "F.Fab") hide
        (effects (font (size 0.7 0.7) (thickness 0.15)) (justify left bottom))
    )
    (fp_text user "Author: Antmicro" (at -1.4224 4.799) (layer "F.Fab") hide
        (effects (font (size 0.7 0.7) (thickness 0.15)) (justify left bottom))
    )
    (fp_line (start -1.18 -0.319) (end -1.18 0.321)
      (stroke (width 0.15) (type solid)) (layer "F.SilkS"))
    (fp_line (start -0.094672 0.001008) (end -0.24 0.001008)
      (stroke (width 0.1) (type solid)) (layer "F.SilkS"))
    (fp_line (start -0.094672 0.001008) (end 0.105328 -0.198992)
      (stroke (width 0.1) (type solid)) (layer "F.SilkS"))
    (fp_line (start -0.094672 0.201008) (end -0.094672 -0.198992)
      (stroke (width 0.1) (type solid)) (layer "F.SilkS"))
    (fp_line (start 0.105328 0.001008) (end 0.24 0.001)
      (stroke (width 0.1) (type solid)) (layer "F.SilkS"))
    (fp_line (start 0.105328 0.201008) (end -0.094672 0.001008)
      (stroke (width 0.1) (type solid)) (layer "F.SilkS"))
    (fp_line (start 0.105328 0.201008) (end 0.105328 -0.198992)
      (stroke (width 0.1) (type solid)) (layer "F.SilkS"))
    (fp_line (start 0.22 -0.35) (end -0.22 -0.35)
      (stroke (width 0.15) (type solid)) (layer "F.SilkS"))
    (fp_line (start 0.22 0.35) (end -0.22 0.35)
      (stroke (width 0.15) (type solid)) (layer "F.SilkS"))
    (fp_rect (start 1.25 0.65) (end -1.25 -0.65)
      (stroke (width 0.05) (type solid)) (fill none) (layer "F.CrtYd"))
    (fp_line (start -0.199 -0.202) (end -0.199 0.1)
      (stroke (width 0.15) (type solid)) (layer "F.Fab"))
    (fp_line (start -0.199 0) (end -0.597 0)
      (stroke (width 0.15) (type solid)) (layer "F.Fab"))
    (fp_line (start -0.199 0.2) (end -0.199 0.1)
      (stroke (width 0.15) (type solid)) (layer "F.Fab"))
    (fp_line (start -0.101 0) (end 0.201 0.2)
      (stroke (width 0.15) (type solid)) (layer "F.Fab"))
    (fp_line (start 0.201 -0.202) (end -0.101 0)
      (stroke (width 0.15) (type solid)) (layer "F.Fab"))
    (fp_line (start 0.201 0) (end 0.201 -0.202)
      (stroke (width 0.15) (type solid)) (layer "F.Fab"))
    (fp_line (start 0.201 0.2) (end 0.201 0)
      (stroke (width 0.15) (type solid)) (layer "F.Fab"))
    (fp_line (start 0.599 0) (end 0.201 0)
      (stroke (width 0.15) (type solid)) (layer "F.Fab"))
    (fp_rect (start 0.848 0.4) (end -0.85 -0.402)
      (stroke (width 0.15) (type solid)) (fill none) (layer "F.Fab"))
    (pad "1" smd roundrect (at -0.7 0 180) (size 0.8 1) (layers "F.Cu" "F.Paste" "F.Mask") (roundrect_rratio 0.2)
      (net 4 "GND") (pinfunction "C") (pintype "passive"))
    (pad "2" smd roundrect (at 0.7 0 180) (size 0.8 1) (layers "F.Cu" "F.Paste" "F.Mask") (roundrect_rratio 0.2)
      (net 37 "Net-(D4-A)") (pinfunction "A") (pintype "passive"))
  )

  (footprint "antmicro-footprints:R_0402_1005Metric" (layer "F.Cu")
    (at 111.55 89.4 180)
    (descr "Resistor SMD 0402")
    (tags "resistor SMD 0402")
    (property "Author" "Antmicro")
    (property "DNP" "DNP")
    (property "License" "Apache-2.0")
    (property "MPN" "CR0402-FX-1002GLF")
    (property "Manufacturer" "Bourns")
    (property "Sheetfile" "power-switch.kicad_sch")
    (property "Sheetname" "Power switch 1")
    (property "Tolerance" "1%")
    (property "Val" "10k")
    (property "dnp" "")
    (property "exclude_from_bom" "")
    (property "ki_description" "SMD Chip Resistor, 10 kohm, ± 1%, 62.5 mW, 0402 [1005 Metric], Thick Film, General Purpose")
    (property "ki_keywords" "0402, SMT, RESISTOR, PASSIVE")
    (attr smd exclude_from_bom)
    (fp_text reference "R46" (at 1.85 -1.4 180) (layer "F.SilkS")
        (effects (font (size 0.7 0.7) (thickness 0.15)) (justify left bottom))
    )
    (fp_text value "R_10k_0402" (at -1.011843 1.772047 180) (layer "F.Fab")
        (effects (font (size 0.7 0.7) (thickness 0.15)) (justify left bottom))
    )
    (fp_text user "${REFERENCE}" (at -0.95 3.168 180) (layer "F.Fab") hide
        (effects (font (size 0.7 0.7) (thickness 0.15)) (justify left bottom))
    )
    (fp_text user "Author: Antmicro" (at -0.95 4.169 180) (layer "F.Fab") hide
        (effects (font (size 0.7 0.7) (thickness 0.15)) (justify left bottom))
    )
    (fp_text user "License: Apache-2.0" (at -0.95 5.169 180) (layer "F.Fab") hide
        (effects (font (size 0.7 0.7) (thickness 0.15)) (justify left bottom))
    )
    (fp_rect (start -0.925 -0.47) (end 0.925 0.47)
      (stroke (width 0.05) (type default)) (fill none) (layer "F.CrtYd"))
    (fp_rect (start -0.5 -0.25) (end 0.5 0.25)
      (stroke (width 0.15) (type solid)) (fill none) (layer "F.Fab"))
    (pad "1" smd roundrect (at -0.48 0 180) (size 0.59 0.64) (layers "F.Cu" "F.Paste" "F.Mask") (roundrect_rratio 0.25)
      (net 23 "/Power Cycling & Current Measurement/PC_1") (pintype "passive"))
    (pad "2" smd roundrect (at 0.48 0 180) (size 0.59 0.64) (layers "F.Cu" "F.Paste" "F.Mask") (roundrect_rratio 0.25)
      (net 4 "GND") (pintype "passive"))
  )

  (footprint "antmicro-footprints:TPD2E009DRTR" (layer "F.Cu")
    (at 181.55 95.25 180)
    (property "Author" "Antmicro")
    (property "License" "Apache-2.0")
    (property "MPN" "PESD5V0S2BQA")
    (property "Manufacturer" "Nexperia")
    (property "Sheetfile" "d1600e-psu-breakout-board.kicad_sch")
    (property "Sheetname" "")
    (property "ki_description" "TVS diode array, 30 kV, SOT-1215, 5V, 45 pF")
    (property "ki_keywords" "SMT, DIODE, SEMICONDUCTOR, TVS, ESD")
    (attr smd)
    (fp_text reference "D13" (at 0.1 -1.3064) (layer "F.SilkS")
        (effects (font (size 0.7 0.7) (thickness 0.15)))
    )
    (fp_text value "PESD5V0S2BQA" (at 5.6088 1.3064) (layer "F.Fab") hide
        (effects (font (size 0.64 0.64) (thickness 0.015)))
    )
    (fp_text user "${REFERENCE}" (at -0.949 4.506 180) (layer "F.Fab") hide
        (effects (font (size 0.7 0.7) (thickness 0.15)) (justify left bottom))
    )
    (fp_text user "License: Apache-2.0" (at -0.949 5.706 180) (layer "F.Fab") hide
        (effects (font (size 0.7 0.7) (thickness 0.15)) (justify left bottom))
    )
    (fp_text user "Author: Antmicro" (at -0.949 3.306 180) (layer "F.Fab") hide
        (effects (font (size 0.7 0.7) (thickness 0.15)) (justify left bottom))
    )
    (fp_line (start 0.03 -0.499) (end 0.4 -0.499)
      (stroke (width 0.15) (type solid)) (layer "F.SilkS"))
    (fp_line (start 0.03 0.499) (end 0.4 0.499)
      (stroke (width 0.15) (type solid)) (layer "F.SilkS"))
    (fp_line (start 0.4 -0.419) (end 0.4 -0.499)
      (stroke (width 0.15) (type solid)) (layer "F.SilkS"))
    (fp_line (start 0.4 0.42) (end 0.4 0.499)
      (stroke (width 0.15) (type solid)) (layer "F.SilkS"))
    (fp_circle (center -0.5 -0.6) (end -0.45 -0.6)
      (stroke (width 0.15) (type solid)) (fill solid) (layer "F.SilkS"))
    (fp_rect (start -0.8 -0.59) (end 0.8 0.59)
      (stroke (width 0.05) (type solid)) (fill none) (layer "F.CrtYd"))
    (fp_line (start -0.4 -0.499) (end 0.4 -0.499)
      (stroke (width 0.15) (type solid)) (layer "F.Fab"))
    (fp_line (start -0.4 0.499) (end -0.4 -0.499)
      (stroke (width 0.15) (type solid)) (layer "F.Fab"))
    (fp_line (start 0.4 -0.499) (end 0.4 0.499)
      (stroke (width 0.15) (type solid)) (layer "F.Fab"))
    (fp_line (start 0.4 0.499) (end -0.4 0.499)
      (stroke (width 0.15) (type solid)) (layer "F.Fab"))
    (pad "1" smd rect (at -0.52 -0.349 180) (size 0.46 0.2) (layers "F.Cu" "F.Paste" "F.Mask")
      (net 17 "SCL") (pinfunction "IO1") (pintype "passive"))
    (pad "2" smd rect (at -0.52 0.348 180) (size 0.46 0.2) (layers "F.Cu" "F.Paste" "F.Mask")
      (net 18 "SDA") (pinfunction "IO2") (pintype "passive"))
    (pad "3" smd rect (at 0.52 0 180) (size 0.46 0.2) (layers "F.Cu" "F.Paste" "F.Mask")
      (net 4 "GND") (pinfunction "GND") (pintype "passive"))
  )

  (footprint "antmicro-footprints:TP_SMD_1mm" (layer "F.Cu")
    (at 162.8 111.7)
    (property "Author" "Antmicro")
    (property "License" "Apache-2.0")
    (property "MPN" "")
    (property "Manufacturer" "")
    (property "Sheetfile" "ftdi-module.kicad_sch")
    (property "Sheetname" "FTDI")
    (property "exclude_from_bom" "")
    (property "ki_description" "Test point 1mm SMD")
    (property "ki_keywords" "TESTPOINT")
    (attr exclude_from_pos_files exclude_from_bom)
    (fp_text reference "WP1" (at -2.95 0.45) (layer "F.SilkS")
        (effects (font (size 0.7 0.7) (thickness 0.15)) (justify left bottom))
    )
    (fp_text value "TP_1mm_SMD" (at 0 1.4) (layer "F.Fab")
        (effects (font (size 0.7 0.7) (thickness 0.15)) (justify left bottom))
    )
    (fp_text user "Author: Antmicro" (at -0.5 4) (layer "F.Fab") hide
        (effects (font (size 0.7 0.7) (thickness 0.15)) (justify left bottom))
    )
    (fp_text user "${REFERENCE}" (at -0.5 2.8) (layer "F.Fab") hide
        (effects (font (size 0.7 0.7) (thickness 0.15)) (justify left bottom))
    )
    (fp_text user "License: Apache-2.0" (at -0.5 5.2) (layer "F.Fab") hide
        (effects (font (size 0.7 0.7) (thickness 0.15)) (justify left bottom))
    )
    (fp_circle (center 0 0) (end 0.6 0)
      (stroke (width 0.05) (type default)) (fill none) (layer "F.CrtYd"))
    (pad "1" smd circle (at 0 0) (size 1 1) (layers "F.Cu" "F.Mask")
      (net 33 "/FTDI/WP") (pinfunction "1") (pintype "passive"))
  )

  (footprint "antmicro-footprints:Conn_Molex_KK_1x4_22-27-2041" (layer "F.Cu")
    (at 117.34 53.85)
    (property "Author" "Antmicro")
    (property "License" "Apache-2.0")
    (property "MPN" "22-27-2041")
    (property "Manufacturer" "Molex")
    (property "Sheetfile" "d1600e-psu-breakout-board.kicad_sch")
    (property "Sheetname" "")
    (property "ki_description" "Rectangular connector (header, female pins)")
    (property "ki_keywords" "VERTICAL, THT, HEADER, CONNECTOR, MALE")
    (attr through_hole)
    (fp_text reference "J11" (at 3.885 4.15) (layer "F.SilkS")
        (effects (font (size 0.7 0.7) (thickness 0.15)) (justify left bottom))
    )
    (fp_text value "Molex_KK_1x4_22-27-2041" (at -0.8 4.6 180) (layer "F.Fab")
        (effects (font (size 0.7 0.7) (thickness 0.15)) (justify left bottom))
    )
    (fp_text user "Author: Antmicro" (at -2.12 6.75) (layer "F.Fab") hide
        (effects (font (size 0.7 0.7) (thickness 0.15)) (justify left bottom))
    )
    (fp_text user "${REFERENCE}" (at -2.12 9.15) (layer "F.Fab") hide
        (effects (font (size 0.7 0.7) (thickness 0.15)) (justify left bottom))
    )
    (fp_text user "License: Apache-2.0" (at -2.12 7.95) (layer "F.Fab") hide
        (effects (font (size 0.7 0.7) (thickness 0.15)) (justify left bottom))
    )
    (fp_line (start -1.39 -3.03) (end -1.39 2.99)
      (stroke (width 0.15) (type solid)) (layer "F.SilkS"))
    (fp_line (start -1.39 2.99) (end 8.99 2.99)
      (stroke (width 0.15) (type solid)) (layer "F.SilkS"))
    (fp_line (start -0.81 -3.03) (end -0.81 -2.43)
      (stroke (width 0.15) (type solid)) (layer "F.SilkS"))
    (fp_line (start -0.81 -2.43) (end 0.79 -2.43)
      (stroke (width 0.15) (type solid)) (layer "F.SilkS"))
    (fp_line (start -0.01 1.99) (end 0.24 1.46)
      (stroke (width 0.15) (type solid)) (layer "F.SilkS"))
    (fp_line (start -0.01 1.99) (end 7.61 1.99)
      (stroke (width 0.15) (type solid)) (layer "F.SilkS"))
    (fp_line (start -0.01 2.99) (end -0.01 1.99)
      (stroke (width 0.15) (type solid)) (layer "F.SilkS"))
    (fp_line (start 0.24 1.46) (end 7.36 1.46)
      (stroke (width 0.15) (type solid)) (layer "F.SilkS"))
    (fp_line (start 0.24 2.99) (end 0.24 1.99)
      (stroke (width 0.15) (type solid)) (layer "F.SilkS"))
    (fp_line (start 0.79 -2.43) (end 0.79 -3.03)
      (stroke (width 0.15) (type solid)) (layer "F.SilkS"))
    (fp_line (start 1.73 -3.03) (end 1.73 -2.43)
      (stroke (width 0.15) (type solid)) (layer "F.SilkS"))
    (fp_line (start 1.73 -2.43) (end 3.33 -2.43)
      (stroke (width 0.15) (type solid)) (layer "F.SilkS"))
    (fp_line (start 3.33 -2.43) (end 3.33 -3.03)
      (stroke (width 0.15) (type solid)) (layer "F.SilkS"))
    (fp_line (start 4.27 -3.03) (end 4.27 -2.43)
      (stroke (width 0.15) (type solid)) (layer "F.SilkS"))
    (fp_line (start 4.27 -2.43) (end 5.87 -2.43)
      (stroke (width 0.15) (type solid)) (layer "F.SilkS"))
    (fp_line (start 5.87 -2.43) (end 5.87 -3.03)
      (stroke (width 0.15) (type solid)) (layer "F.SilkS"))
    (fp_line (start 6.81 -3.03) (end 6.81 -2.43)
      (stroke (width 0.15) (type solid)) (layer "F.SilkS"))
    (fp_line (start 6.81 -2.43) (end 8.41 -2.43)
      (stroke (width 0.15) (type solid)) (layer "F.SilkS"))
    (fp_line (start 7.36 1.46) (end 7.61 1.99)
      (stroke (width 0.15) (type solid)) (layer "F.SilkS"))
    (fp_line (start 7.36 2.99) (end 7.36 1.99)
      (stroke (width 0.15) (type solid)) (layer "F.SilkS"))
    (fp_line (start 7.61 1.99) (end 7.61 2.99)
      (stroke (width 0.15) (type solid)) (layer "F.SilkS"))
    (fp_line (start 8.41 -2.43) (end 8.41 -3.03)
      (stroke (width 0.15) (type solid)) (layer "F.SilkS"))
    (fp_line (start 8.99 -3.03) (end -1.39 -3.03)
      (stroke (width 0.15) (type solid)) (layer "F.SilkS"))
    (fp_line (start 8.99 2.99) (end 8.99 -3.03)
      (stroke (width 0.15) (type solid)) (layer "F.SilkS"))
    (fp_line (start -1.79 -3.38) (end -1.79 3.42)
      (stroke (width 0.05) (type solid)) (layer "F.CrtYd"))
    (fp_line (start -1.79 3.42) (end 9.37 3.42)
      (stroke (width 0.05) (type solid)) (layer "F.CrtYd"))
    (fp_line (start 9.37 -3.38) (end -1.79 -3.38)
      (stroke (width 0.05) (type solid)) (layer "F.CrtYd"))
    (fp_line (start 9.37 3.42) (end 9.37 -3.38)
      (stroke (width 0.05) (type solid)) (layer "F.CrtYd"))
    (fp_line (start -1.29 -2.88) (end -1.29 2.92)
      (stroke (width 0.15) (type solid)) (layer "F.Fab"))
    (fp_line (start -1.29 2.92) (end 8.87 2.92)
      (stroke (width 0.15) (type solid)) (layer "F.Fab"))
    (fp_line (start 8.163 0) (end 8.87 -0.5)
      (stroke (width 0.15) (type solid)) (layer "F.Fab"))
    (fp_line (start 8.87 -2.88) (end -1.29 -2.88)
      (stroke (width 0.15) (type solid)) (layer "F.Fab"))
    (fp_line (start 8.87 0.5) (end 8.163 0)
      (stroke (width 0.15) (type solid)) (layer "F.Fab"))
    (fp_line (start 8.87 2.92) (end 8.87 -2.88)
      (stroke (width 0.15) (type solid)) (layer "F.Fab"))
    (pad "1" thru_hole roundrect (at 0 0) (size 1.74 2.19) (drill 1.19) (layers "*.Cu" "*.Mask") (roundrect_rratio 0.143678)
      (net 11 "VCC12V0") (pintype "passive"))
    (pad "2" thru_hole oval (at 2.54 0) (size 1.74 2.19) (drill 1.19) (layers "*.Cu" "*.Mask")
      (net 4 "GND") (pintype "passive"))
    (pad "3" thru_hole oval (at 5.08 0) (size 1.74 2.19) (drill 1.19) (layers "*.Cu" "*.Mask")
      (net 4 "GND") (pintype "passive"))
    (pad "4" thru_hole oval (at 7.62 0) (size 1.74 2.19) (drill 1.19) (layers "*.Cu" "*.Mask")
      (net 2 "VCC5V0") (pintype "passive"))
  )

  (footprint "antmicro-footprints:TP_SMD_1mm" (layer "F.Cu")
    (at 189.15 119.55)
    (property "Author" "Antmicro")
    (property "License" "Apache-2.0")
    (property "MPN" "")
    (property "Manufacturer" "")
    (property "Sheetfile" "ftdi-module.kicad_sch")
    (property "Sheetname" "FTDI")
    (property "exclude_from_bom" "")
    (property "ki_description" "Test point 1mm SMD")
    (property "ki_keywords" "TESTPOINT")
    (attr exclude_from_pos_files exclude_from_bom)
    (fp_text reference "TP3" (at -0.75 1.2 90) (layer "F.SilkS")
        (effects (font (size 0.7 0.7) (thickness 0.15)) (justify left bottom))
    )
    (fp_text value "TP_1mm_SMD" (at 0 1.4) (layer "F.Fab")
        (effects (font (size 0.7 0.7) (thickness 0.15)) (justify left bottom))
    )
    (fp_text user "${REFERENCE}" (at -0.5 2.8) (layer "F.Fab") hide
        (effects (font (size 0.7 0.7) (thickness 0.15)) (justify left bottom))
    )
    (fp_text user "Author: Antmicro" (at -0.5 4) (layer "F.Fab") hide
        (effects (font (size 0.7 0.7) (thickness 0.15)) (justify left bottom))
    )
    (fp_text user "License: Apache-2.0" (at -0.5 5.2) (layer "F.Fab") hide
        (effects (font (size 0.7 0.7) (thickness 0.15)) (justify left bottom))
    )
    (fp_circle (center 0 0) (end 0.6 0)
      (stroke (width 0.05) (type default)) (fill none) (layer "F.CrtYd"))
    (pad "1" smd circle (at 0 0) (size 1 1) (layers "F.Cu" "F.Mask")
      (net 118 "Net-(U1-SBU_{2})") (pinfunction "1") (pintype "passive"))
  )

  (footprint "antmicro-footprints:D_SOD-323" (layer "F.Cu")
    (at 168.75 91.55 -90)
    (property "Author" "Antmicro")
    (property "License" "Apache-2.0")
    (property "MPN" "BZT52B15SV-T")
    (property "Manufacturer" "Rectron")
    (property "Sheetfile" "power-switch.kicad_sch")
    (property "Sheetname" "Power switch 4")
    (property "ki_description" "Zener Single Diode, AEC-Q101, 15 V, 500 mW, SOD-323, 2 Pins, 150 °C, Surface Mount")
    (property "ki_keywords" "SMT, DIODE, SEMICONDUCTOR, ZENER")
    (attr smd)
    (fp_text reference "D17" (at 1.1 -1.95 -90) (layer "F.SilkS")
        (effects (font (size 0.7 0.7) (thickness 0.15)) (justify left bottom))
    )
    (fp_text value "BZT52B15SV-T" (at 0 1.841 -90) (layer "F.Fab")
        (effects (font (size 0.7 0.7) (thickness 0.15)) (justify left bottom))
    )
    (fp_text user "Author: Antmicro" (at -1.4 6.241 -90) (layer "F.Fab") hide
        (effects (font (size 0.7 0.7) (thickness 0.15)) (justify left bottom))
    )
    (fp_text user "License: Apache-2.0" (at -1.4 3.841 -90) (layer "F.Fab") hide
        (effects (font (size 0.7 0.7) (thickness 0.15)) (justify left bottom))
    )
    (fp_text user "${REFERENCE}" (at -1.4 5.041 -90) (layer "F.Fab") hide
        (effects (font (size 0.7 0.7) (thickness 0.15)) (justify left bottom))
    )
    (fp_line (start -0.949 -0.749) (end -0.949 -0.499)
      (stroke (width 0.15) (type solid)) (layer "F.SilkS"))
    (fp_line (start -0.949 0.501) (end -0.949 0.751)
      (stroke (width 0.15) (type solid)) (layer "F.SilkS"))
    (fp_line (start -0.6 -0.499) (end -0.6 0.499)
      (stroke (width 0.15) (type solid)) (layer "F.SilkS"))
    (fp_line (start -0.577 -0.749) (end -0.949 -0.749)
      (stroke (width 0.15) (type solid)) (layer "F.SilkS"))
    (fp_line (start -0.577 0.751) (end -0.949 0.751)
      (stroke (width 0.15) (type solid)) (layer "F.SilkS"))
    (fp_line (start 0.625 -0.736) (end 0.949 -0.736)
      (stroke (width 0.15) (type solid)) (layer "F.SilkS"))
    (fp_line (start 0.949 -0.736) (end 0.949 -0.499)
      (stroke (width 0.15) (type solid)) (layer "F.SilkS"))
    (fp_line (start 0.95 0.501) (end 0.95 0.751)
      (stroke (width 0.15) (type solid)) (layer "F.SilkS"))
    (fp_line (start 0.95 0.751) (end 0.649 0.751)
      (stroke (width 0.15) (type solid)) (layer "F.SilkS"))
    (fp_rect (start -1.6 -0.925) (end 1.6 0.925)
      (stroke (width 0.05) (type solid)) (fill none) (layer "F.CrtYd"))
    (fp_line (start -0.902 0.699) (end -0.902 -0.699)
      (stroke (width 0.15) (type solid)) (layer "F.Fab"))
    (fp_line (start -0.902 0.699) (end 0.9 0.699)
      (stroke (width 0.15) (type solid)) (layer "F.Fab"))
    (fp_line (start 0.9 -0.699) (end -0.902 -0.699)
      (stroke (width 0.15) (type solid)) (layer "F.Fab"))
    (fp_line (start 0.9 -0.699) (end 0.9 0.699)
      (stroke (width 0.15) (type solid)) (layer "F.Fab"))
    (pad "1" smd rect (at -1.125 0.001 270) (size 0.8 0.8) (layers "F.Cu" "F.Paste" "F.Mask")
      (net 11 "VCC12V0") (pinfunction "C") (pintype "passive"))
    (pad "2" smd rect (at 1.124 0.001 270) (size 0.8 0.8) (layers "F.Cu" "F.Paste" "F.Mask")
      (net 85 "Net-(D17-A)") (pinfunction "A") (pintype "passive"))
  )

  (footprint "antmicro-footprints:LED_0603_1608Metric_G" (layer "F.Cu")
    (at 94.2 101.6)
    (descr "LED SMD 0603 Green")
    (tags "LED SMD 0603 Green")
    (property "Author" "Antmicro")
    (property "Color" "Green")
    (property "License" "Apache-2.0")
    (property "MPN" "LG L29K-G2J1-24-Z")
    (property "Manufacturer" "OSRAM")
    (property "Sheetfile" "d1600e-psu-breakout-board.kicad_sch")
    (property "Sheetname" "")
    (property "ki_description" "LED, Green, SMD, 0603, 20 mA, 1.7 V, 570 nm")
    (property "ki_keywords" "SMT, DIODE, SEMICONDUCTOR, LED")
    (zone_connect 1)
    (attr smd)
    (fp_text reference "D9" (at -0.7 -0.7) (layer "F.SilkS")
        (effects (font (size 0.7 0.7) (thickness 0.15)) (justify left bottom))
    )
    (fp_text value "LED_G_0603_LG_L29K-G2J1-24-Z" (at -0.001 1.599) (layer "F.Fab")
        (effects (font (size 0.7 0.7) (thickness 0.15)) (justify left bottom))
    )
    (fp_text user "${REFERENCE}" (at -1.4224 5.999) (layer "F.Fab") hide
        (effects (font (size 0.7 0.7) (thickness 0.15)) (justify left bottom))
    )
    (fp_text user "License: Apache-2.0" (at -1.4224 3.599) (layer "F.Fab") hide
        (effects (font (size 0.7 0.7) (thickness 0.15)) (justify left bottom))
    )
    (fp_text user "Author: Antmicro" (at -1.4224 4.799) (layer "F.Fab") hide
        (effects (font (size 0.7 0.7) (thickness 0.15)) (justify left bottom))
    )
    (fp_line (start -1.18 -0.319) (end -1.18 0.321)
      (stroke (width 0.15) (type solid)) (layer "F.SilkS"))
    (fp_line (start -0.094672 0.001008) (end -0.24 0.001008)
      (stroke (width 0.1) (type solid)) (layer "F.SilkS"))
    (fp_line (start -0.094672 0.001008) (end 0.105328 -0.198992)
      (stroke (width 0.1) (type solid)) (layer "F.SilkS"))
    (fp_line (start -0.094672 0.201008) (end -0.094672 -0.198992)
      (stroke (width 0.1) (type solid)) (layer "F.SilkS"))
    (fp_line (start 0.105328 0.001008) (end 0.24 0.001)
      (stroke (width 0.1) (type solid)) (layer "F.SilkS"))
    (fp_line (start 0.105328 0.201008) (end -0.094672 0.001008)
      (stroke (width 0.1) (type solid)) (layer "F.SilkS"))
    (fp_line (start 0.105328 0.201008) (end 0.105328 -0.198992)
      (stroke (width 0.1) (type solid)) (layer "F.SilkS"))
    (fp_line (start 0.22 -0.35) (end -0.22 -0.35)
      (stroke (width 0.15) (type solid)) (layer "F.SilkS"))
    (fp_line (start 0.22 0.35) (end -0.22 0.35)
      (stroke (width 0.15) (type solid)) (layer "F.SilkS"))
    (fp_rect (start 1.25 0.65) (end -1.25 -0.65)
      (stroke (width 0.05) (type solid)) (fill none) (layer "F.CrtYd"))
    (fp_line (start -0.199 -0.202) (end -0.199 0.1)
      (stroke (width 0.15) (type solid)) (layer "F.Fab"))
    (fp_line (start -0.199 0) (end -0.597 0)
      (stroke (width 0.15) (type solid)) (layer "F.Fab"))
    (fp_line (start -0.199 0.2) (end -0.199 0.1)
      (stroke (width 0.15) (type solid)) (layer "F.Fab"))
    (fp_line (start -0.101 0) (end 0.201 0.2)
      (stroke (width 0.15) (type solid)) (layer "F.Fab"))
    (fp_line (start 0.201 -0.202) (end -0.101 0)
      (stroke (width 0.15) (type solid)) (layer "F.Fab"))
    (fp_line (start 0.201 0) (end 0.201 -0.202)
      (stroke (width 0.15) (type solid)) (layer "F.Fab"))
    (fp_line (start 0.201 0.2) (end 0.201 0)
      (stroke (width 0.15) (type solid)) (layer "F.Fab"))
    (fp_line (start 0.599 0) (end 0.201 0)
      (stroke (width 0.15) (type solid)) (layer "F.Fab"))
    (fp_rect (start 0.848 0.4) (end -0.85 -0.402)
      (stroke (width 0.15) (type solid)) (fill none) (layer "F.Fab"))
    (pad "1" smd roundrect (at -0.7 0 180) (size 0.8 1) (layers "F.Cu" "F.Paste" "F.Mask") (roundrect_rratio 0.2)
      (net 4 "GND") (pinfunction "C") (pintype "passive"))
    (pad "2" smd roundrect (at 0.7 0 180) (size 0.8 1) (layers "F.Cu" "F.Paste" "F.Mask") (roundrect_rratio 0.2)
      (net 78 "Net-(D9-A)") (pinfunction "A") (pintype "passive"))
  )

  (footprint "antmicro-footprints:Vishay_PowerPAK_1212-8_Single" (layer "F.Cu")
    (at 185.6 86.2008 90)
    (descr "PowerPAK 1212-8 Single")
    (tags "Vishay PowerPAK 1212-8 Single")
    (property "Author" "Antmicro")
    (property "License" "Apache-2.0")
    (property "MPN" "SI7613DN-T1-GE3")
    (property "Manufacturer" "Vishay")
    (property "Sheetfile" "power-switch.kicad_sch")
    (property "Sheetname" "Power switch 5")
    (property "ki_description" "Power MOSFET, P Channel, 20 V, 35 A, 0.0072 ohm, PowerPAK 1212, Surface Mount")
    (property "ki_keywords" "SMT, TRANSISTOR, SEMICONDUCTOR, MOSFET, PMOS")
    (attr smd)
    (fp_text reference "QB5" (at -2.9492 0.4 180) (layer "F.SilkS")
        (effects (font (size 0.7 0.7) (thickness 0.15)) (justify left bottom))
    )
    (fp_text value "SI7613DN-T1-GE3" (at 0 2.7 90) (layer "F.Fab")
        (effects (font (size 0.7 0.7) (thickness 0.15)) (justify left bottom))
    )
    (fp_text user "Author: Antmicro" (at -8 5.9 90) (layer "F.Fab") hide
        (effects (font (size 0.7 0.7) (thickness 0.15)) (justify left bottom))
    )
    (fp_text user "${REFERENCE}" (at -8 4.7 90) (layer "F.Fab") hide
        (effects (font (size 0.7 0.7) (thickness 0.15)) (justify left bottom))
    )
    (fp_text user "License: Apache-2.0" (at -8 7.1 90) (layer "F.Fab") hide
        (effects (font (size 0.7 0.7) (thickness 0.15)) (justify left bottom))
    )
    (fp_line (start -1.651 -1.651) (end -1.651 -1.317)
      (stroke (width 0.15) (type solid)) (layer "F.SilkS"))
    (fp_line (start -1.651 -1.651) (end 1.648 -1.651)
      (stroke (width 0.15) (type solid)) (layer "F.SilkS"))
    (fp_line (start -1.635 1.3) (end -1.635 1.634)
      (stroke (width 0.15) (type solid)) (layer "F.SilkS"))
    (fp_line (start -1.635 1.634) (end 1.634 1.634)
      (stroke (width 0.15) (type solid)) (layer "F.SilkS"))
    (fp_line (start 1.634 1.3) (end 1.634 1.634)
      (stroke (width 0.15) (type solid)) (layer "F.SilkS"))
    (fp_line (start 1.648 -1.651) (end 1.648 -1.317)
      (stroke (width 0.15) (type solid)) (layer "F.SilkS"))
    (fp_circle (center -1.9 -1.4) (end -1.85 -1.4)
      (stroke (width 0.15) (type solid)) (fill solid) (layer "F.SilkS"))
    (fp_rect (start -2 -1.8) (end 2 1.798)
      (stroke (width 0.05) (type solid)) (fill none) (layer "F.CrtYd"))
    (fp_line (start -1.6425 -1.4175) (end -1.4175 -1.6425)
      (stroke (width 0.15) (type solid)) (layer "F.Fab"))
    (fp_rect (start -1.651 -1.651) (end 1.648 1.648)
      (stroke (width 0.15) (type solid)) (fill none) (layer "F.Fab"))
    (pad "1" smd rect (at -1.436 -0.99 90) (size 0.99 0.405) (layers "F.Cu" "F.Paste" "F.Mask")
      (net 11 "VCC12V0") (pinfunction "S") (pintype "passive"))
    (pad "2" smd rect (at -1.436 -0.332 90) (size 0.99 0.405) (layers "F.Cu" "F.Paste" "F.Mask")
      (net 11 "VCC12V0") (pinfunction "S") (pintype "passive"))
    (pad "3" smd rect (at -1.436 0.33 90) (size 0.99 0.405) (layers "F.Cu" "F.Paste" "F.Mask")
      (net 11 "VCC12V0") (pinfunction "S") (pintype "passive"))
    (pad "4" smd rect (at -1.436 0.988 90) (size 0.99 0.405) (layers "F.Cu" "F.Paste" "F.Mask")
      (net 103 "Net-(QB5-G)") (pinfunction "G") (pintype "passive"))
    (pad "5" smd custom (at 0.557 0 90) (size 1.725 2.235) (layers "F.Cu" "F.Paste" "F.Mask")
      (net 25 "C_MEAS_5") (pinfunction "D") (pintype "passive") (zone_connect 2)
      (options (clearance outline) (anchor rect))
      (primitives
        (gr_poly
          (pts
            (xy 0.8625 0.1275)
            (xy 0.8625 -0.1275)
            (xy 1.3725 -0.1275)
            (xy 1.3725 -0.5325)
            (xy 0.8625 -0.5325)
            (xy 0.8625 -0.7875)
            (xy 1.3725 -0.7875)
            (xy 1.3725 -1.195)
            (xy 0.6125 -1.195)
            (xy 0.6125 1.195)
            (xy 1.3725 1.195)
            (xy 1.3725 0.7875)
            (xy 0.8625 0.7875)
            (xy 0.8625 0.5325)
            (xy 1.3725 0.5325)
            (xy 1.3725 0.1275)
          )
          (width 0) (fill yes))
      ))
  )

  (footprint "antmicro-footprints:D_SOD-323" (layer "F.Cu")
    (at 151.9 91.15 -90)
    (property "Author" "Antmicro")
    (property "License" "Apache-2.0")
    (property "MPN" "BZT52B15SV-T")
    (property "Manufacturer" "Rectron")
    (property "Sheetfile" "power-switch.kicad_sch")
    (property "Sheetname" "Power switch 3")
    (property "ki_description" "Zener Single Diode, AEC-Q101, 15 V, 500 mW, SOD-323, 2 Pins, 150 °C, Surface Mount")
    (property "ki_keywords" "SMT, DIODE, SEMICONDUCTOR, ZENER")
    (attr smd)
    (fp_text reference "D18" (at 3.7 -0.4 90) (layer "F.SilkS")
        (effects (font (size 0.7 0.7) (thickness 0.15)) (justify left bottom))
    )
    (fp_text value "BZT52B15SV-T" (at 0 1.841 -90) (layer "F.Fab")
        (effects (font (size 0.7 0.7) (thickness 0.15)) (justify left bottom))
    )
    (fp_text user "Author: Antmicro" (at -1.4 6.241 -90) (layer "F.Fab") hide
        (effects (font (size 0.7 0.7) (thickness 0.15)) (justify left bottom))
    )
    (fp_text user "${REFERENCE}" (at -1.4 5.041 -90) (layer "F.Fab") hide
        (effects (font (size 0.7 0.7) (thickness 0.15)) (justify left bottom))
    )
    (fp_text user "License: Apache-2.0" (at -1.4 3.841 -90) (layer "F.Fab") hide
        (effects (font (size 0.7 0.7) (thickness 0.15)) (justify left bottom))
    )
    (fp_line (start -0.949 -0.749) (end -0.949 -0.499)
      (stroke (width 0.15) (type solid)) (layer "F.SilkS"))
    (fp_line (start -0.949 0.501) (end -0.949 0.751)
      (stroke (width 0.15) (type solid)) (layer "F.SilkS"))
    (fp_line (start -0.6 -0.499) (end -0.6 0.499)
      (stroke (width 0.15) (type solid)) (layer "F.SilkS"))
    (fp_line (start -0.577 -0.749) (end -0.949 -0.749)
      (stroke (width 0.15) (type solid)) (layer "F.SilkS"))
    (fp_line (start -0.577 0.751) (end -0.949 0.751)
      (stroke (width 0.15) (type solid)) (layer "F.SilkS"))
    (fp_line (start 0.625 -0.736) (end 0.949 -0.736)
      (stroke (width 0.15) (type solid)) (layer "F.SilkS"))
    (fp_line (start 0.949 -0.736) (end 0.949 -0.499)
      (stroke (width 0.15) (type solid)) (layer "F.SilkS"))
    (fp_line (start 0.95 0.501) (end 0.95 0.751)
      (stroke (width 0.15) (type solid)) (layer "F.SilkS"))
    (fp_line (start 0.95 0.751) (end 0.649 0.751)
      (stroke (width 0.15) (type solid)) (layer "F.SilkS"))
    (fp_rect (start -1.6 -0.925) (end 1.6 0.925)
      (stroke (width 0.05) (type solid)) (fill none) (layer "F.CrtYd"))
    (fp_line (start -0.902 0.699) (end -0.902 -0.699)
      (stroke (width 0.15) (type solid)) (layer "F.Fab"))
    (fp_line (start -0.902 0.699) (end 0.9 0.699)
      (stroke (width 0.15) (type solid)) (layer "F.Fab"))
    (fp_line (start 0.9 -0.699) (end -0.902 -0.699)
      (stroke (width 0.15) (type solid)) (layer "F.Fab"))
    (fp_line (start 0.9 -0.699) (end 0.9 0.699)
      (stroke (width 0.15) (type solid)) (layer "F.Fab"))
    (pad "1" smd rect (at -1.125 0.001 270) (size 0.8 0.8) (layers "F.Cu" "F.Paste" "F.Mask")
      (net 11 "VCC12V0") (pinfunction "C") (pintype "passive"))
    (pad "2" smd rect (at 1.124 0.001 270) (size 0.8 0.8) (layers "F.Cu" "F.Paste" "F.Mask")
      (net 86 "Net-(D18-A)") (pinfunction "A") (pintype "passive"))
  )

  (footprint "antmicro-footprints:R_0603_1608Metric" (layer "F.Cu")
    (at 113.6 53.65)
    (descr "Resistor SMD 0603")
    (tags "resistor SMD 0603")
    (property "Author" "Antmicro")
    (property "License" "Apache-2.0")
    (property "MPN" "CR0603-FX-4701ELF")
    (property "Manufacturer" "Bourns")
    (property "Sheetfile" "d1600e-psu-breakout-board.kicad_sch")
    (property "Sheetname" "")
    (property "Tolerance" "1%")
    (property "Val" "4k7")
    (property "ki_description" "SMD Chip Resistor, 4.7 kohm, ± 1%, 100 mW, 0603 [1608 Metric], Thick Film, General Purpose")
    (property "ki_keywords" "0603, SMT, RESISTOR, PASSIVE")
    (attr smd)
    (fp_text reference "R11" (at -1.05 1.7) (layer "F.SilkS")
        (effects (font (size 0.7 0.7) (thickness 0.15)) (justify left bottom))
    )
    (fp_text value "R_4k7_0603" (at 0 1.6) (layer "F.Fab")
        (effects (font (size 0.7 0.7) (thickness 0.15)) (justify left bottom))
    )
    (fp_text user "Author: Antmicro" (at -1.25 4.9) (layer "F.Fab") hide
        (effects (font (size 0.7 0.7) (thickness 0.15)) (justify left bottom))
    )
    (fp_text user "License: Apache-2.0" (at -1.25 5.9) (layer "F.Fab") hide
        (effects (font (size 0.7 0.7) (thickness 0.15)) (justify left bottom))
    )
    (fp_text user "${REFERENCE}" (at -1.25 3.898) (layer "F.Fab") hide
        (effects (font (size 0.7 0.7) (thickness 0.15)) (justify left bottom))
    )
    (fp_line (start -0.15 -0.4) (end 0.15 -0.4)
      (stroke (width 0.15) (type solid)) (layer "F.SilkS"))
    (fp_line (start -0.15 0.4) (end 0.15 0.4)
      (stroke (width 0.15) (type solid)) (layer "F.SilkS"))
    (fp_rect (start -1.25 -0.65) (end 1.25 0.65)
      (stroke (width 0.05) (type solid)) (fill none) (layer "F.CrtYd"))
    (fp_rect (start -0.8 -0.4) (end 0.8 0.4)
      (stroke (width 0.15) (type solid)) (fill none) (layer "F.Fab"))
    (pad "1" smd roundrect (at -0.7 0) (size 0.8 1) (layers "F.Cu" "F.Paste" "F.Mask") (roundrect_rratio 0.2)
      (net 36 "Net-(D3-A)") (pintype "passive"))
    (pad "2" smd roundrect (at 0.7 0) (size 0.8 1) (layers "F.Cu" "F.Paste" "F.Mask") (roundrect_rratio 0.2)
      (net 41 "LOAD_1") (pintype "passive"))
  )

  (footprint "antmicro-footprints:R_0402_1005Metric" (layer "F.Cu")
    (at 138.45 91.75 -90)
    (descr "Resistor SMD 0402")
    (tags "resistor SMD 0402")
    (property "Author" "Antmicro")
    (property "License" "Apache-2.0")
    (property "MPN" "CR0402-FX-2R00GLF")
    (property "Manufacturer" "Bourns")
    (property "Sheetfile" "power-switch.kicad_sch")
    (property "Sheetname" "Power switch 2")
    (property "Tolerance" "1%")
    (property "Val" "2R")
    (property "ki_description" "SMD Chip Resistor")
    (property "ki_keywords" "0402, SMT, RESISTOR, PASSIVE")
    (attr smd)
    (fp_text reference "R61" (at 0.85 -0.4 90) (layer "F.SilkS")
        (effects (font (size 0.7 0.7) (thickness 0.15)) (justify right bottom))
    )
    (fp_text value "R_2R_0402" (at -1.011843 1.772047 90) (layer "F.Fab")
        (effects (font (size 0.7 0.7) (thickness 0.15)) (justify right bottom))
    )
    (fp_text user "${REFERENCE}" (at -0.95 3.168 90) (layer "F.Fab") hide
        (effects (font (size 0.7 0.7) (thickness 0.15)) (justify right bottom))
    )
    (fp_text user "License: Apache-2.0" (at -0.95 5.169 90) (layer "F.Fab") hide
        (effects (font (size 0.7 0.7) (thickness 0.15)) (justify right bottom))
    )
    (fp_text user "Author: Antmicro" (at -0.95 4.169 90) (layer "F.Fab") hide
        (effects (font (size 0.7 0.7) (thickness 0.15)) (justify right bottom))
    )
    (fp_rect (start -0.925 -0.47) (end 0.925 0.47)
      (stroke (width 0.05) (type default)) (fill none) (layer "F.CrtYd"))
    (fp_rect (start -0.5 -0.25) (end 0.5 0.25)
      (stroke (width 0.15) (type solid)) (fill none) (layer "F.Fab"))
    (pad "1" smd roundrect (at -0.48 0 270) (size 0.59 0.64) (layers "F.Cu" "F.Paste" "F.Mask") (roundrect_rratio 0.25)
      (net 100 "Net-(QB2-G)") (pintype "passive"))
    (pad "2" smd roundrect (at 0.48 0 270) (size 0.59 0.64) (layers "F.Cu" "F.Paste" "F.Mask") (roundrect_rratio 0.25)
      (net 84 "Net-(D16-A)") (pintype "passive"))
  )

  (footprint "antmicro-footprints:R_0603_1608Metric" (layer "F.Cu")
    (at 96.9 99)
    (descr "Resistor SMD 0603")
    (tags "resistor SMD 0603")
    (property "Author" "Antmicro")
    (property "License" "Apache-2.0")
    (property "MPN" "CR0603-FX-1001ELF")
    (property "Manufacturer" "Bourns")
    (property "Sheetfile" "d1600e-psu-breakout-board.kicad_sch")
    (property "Sheetname" "")
    (property "Tolerance" "1%")
    (property "Val" "1k")
    (property "ki_description" "SMD Chip Resistor, 1 kohm, ± 1%, 100 mW, 0603 [1608 Metric], Thick Film, General Purpose")
    (property "ki_keywords" "0603, SMT, RESISTOR, PASSIVE")
    (attr smd)
    (fp_text reference "R55" (at -1.05 -0.6) (layer "F.SilkS")
        (effects (font (size 0.7 0.7) (thickness 0.15)) (justify left bottom))
    )
    (fp_text value "R_1k_0603" (at 0 1.6) (layer "F.Fab")
        (effects (font (size 0.7 0.7) (thickness 0.15)) (justify left bottom))
    )
    (fp_text user "Author: Antmicro" (at -1.25 4.9) (layer "F.Fab") hide
        (effects (font (size 0.7 0.7) (thickness 0.15)) (justify left bottom))
    )
    (fp_text user "License: Apache-2.0" (at -1.25 5.9) (layer "F.Fab") hide
        (effects (font (size 0.7 0.7) (thickness 0.15)) (justify left bottom))
    )
    (fp_text user "${REFERENCE}" (at -1.25 3.898) (layer "F.Fab") hide
        (effects (font (size 0.7 0.7) (thickness 0.15)) (justify left bottom))
    )
    (fp_line (start -0.15 -0.4) (end 0.15 -0.4)
      (stroke (width 0.15) (type solid)) (layer "F.SilkS"))
    (fp_line (start -0.15 0.4) (end 0.15 0.4)
      (stroke (width 0.15) (type solid)) (layer "F.SilkS"))
    (fp_rect (start -1.25 -0.65) (end 1.25 0.65)
      (stroke (width 0.05) (type solid)) (fill none) (layer "F.CrtYd"))
    (fp_rect (start -0.8 -0.4) (end 0.8 0.4)
      (stroke (width 0.15) (type solid)) (fill none) (layer "F.Fab"))
    (pad "1" smd roundrect (at -0.7 0) (size 0.8 1) (layers "F.Cu" "F.Paste" "F.Mask") (roundrect_rratio 0.2)
      (net 79 "Net-(D10-A)") (pintype "passive"))
    (pad "2" smd roundrect (at 0.7 0) (size 0.8 1) (layers "F.Cu" "F.Paste" "F.Mask") (roundrect_rratio 0.2)
      (net 2 "VCC5V0") (pintype "passive"))
  )

  (footprint "antmicro-footprints:Vishay_PowerPAK_1212-8_Single" (layer "F.Cu")
    (at 181.79 87.35 90)
    (descr "PowerPAK 1212-8 Single")
    (tags "Vishay PowerPAK 1212-8 Single")
    (property "Author" "Antmicro")
    (property "License" "Apache-2.0")
    (property "MPN" "SI7613DN-T1-GE3")
    (property "Manufacturer" "Vishay")
    (property "Sheetfile" "power-switch.kicad_sch")
    (property "Sheetname" "Power switch 5")
    (property "ki_description" "Power MOSFET, P Channel, 20 V, 35 A, 0.0072 ohm, PowerPAK 1212, Surface Mount")
    (property "ki_keywords" "SMT, TRANSISTOR, SEMICONDUCTOR, MOSFET, PMOS")
    (attr smd)
    (fp_text reference "QA5" (at 3.5 1.61 180) (layer "F.SilkS")
        (effects (font (size 0.7 0.7) (thickness 0.15)) (justify left bottom))
    )
    (fp_text value "SI7613DN-T1-GE3" (at 0 2.7 90) (layer "F.Fab")
        (effects (font (size 0.7 0.7) (thickness 0.15)) (justify left bottom))
    )
    (fp_text user "${REFERENCE}" (at -8 4.7 90) (layer "F.Fab") hide
        (effects (font (size 0.7 0.7) (thickness 0.15)) (justify left bottom))
    )
    (fp_text user "Author: Antmicro" (at -8 5.9 90) (layer "F.Fab") hide
        (effects (font (size 0.7 0.7) (thickness 0.15)) (justify left bottom))
    )
    (fp_text user "License: Apache-2.0" (at -8 7.1 90) (layer "F.Fab") hide
        (effects (font (size 0.7 0.7) (thickness 0.15)) (justify left bottom))
    )
    (fp_line (start -1.651 -1.651) (end -1.651 -1.317)
      (stroke (width 0.15) (type solid)) (layer "F.SilkS"))
    (fp_line (start -1.651 -1.651) (end 1.648 -1.651)
      (stroke (width 0.15) (type solid)) (layer "F.SilkS"))
    (fp_line (start -1.635 1.3) (end -1.635 1.634)
      (stroke (width 0.15) (type solid)) (layer "F.SilkS"))
    (fp_line (start -1.635 1.634) (end 1.634 1.634)
      (stroke (width 0.15) (type solid)) (layer "F.SilkS"))
    (fp_line (start 1.634 1.3) (end 1.634 1.634)
      (stroke (width 0.15) (type solid)) (layer "F.SilkS"))
    (fp_line (start 1.648 -1.651) (end 1.648 -1.317)
      (stroke (width 0.15) (type solid)) (layer "F.SilkS"))
    (fp_circle (center -1.9 -1.4) (end -1.85 -1.4)
      (stroke (width 0.15) (type solid)) (fill solid) (layer "F.SilkS"))
    (fp_rect (start -2 -1.8) (end 2 1.798)
      (stroke (width 0.05) (type solid)) (fill none) (layer "F.CrtYd"))
    (fp_line (start -1.6425 -1.4175) (end -1.4175 -1.6425)
      (stroke (width 0.15) (type solid)) (layer "F.Fab"))
    (fp_rect (start -1.651 -1.651) (end 1.648 1.648)
      (stroke (width 0.15) (type solid)) (fill none) (layer "F.Fab"))
    (pad "1" smd rect (at -1.436 -0.99 90) (size 0.99 0.405) (layers "F.Cu" "F.Paste" "F.Mask")
      (net 11 "VCC12V0") (pinfunction "S") (pintype "passive"))
    (pad "2" smd rect (at -1.436 -0.332 90) (size 0.99 0.405) (layers "F.Cu" "F.Paste" "F.Mask")
      (net 11 "VCC12V0") (pinfunction "S") (pintype "passive"))
    (pad "3" smd rect (at -1.436 0.33 90) (size 0.99 0.405) (layers "F.Cu" "F.Paste" "F.Mask")
      (net 11 "VCC12V0") (pinfunction "S") (pintype "passive"))
    (pad "4" smd rect (at -1.436 0.988 90) (size 0.99 0.405) (layers "F.Cu" "F.Paste" "F.Mask")
      (net 97 "Net-(QA5-G)") (pinfunction "G") (pintype "passive"))
    (pad "5" smd custom (at 0.557 0 90) (size 1.725 2.235) (layers "F.Cu" "F.Paste" "F.Mask")
      (net 25 "C_MEAS_5") (pinfunction "D") (pintype "passive") (zone_connect 2)
      (options (clearance outline) (anchor rect))
      (primitives
        (gr_poly
          (pts
            (xy 0.8625 0.1275)
            (xy 0.8625 -0.1275)
            (xy 1.3725 -0.1275)
            (xy 1.3725 -0.5325)
            (xy 0.8625 -0.5325)
            (xy 0.8625 -0.7875)
            (xy 1.3725 -0.7875)
            (xy 1.3725 -1.195)
            (xy 0.6125 -1.195)
            (xy 0.6125 1.195)
            (xy 1.3725 1.195)
            (xy 1.3725 0.7875)
            (xy 0.8625 0.7875)
            (xy 0.8625 0.5325)
            (xy 1.3725 0.5325)
            (xy 1.3725 0.1275)
          )
          (width 0) (fill yes))
      ))
  )

  (footprint "antmicro-footprints:R_0402_1005Metric" (layer "F.Cu")
    (at 186.55 90.1 -90)
    (descr "Resistor SMD 0402")
    (tags "resistor SMD 0402")
    (property "Author" "Antmicro")
    (property "License" "Apache-2.0")
    (property "MPN" "CR0402-FX-2R00GLF")
    (property "Manufacturer" "Bourns")
    (property "Sheetfile" "power-switch.kicad_sch")
    (property "Sheetname" "Power switch 5")
    (property "Tolerance" "1%")
    (property "Val" "2R")
    (property "ki_description" "SMD Chip Resistor")
    (property "ki_keywords" "0402, SMT, RESISTOR, PASSIVE")
    (attr smd)
    (fp_text reference "R68" (at 1.15 -1.35 -90) (layer "F.SilkS")
        (effects (font (size 0.7 0.7) (thickness 0.15)) (justify left bottom))
    )
    (fp_text value "R_2R_0402" (at -1.011843 1.772047 -90) (layer "F.Fab")
        (effects (font (size 0.7 0.7) (thickness 0.15)) (justify left bottom))
    )
    (fp_text user "${REFERENCE}" (at -0.95 3.168 -90) (layer "F.Fab") hide
        (effects (font (size 0.7 0.7) (thickness 0.15)) (justify left bottom))
    )
    (fp_text user "Author: Antmicro" (at -0.95 4.169 -90) (layer "F.Fab") hide
        (effects (font (size 0.7 0.7) (thickness 0.15)) (justify left bottom))
    )
    (fp_text user "License: Apache-2.0" (at -0.95 5.169 -90) (layer "F.Fab") hide
        (effects (font (size 0.7 0.7) (thickness 0.15)) (justify left bottom))
    )
    (fp_rect (start -0.925 -0.47) (end 0.925 0.47)
      (stroke (width 0.05) (type default)) (fill none) (layer "F.CrtYd"))
    (fp_rect (start -0.5 -0.25) (end 0.5 0.25)
      (stroke (width 0.15) (type solid)) (fill none) (layer "F.Fab"))
    (pad "1" smd roundrect (at -0.48 0 270) (size 0.59 0.64) (layers "F.Cu" "F.Paste" "F.Mask") (roundrect_rratio 0.25)
      (net 103 "Net-(QB5-G)") (pintype "passive"))
    (pad "2" smd roundrect (at 0.48 0 270) (size 0.59 0.64) (layers "F.Cu" "F.Paste" "F.Mask") (roundrect_rratio 0.25)
      (net 87 "Net-(D19-A)") (pintype "passive"))
  )

  (footprint "antmicro-footprints:Vishay_PowerPAK_1212-8_Single" (layer "F.Cu")
    (at 133.65 87.25 90)
    (descr "PowerPAK 1212-8 Single")
    (tags "Vishay PowerPAK 1212-8 Single")
    (property "Author" "Antmicro")
    (property "License" "Apache-2.0")
    (property "MPN" "SI7613DN-T1-GE3")
    (property "Manufacturer" "Vishay")
    (property "Sheetfile" "power-switch.kicad_sch")
    (property "Sheetname" "Power switch 2")
    (property "ki_description" "Power MOSFET, P Channel, 20 V, 35 A, 0.0072 ohm, PowerPAK 1212, Surface Mount")
    (property "ki_keywords" "SMT, TRANSISTOR, SEMICONDUCTOR, MOSFET, PMOS")
    (attr smd)
    (fp_text reference "QA2" (at -2.85 -1 180) (layer "F.SilkS")
        (effects (font (size 0.7 0.7) (thickness 0.15)) (justify left bottom))
    )
    (fp_text value "SI7613DN-T1-GE3" (at 0 2.7 90) (layer "F.Fab")
        (effects (font (size 0.7 0.7) (thickness 0.15)) (justify left bottom))
    )
    (fp_text user "Author: Antmicro" (at -8 5.9 90) (layer "F.Fab") hide
        (effects (font (size 0.7 0.7) (thickness 0.15)) (justify left bottom))
    )
    (fp_text user "${REFERENCE}" (at -8 4.7 90) (layer "F.Fab") hide
        (effects (font (size 0.7 0.7) (thickness 0.15)) (justify left bottom))
    )
    (fp_text user "License: Apache-2.0" (at -8 7.1 90) (layer "F.Fab") hide
        (effects (font (size 0.7 0.7) (thickness 0.15)) (justify left bottom))
    )
    (fp_line (start -1.651 -1.651) (end -1.651 -1.317)
      (stroke (width 0.15) (type solid)) (layer "F.SilkS"))
    (fp_line (start -1.651 -1.651) (end 1.648 -1.651)
      (stroke (width 0.15) (type solid)) (layer "F.SilkS"))
    (fp_line (start -1.635 1.3) (end -1.635 1.634)
      (stroke (width 0.15) (type solid)) (layer "F.SilkS"))
    (fp_line (start -1.635 1.634) (end 1.634 1.634)
      (stroke (width 0.15) (type solid)) (layer "F.SilkS"))
    (fp_line (start 1.634 1.3) (end 1.634 1.634)
      (stroke (width 0.15) (type solid)) (layer "F.SilkS"))
    (fp_line (start 1.648 -1.651) (end 1.648 -1.317)
      (stroke (width 0.15) (type solid)) (layer "F.SilkS"))
    (fp_circle (center -1.9 -1.4) (end -1.85 -1.4)
      (stroke (width 0.15) (type solid)) (fill solid) (layer "F.SilkS"))
    (fp_rect (start -2 -1.8) (end 2 1.798)
      (stroke (width 0.05) (type solid)) (fill none) (layer "F.CrtYd"))
    (fp_line (start -1.6425 -1.4175) (end -1.4175 -1.6425)
      (stroke (width 0.15) (type solid)) (layer "F.Fab"))
    (fp_rect (start -1.651 -1.651) (end 1.648 1.648)
      (stroke (width 0.15) (type solid)) (fill none) (layer "F.Fab"))
    (pad "1" smd rect (at -1.436 -0.99 90) (size 0.99 0.405) (layers "F.Cu" "F.Paste" "F.Mask")
      (net 11 "VCC12V0") (pinfunction "S") (pintype "passive"))
    (pad "2" smd rect (at -1.436 -0.332 90) (size 0.99 0.405) (layers "F.Cu" "F.Paste" "F.Mask")
      (net 11 "VCC12V0") (pinfunction "S") (pintype "passive"))
    (pad "3" smd rect (at -1.436 0.33 90) (size 0.99 0.405) (layers "F.Cu" "F.Paste" "F.Mask")
      (net 11 "VCC12V0") (pinfunction "S") (pintype "passive"))
    (pad "4" smd rect (at -1.436 0.988 90) (size 0.99 0.405) (layers "F.Cu" "F.Paste" "F.Mask")
      (net 94 "Net-(QA2-G)") (pinfunction "G") (pintype "passive"))
    (pad "5" smd custom (at 0.557 0 90) (size 1.725 2.235) (layers "F.Cu" "F.Paste" "F.Mask")
      (net 22 "C_MEAS_2") (pinfunction "D") (pintype "passive") (zone_connect 2)
      (options (clearance outline) (anchor rect))
      (primitives
        (gr_poly
          (pts
            (xy 0.8625 0.1275)
            (xy 0.8625 -0.1275)
            (xy 1.3725 -0.1275)
            (xy 1.3725 -0.5325)
            (xy 0.8625 -0.5325)
            (xy 0.8625 -0.7875)
            (xy 1.3725 -0.7875)
            (xy 1.3725 -1.195)
            (xy 0.6125 -1.195)
            (xy 0.6125 1.195)
            (xy 1.3725 1.195)
            (xy 1.3725 0.7875)
            (xy 0.8625 0.7875)
            (xy 0.8625 0.5325)
            (xy 1.3725 0.5325)
            (xy 1.3725 0.1275)
          )
          (width 0) (fill yes))
      ))
  )

  (footprint "antmicro-footprints:C_0402_1005Metric" (layer "F.Cu")
    (at 170.1 123.2 -90)
    (descr "Capacitor SMD 0402")
    (tags "capacitor SMD 0402")
    (property "Author" "Antmicro")
    (property "Dielectric" "")
    (property "License" "Apache-2.0")
    (property "MPN" "CL05C180JB51PNC")
    (property "Manufacturer" "Samsung Electro-Mechanics")
    (property "Sheetfile" "ftdi-module.kicad_sch")
    (property "Sheetname" "FTDI")
    (property "Val" "18p")
    (property "Voltage" "")
    (property "ki_description" "SMD Multilayer Ceramic Capacitor, 18 pF, 50 V, 0402 [1005 Metric], ± 5%, C0G / NP0, MC")
    (property "ki_keywords" "0402, SMT, CAPACITOR, PASSIVE")
    (attr smd)
    (fp_text reference "C1" (at -0.75 -1.5 90) (layer "F.SilkS")
        (effects (font (size 0.7 0.7) (thickness 0.15)) (justify right bottom))
    )
    (fp_text value "C_18p_0402" (at -1.022927 2.155213 90) (layer "F.Fab")
        (effects (font (size 0.7 0.7) (thickness 0.15)) (justify right bottom))
    )
    (fp_text user "${REFERENCE}" (at -0.939 4.599 90) (layer "F.Fab") hide
        (effects (font (size 0.7 0.7) (thickness 0.15)) (justify right bottom))
    )
    (fp_text user "Author: Antmicro" (at -0.939 3.399 90) (layer "F.Fab") hide
        (effects (font (size 0.7 0.7) (thickness 0.15)) (justify right bottom))
    )
    (fp_text user "License: Apache-2.0" (at -0.939 5.799 90) (layer "F.Fab") hide
        (effects (font (size 0.7 0.7) (thickness 0.15)) (justify right bottom))
    )
    (fp_rect (start -0.925 -0.47) (end 0.925 0.47)
      (stroke (width 0.05) (type default)) (fill none) (layer "F.CrtYd"))
    (fp_line (start -0.494 -0.25) (end 0.504 -0.25)
      (stroke (width 0.15) (type solid)) (layer "F.Fab"))
    (fp_line (start -0.494 0.248) (end -0.494 -0.25)
      (stroke (width 0.15) (type solid)) (layer "F.Fab"))
    (fp_line (start 0.504 -0.25) (end 0.504 0.248)
      (stroke (width 0.15) (type solid)) (layer "F.Fab"))
    (fp_line (start 0.504 0.248) (end -0.494 0.248)
      (stroke (width 0.15) (type solid)) (layer "F.Fab"))
    (pad "1" smd roundrect (at -0.48 0 270) (size 0.59 0.64) (layers "F.Cu" "F.Paste" "F.Mask") (roundrect_rratio 0.25)
      (net 77 "GNDD") (pintype "passive"))
    (pad "2" smd roundrect (at 0.48 0 270) (size 0.59 0.64) (layers "F.Cu" "F.Paste" "F.Mask") (roundrect_rratio 0.25)
      (net 125 "/FTDI/OSCO") (pintype "passive"))
  )
  (gr_line (start 90 50) (end 190 50)
    (stroke (width 0.12) (type solid)) (layer "Edge.Cuts"))
  (gr_line (start 90 150) (end 90 50)
    (stroke (width 0.12) (type solid)) (layer "Edge.Cuts"))
  (gr_line (start 100 150) (end 90 150)
    (stroke (width 0.12) (type solid)) (layer "Edge.Cuts"))
  (gr_line (start 170.85 146.4) (end 125.85 146.4)
    (stroke (width 0.12) (type solid)) (layer "Edge.Cuts"))
  (gr_line (start 107.9 147.6) (end 107.9 150)
    (stroke (width 0.12) (type solid)) (layer "Edge.Cuts"))
  (gr_arc (start 170.85 146.4) (mid 171.733883 146.766117) (end 172.1 147.65)
    (stroke (width 0.12) (type solid)) (layer "Edge.Cuts"))
  (gr_line (start 172.1 150) (end 172.1 147.65)
    (stroke (width 0.12) (type solid)) (layer "Edge.Cuts"))
  (gr_line (start 124.5 146.15) (end 124.25 146.4)
    (stroke (width 0.12) (type solid)) (layer "Edge.Cuts"))
  (gr_line (start 124.5 138.9) (end 124.5 146.15)
    (stroke (width 0.12) (type solid)) (layer "Edge.Cuts"))
  (gr_line (start 190 150) (end 172.1 150)
    (stroke (width 0.12) (type solid)) (layer "Edge.Cuts"))
  (gr_arc (start 107.9 147.6) (mid 108.269078 146.733415) (end 109.15 146.4)
    (stroke (width 0.12) (type solid)) (layer "Edge.Cuts"))
  (gr_line (start 125.85 146.4) (end 125.6 146.15)
    (stroke (width 0.12) (type solid)) (layer "Edge.Cuts"))
  (gr_line (start 190 150) (end 190 50)
    (stroke (width 0.12) (type solid)) (layer "Edge.Cuts"))
  (gr_arc (start 124.5 138.9) (mid 125.05 138.35) (end 125.6 138.9)
    (stroke (width 0.12) (type solid)) (layer "Edge.Cuts"))
  (gr_line (start 100 150) (end 107.9 150)
    (stroke (width 0.12) (type solid)) (layer "Edge.Cuts"))
  (gr_line (start 124.25 146.4) (end 109.15 146.4)
    (stroke (width 0.12) (type solid)) (layer "Edge.Cuts"))
  (gr_line (start 125.6 146.15) (end 125.6 138.9)
    (stroke (width 0.12) (type solid)) (layer "Edge.Cuts"))

  (segment (start 165.75 96.985) (end 165.75 97.85) (width 0.25) (layer "F.Cu") (net 1))
  (segment (start 129.16 84.115) (end 129.22 84.055) (width 0.5) (layer "F.Cu") (net 1))
  (segment (start 177.8 86.5) (end 177.8 85.65) (width 0.25) (layer "F.Cu") (net 1))
  (segment (start 162.8 84.055) (end 160.91 84.055) (width 0.5) (layer "F.Cu") (net 1))
  (segment (start 145.8275 84.0825) (end 143.9875 84.0825) (width 0.5) (layer "F.Cu") (net 1))
  (segment (start 178.75 84.95) (end 178.75 85.365) (width 0.25) (layer "F.Cu") (net 1))
  (segment (start 173.195 101.335) (end 173.48 101.05) (width 0.25) (layer "F.Cu") (net 1))
  (segment (start 143.1075 84.0925) (end 143 84.2) (width 0.5) (layer "F.Cu") (net 1))
  (segment (start 180.65 98.25) (end 181.47 98.25) (width 0.25) (layer "F.Cu") (net 1))
  (segment (start 146.835 101.4) (end 146.75 101.485) (width 0.5) (layer "F.Cu") (net 1))
  (segment (start 154.375 102.1125) (end 154.375 103.975) (width 0.25) (layer "F.Cu") (net 1))
  (segment (start 174.785 101.485) (end 174.35 101.05) (width 0.4) (layer "F.Cu") (net 1))
  (segment (start 172.1 101.335) (end 173.195 101.335) (width 0.25) (layer "F.Cu") (net 1))
  (segment (start 181.47 98.25) (end 182.25 99.03) (width 0.25) (layer "F.Cu") (net 1))
  (segment (start 126.685 84.115) (end 126.6 84.2) (width 0.5) (layer "F.Cu") (net 1))
  (segment (start 165.1 101.32) (end 165.1 102.15) (width 0.25) (layer "F.Cu") (net 1))
  (segment (start 127.32 84.115) (end 129.16 84.115) (width 0.5) (layer "F.Cu") (net 1))
  (segment (start 178.2 84.75) (end 178.55 84.75) (width 0.25) (layer "F.Cu") (net 1))
  (segment (start 109 84) (end 109.035 83.965) (width 0.5) (layer "F.Cu") (net 1))
  (segment (start 111.9 83.955) (end 110.06 83.955) (width 0.5) (layer "F.Cu") (net 1))
  (segment (start 162.3 103.7) (end 161.4 104.6) (width 0.25) (layer "F.Cu") (net 1))
  (segment (start 180.73 93.6) (end 179.6 93.6) (width 0.25) (layer "F.Cu") (net 1))
  (segment (start 109.035 83.965) (end 110.05 83.965) (width 0.5) (layer "F.Cu") (net 1))
  (segment (start 126.4 84.2) (end 126.4 86.885) (width 0.5) (layer "F.Cu") (net 1))
  (segment (start 174.785 102.05) (end 174.785 103.84) (width 0.4) (layer "F.Cu") (net 1))
  (segment (start 177.8 85.65) (end 177.85 85.6) (width 0.25) (layer "F.Cu") (net 1))
  (segment (start 173.48 101.05) (end 174.1 101.05) (width 0.25) (layer "F.Cu") (net 1))
  (segment (start 154.375 103.975) (end 154.9 104.5) (width 0.25) (layer "F.Cu") (net 1))
  (segment (start 159.315 103.8) (end 158.3 103.8) (width 0.25) (layer "F.Cu") (net 1))
  (segment (start 148.4 103.8) (end 148.4 104.55) (width 0.5) (layer "F.Cu") (net 1))
  (segment (start 126.6 84.2) (end 126.4 84.2) (width 0.5) (layer "F.Cu") (net 1))
  (segment (start 174.35 101.05) (end 174.1 101.05) (width 0.4) (layer "F.Cu") (net 1))
  (segment (start 161.4 104.6) (end 161.4 104.7) (width 0.25) (layer "F.Cu") (net 1))
  (segment (start 165.635 101.335) (end 165.855 101.115) (width 0.25) (layer "F.Cu") (net 1))
  (segment (start 147.8 101.4) (end 146.835 101.4) (width 0.5) (layer "F.Cu") (net 1))
  (segment (start 96.7 102.7) (end 97.5 101.9) (width 0.5) (layer "F.Cu") (net 1))
  (segment (start 146.75 101.485) (end 145.75 101.485) (width 0.5) (layer "F.Cu") (net 1))
  (segment (start 127.32 84.115) (end 126.685 84.115) (width 0.5) (layer "F.Cu") (net 1))
  (segment (start 171.107 101.335) (end 172.1 101.335) (width 0.25) (layer "F.Cu") (net 1))
  (segment (start 102.05 133.65) (end 103.3 133.65) (width 0.25) (layer "F.Cu") (net 1))
  (segment (start 160.9 84.065) (end 160.135 84.065) (width 0.5) (layer "F.Cu") (net 1))
  (segment (start 96.3 102.7) (end 96.7 102.7) (width 0.5) (layer "F.Cu") (net 1))
  (segment (start 174.785 102.05) (end 174.785 101.485) (width 0.4) (layer "F.Cu") (net 1))
  (segment (start 162.275 102.12) (end 162.275 103.71) (width 0.2) (layer "F.Cu") (net 1))
  (segment (start 97.5 101.9) (end 97.5 101.6) (width 0.5) (layer "F.Cu") (net 1))
  (segment (start 154.6 101.75) (end 155.6 101.75) (width 0.25) (layer "F.Cu") (net 1))
  (segment (start 143.4075 84.0925) (end 143.9775 84.0925) (width 0.5) (layer "F.Cu") (net 1))
  (segment (start 143.4075 84.0925) (end 143.1075 84.0925) (width 0.5) (layer "F.Cu") (net 1))
  (segment (start 160 84.2) (end 160 86.985) (width 0.5) (layer "F.Cu") (net 1))
  (segment (start 109 84) (end 109 86.685) (width 0.6) (layer "F.Cu") (net 1))
  (segment (start 177.3 84.55) (end 177.3 84.0558) (width 0.25) (layer "F.Cu") (net 1))
  (segment (start 143 84.2) (end 143 86.985) (width 0.5) (layer "F.Cu") (net 1))
  (segment (start 177.85 85.6) (end 177.85 85.1) (width 0.25) (layer "F.Cu") (net 1))
  (segment (start 109 86.685) (end 109.115 86.8) (width 0.6) (layer "F.Cu") (net 1))
  (segment (start 154.375 101.975) (end 154.6 101.75) (width 0.25) (layer "F.Cu") (net 1))
  (segment (start 166.315 101.115) (end 165.855 101.115) (width 0.25) (layer "F.Cu") (net 1))
  (segment (start 165.1 101.335) (end 165.635 101.335) (width 0.25) (layer "F.Cu") (net 1))
  (segment (start 178.55 84.75) (end 178.75 84.95) (width 0.25) (layer "F.Cu") (net 1))
  (segment (start 163.9 98.55) (end 163.9 97.7) (width 0.25) (layer "F.Cu") (net 1))
  (segment (start 167.95 96.985) (end 167.95 97.85) (width 0.25) (layer "F.Cu") (net 1))
  (segment (start 160.135 84.065) (end 160 84.2) (width 0.5) (layer "F.Cu") (net 1))
  (segment (start 170.15 96.985) (end 170.15 97.85) (width 0.25) (layer "F.Cu") (net 1))
  (segment (start 177.85 85.1) (end 177.3 84.55) (width 0.25) (layer "F.Cu") (net 1))
  (segment (start 177.85 85.6) (end 177.335 85.6) (width 0.25) (layer "F.Cu") (net 1))
  (segment (start 177.85 85.1) (end 178.2 84.75) (width 0.25) (layer "F.Cu") (net 1))
  (segment (start 148.4 104.55) (end 148.9 105.05) (width 0.5) (layer "F.Cu") (net 1))
  (via (at 177.8 86.5) (size 0.8) (drill 0.4) (layers "F.Cu" "B.Cu") (net 1))
  (via (at 143 84.2) (size 0.8) (drill 0.4) (layers "F.Cu" "B.Cu") (net 1))
  (via (at 103.2 84.65) (size 0.8) (drill 0.4) (layers "F.Cu" "B.Cu") (free) (net 1))
  (via (at 158.3 103.8) (size 0.8) (drill 0.4) (layers "F.Cu" "B.Cu") (net 1))
  (via (at 154.9 104.5) (size 0.6) (drill 0.25) (layers "F.Cu" "B.Cu") (net 1))
  (via (at 170.15 97.85) (size 0.6) (drill 0.25) (layers "F.Cu" "B.Cu") (net 1))
  (via (at 101.2 85.6) (size 0.8) (drill 0.4) (layers "F.Cu" "B.Cu") (free) (net 1))
  (via (at 148.4 103.8) (size 0.8) (drill 0.4) (layers "F.Cu" "B.Cu") (net 1))
  (via (at 165.75 97.85) (size 0.6) (drill 0.25) (layers "F.Cu" "B.Cu") (net 1))
  (via (at 96.3 102.7) (size 0.8) (drill 0.4) (layers "F.Cu" "B.Cu") (net 1))
  (via (at 180.65 98.25) (size 0.6) (drill 0.25) (layers "F.Cu" "B.Cu") (net 1))
  (via (at 147.8 101.4) (size 0.8) (drill 0.4) (layers "F.Cu" "B.Cu") (net 1))
  (via (at 101.9 86.6) (size 0.8) (drill 0.4) (layers "F.Cu" "B.Cu") (free) (net 1))
  (via (at 102.45 83.55) (size 0.8) (drill 0.4) (layers "F.Cu" "B.Cu") (free) (net 1))
  (via (at 165.1 102.15) (size 0.6) (drill 0.25) (layers "F.Cu" "B.Cu") (net 1))
  (via (at 160 84.2) (size 0.8) (drill 0.4) (layers "F.Cu" "B.Cu") (net 1))
  (via (at 179.85 93.45) (size 0.8) (drill 0.4) (layers "F.Cu" "B.Cu") (net 1))
  (via (at 102 84.55) (size 0.8) (drill 0.4) (layers "F.Cu" "B.Cu") (free) (net 1))
  (via (at 101.05 84.4) (size 0.8) (drill 0.4) (layers "F.Cu" "B.Cu") (free) (net 1))
  (via (at 161.4 104.7) (size 0.6) (drill 0.25) (layers "F.Cu" "B.Cu") (net 1))
  (via (at 167.95 97.85) (size 0.6) (drill 0.25) (layers "F.Cu" "B.Cu") (net 1))
  (via (at 103.25 86.4) (size 0.8) (drill 0.4) (layers "F.Cu" "B.Cu") (free) (net 1))
  (via (at 102.35 85.55) (size 0.8) (drill 0.4) (layers "F.Cu" "B.Cu") (free) (net 1))
  (via (at 174.1 101.05) (size 0.6) (drill 0.25) (layers "F.Cu" "B.Cu") (net 1))
  (via (at 126.4 84.2) (size 0.8) (drill 0.4) (layers "F.Cu" "B.Cu") (net 1))
  (via (at 101.25 83.35) (size 0.8) (drill 0.4) (layers "F.Cu" "B.Cu") (free) (net 1))
  (via (at 109 84) (size 0.8) (drill 0.4) (layers "F.Cu" "B.Cu") (net 1))
  (via (at 103.3 133.65) (size 0.6) (drill 0.25) (layers "F.Cu" "B.Cu") (net 1))
  (via (at 163.9 97.7) (size 0.6) (drill 0.25) (layers "F.Cu" "B.Cu") (net 1))
  (segment (start 103.3 133.5) (end 101.1 131.3) (width 0.5) (layer "In2.Cu") (net 1))
  (segment (start 97.7 131.3) (end 96.3 129.9) (width 0.5) (layer "In2.Cu") (net 1))
  (segment (start 96.3 102.7) (end 96.3 100.7) (width 0.5) (layer "In2.Cu") (net 1))
  (segment (start 100.2 96.8) (end 102.3 96.8) (width 0.5) (layer "In2.Cu") (net 1))
  (segment (start 109.2 86.8) (end 110.2 86.8) (width 0.5) (layer "In2.Cu") (net 1))
  (segment (start 103.3 133.65) (end 103.3 133.5) (width 0.5) (layer "In2.Cu") (net 1))
  (segment (start 108.8 87.2) (end 109.2 86.8) (width 0.5) (layer "In2.Cu") (net 1))
  (segment (start 96.3 100.7) (end 100.2 96.8) (width 0.5) (layer "In2.Cu") (net 1))
  (segment (start 102.3 96.8) (end 108.8 90.3) (width 0.5) (layer "In2.Cu") (net 1))
  (segment (start 101.1 131.3) (end 97.7 131.3) (width 0.5) (layer "In2.Cu") (net 1))
  (segment (start 108.8 90.3) (end 108.8 87.2) (width 0.5) (layer "In2.Cu") (net 1))
  (segment (start 96.3 129.9) (end 96.3 102.7) (width 0.5) (layer "In2.Cu") (net 1))
  (segment (start 99.6 85.8) (end 102.35 88.55) (width 0.25) (layer "F.Cu") (net 2))
  (segment (start 97 85.8) (end 99.6 85.8) (width 0.25) (layer "F.Cu") (net 2))
  (segment (start 103 91.4) (end 102.58 90.98) (width 0.25) (layer "F.Cu") (net 2))
  (segment (start 96.8 86) (end 96.8 86.85) (width 0.25) (layer "F.Cu") (net 2))
  (segment (start 98.5 95.75) (end 99.65 94.6) (width 0.25) (layer "F.Cu") (net 2))
  (segment (start 97.5 99) (end 98 99) (width 0.25) (layer "F.Cu") (net 2))
  (segment (start 97 85.8) (end 96.8 86) (width 0.25) (layer "F.Cu") (net 2))
  (segment (start 103 93.2) (end 103 91.4) (width 0.25) (layer "F.Cu") (net 2))
  (segment (start 99.65 94.6) (end 99.8 94.6) (width 0.25) (layer "F.Cu") (net 2))
  (segment (start 98.5 98.5) (end 98.5 95.75) (width 0.25) (layer "F.Cu") (net 2))
  (segment (start 100.148 85.252) (end 100.148 83.052) (width 0.25) (layer "F.Cu") (net 2))
  (segment (start 104.84 82.3) (end 105.85 81.29) (width 0.25) (layer "F.Cu") (net 2))
  (segment (start 99.8 94.6) (end 101.6 94.6) (width 0.25) (layer "F.Cu") (net 2))
  (segment (start 102.58 90.98) (end 102.35 90.98) (width 0.25) (layer "F.Cu") (net 2))
  (segment (start 100.9 82.3) (end 104.84 82.3) (width 0.25) (layer "F.Cu") (net 2))
  (segment (start 98 99) (end 98.5 98.5) (width 0.25) (layer "F.Cu") (net 2))
  (segment (start 100.148 83.052) (end 100.9 82.3) (width 0.25) (layer "F.Cu") (net 2))
  (segment (start 102.35 88.55) (end 102.35 90.98) (width 0.25) (layer "F.Cu") (net 2))
  (segment (start 101.6 94.6) (end 103 93.2) (width 0.25) (layer "F.Cu") (net 2))
  (segment (start 99.6 85.8) (end 100.148 85.252) (width 0.25) (layer "F.Cu") (net 2))
  (segment (start 159.973 51.277) (end 160.1 51.15) (width 1) (layer "In2.Cu") (net 2))
  (segment (start 159.98 54) (end 159.973 53.993) (width 1) (layer "In2.Cu") (net 2))
  (segment (start 91.05 60.5) (end 93.6 57.95) (width 1) (layer "In2.Cu") (net 2))
  (segment (start 108.4 51.15) (end 125 51.15) (width 1) (layer "In2.Cu") (net 2))
  (segment (start 176.73 51.827602) (end 176.052398 51.15) (width 1) (layer "In2.Cu") (net 2))
  (segment (start 107.48 54.2) (end 107.48 52.07) (width 1) (layer "In2.Cu") (net 2))
  (segment (start 125 51.15) (end 142.8 51.15) (width 1) (layer "In2.Cu") (net 2))
  (segment (start 160.1 51.15) (end 176.052398 51.15) (width 1) (layer "In2.Cu") (net 2))
  (segment (start 142.43 53.75) (end 142.43 51.52) (width 1) (layer "In2.Cu") (net 2))
  (segment (start 91.05 67.3) (end 91.05 60.5) (width 1) (layer "In2.Cu") (net 2))
  (segment (start 94.25 70.5) (end 91.05 67.3) (width 1) (layer "In2.Cu") (net 2))
  (segment (start 124.98 51.17) (end 124.98 53.85) (width 1) (layer "In2.Cu") (net 2))
  (segment (start 103.73 57.95) (end 107.53 54.15) (width 1) (layer "In2.Cu") (net 2))
  (segment (start 125 51.15) (end 124.98 51.17) (width 1) (layer "In2.Cu") (net 2))
  (segment (start 176.73 54) (end 176.73 51.827602) (width 1) (layer "In2.Cu") (net 2))
  (segment (start 159.973 53.993) (end 159.973 51.277) (width 1) (layer "In2.Cu") (net 2))
  (segment (start 93.6 57.95) (end 103.73 57.95) (width 1) (layer "In2.Cu") (net 2))
  (segment (start 142.8 51.15) (end 160.1 51.15) (width 1) (layer "In2.Cu") (net 2))
  (segment (start 142.43 51.52) (end 142.8 51.15) (width 1) (layer "In2.Cu") (net 2))
  (segment (start 107.48 52.07) (end 108.4 51.15) (width 1) (layer "In2.Cu") (net 2))
  (segment (start 183.2 117.45) (end 183.2 119.3) (width 0.325) (layer "F.Cu") (net 3))
  (segment (start 183.2 117.45) (end 181.685 117.45) (width 0.325) (layer "F.Cu") (net 3))
  (segment (start 186 120.875) (end 186 121.775) (width 0.25) (layer "F.Cu") (net 3))
  (segment (start 187.55 121.825) (end 185.95 121.825) (width 0.25) (layer "F.Cu") (net 3))
  (segment (start 183.2 116.75) (end 183.2 117.45) (width 0.325) (layer "F.Cu") (net 3))
  (segment (start 184.1 120.2) (end 184.1 120.875) (width 0.325) (layer "F.Cu") (net 3))
  (segment (start 184.225 121.825) (end 185.95 121.825) (width 0.25) (layer "F.Cu") (net 3))
  (segment (start 183.2 119.3) (end 184.1 120.2) (width 0.325) (layer "F.Cu") (net 3))
  (segment (start 186 121.775) (end 185.95 121.825) (width 0.25) (layer "F.Cu") (net 3))
  (segment (start 184.1 121.7) (end 184.225 121.825) (width 0.25) (layer "F.Cu") (net 3))
  (segment (start 184.1 120.875) (end 184.1 121.7) (width 0.25) (layer "F.Cu") (net 3))
  (segment (start 149.825 103.325) (end 149.5 103.65) (width 0.2) (layer "F.Cu") (net 4))
  (segment (start 143.9775 85.0625) (end 143.9775 85.9275) (width 0.25) (layer "F.Cu") (net 4))
  (segment (start 129.22 81.515) (end 129.22 80.245) (width 0.25) (layer "F.Cu") (net 4))
  (segment (start 129.22 80.245) (end 127.465 80.245) (width 0.25) (layer "F.Cu") (net 4))
  (segment (start 150.95 100.775) (end 151.125 100.95) (width 0.2) (layer "F.Cu") (net 4))
  (segment (start 101.25 93.65) (end 101.2 93.7) (width 0.5) (layer "F.Cu") (net 4))
  (segment (start 145.8275 81.5425) (end 145.8275 80.2725) (width 0.2) (layer "F.Cu") (net 4))
  (segment (start 180.55 95.25) (end 180.4 95.4) (width 0.2) (layer "F.Cu") (net 4))
  (segment (start 110.05 84.935) (end 110.05 85.85) (width 0.25) (layer "F.Cu") (net 4))
  (segment (start 111.9 81.415) (end 111.9 80.145) (width 0.25) (layer "F.Cu") (net 4))
  (segment (start 149.825 102.1125) (end 149.825 100.975) (width 0.2) (layer "F.Cu") (net 4))
  (segment (start 127.32 85.085) (end 127.32 85.78) (width 0.5) (layer "F.Cu") (net 4))
  (segment (start 145.8275 80.2725) (end 144.1225 80.2725) (width 0.25) (layer "F.Cu") (net 4))
  (segment (start 110.35 87.75) (end 110.2 87.9) (width 0.25) (layer "F.Cu") (net 4))
  (segment (start 181.13 95.25) (end 180.55 95.25) (width 0.2) (layer "F.Cu") (net 4))
  (segment (start 149.825 100.975) (end 150.025 100.775) (width 0.2) (layer "F.Cu") (net 4))
  (segment (start 127.465 80.245) (end 127.42 80.2) (width 0.25) (layer "F.Cu") (net 4))
  (segment (start 162.8 80.245) (end 160.955 80.245) (width 0.25) (layer "F.Cu") (net 4))
  (segment (start 160.9 85.75) (end 160.9 85.035) (width 0.25) (layer "F.Cu") (net 4))
  (segment (start 176.4 85.635) (end 176.365 85.6) (width 0.6) (layer "F.Cu") (net 4))
  (segment (start 110.195 80.145) (end 110.15 80.1) (width 0.25) (layer "F.Cu") (net 4))
  (segment (start 127.32 85.78) (end 127.3 85.8) (width 0.5) (layer "F.Cu") (net 4))
  (segment (start 101.25 92.935) (end 101.25 93.65) (width 0.5) (layer "F.Cu") (net 4))
  (segment (start 99.45 93.7) (end 100.2 93.7) (width 0.5) (layer "F.Cu") (net 4))
  (segment (start 176.4 86.6) (end 176.4 85.635) (width 0.6) (layer "F.Cu") (net 4))
  (segment (start 151.125 100.95) (end 151.125 102.1125) (width 0.2) (layer "F.Cu") (net 4))
  (segment (start 150.025 100.775) (end 150.95 100.775) (width 0.2) (layer "F.Cu") (net 4))
  (segment (start 162.8 81.515) (end 162.8 80.245) (width 0.25) (layer "F.Cu") (net 4))
  (segment (start 177.3 81.5008) (end 177.3 80.2458) (width 0.25) (layer "F.Cu") (net 4))
  (segment (start 111.9 80.145) (end 110.195 80.145) (width 0.25) (layer "F.Cu") (net 4))
  (segment (start 149.825 102.1125) (end 149.825 103.325) (width 0.2) (layer "F.Cu") (net 4))
  (segment (start 144.1225 80.2725) (end 144.0775 80.2275) (width 0.25) (layer "F.Cu") (net 4))
  (segment (start 111.45 87.75) (end 110.35 87.75) (width 0.25) (layer "F.Cu") (net 4))
  (via (at 138.4 134.8) (size 0.8) (drill 0.4) (layers "F.Cu" "B.Cu") (net 4))
  (via (at 149.6 134.8) (size 0.8) (drill 0.4) (layers "F.Cu" "B.Cu") (net 4))
  (via (at 133.6 132.4) (size 0.8) (drill 0.4) (layers "F.Cu" "B.Cu") (net 4))
  (via (at 136.8 132.4) (size 0.8) (drill 0.4) (layers "F.Cu" "B.Cu") (net 4))
  (via (at 134.4 131.2) (size 0.8) (drill 0.4) (layers "F.Cu" "B.Cu") (net 4))
  (via (at 148 134.8) (size 0.8) (drill 0.4) (layers "F.Cu" "B.Cu") (net 4))
  (via (at 141.6 132.4) (size 0.8) (drill 0.4) (layers "F.Cu" "B.Cu") (net 4))
  (via (at 147.2 131.2) (size 0.8) (drill 0.4) (layers "F.Cu" "B.Cu") (net 4))
  (via (at 144.8 132.4) (size 0.8) (drill 0.4) (layers "F.Cu" "B.Cu") (net 4))
  (via (at 145.6 133.6) (size 0.8) (drill 0.4) (layers "F.Cu" "B.Cu") (net 4))
  (via (at 142.4 133.6) (size 0.8) (drill 0.4) (layers "F.Cu" "B.Cu") (net 4))
  (via (at 146.4 132.4) (size 0.8) (drill 0.4) (layers "F.Cu" "B.Cu") (net 4))
  (via (at 148.8 131.2) (size 0.8) (drill 0.4) (layers "F.Cu" "B.Cu") (net 4))
  (via (at 135.2 132.4) (size 0.8) (drill 0.4) (layers "F.Cu" "B.Cu") (net 4))
  (via (at 146.4 134.8) (size 0.8) (drill 0.4) (layers "F.Cu" "B.Cu") (net 4))
  (via (at 149.6 132.4) (size 0.8) (drill 0.4) (layers "F.Cu" "B.Cu") (net 4))
  (via (at 137.6 133.6) (size 0.8) (drill 0.4) (layers "F.Cu" "B.Cu") (net 4))
  (via (at 142.4 131.2) (size 0.8) (drill 0.4) (layers "F.Cu" "B.Cu") (net 4))
  (via (at 145.6 131.2) (size 0.8) (drill 0.4) (layers "F.Cu" "B.Cu") (net 4))
  (via (at 136 131.2) (size 0.8) (drill 0.4) (layers "F.Cu" "B.Cu") (net 4))
  (via (at 139.2 131.2) (size 0.8) (drill 0.4) (layers "F.Cu" "B.Cu") (net 4))
  (via (at 137.6 131.2) (size 0.8) (drill 0.4) (layers "F.Cu" "B.Cu") (net 4))
  (via (at 140.8 131.2) (size 0.8) (drill 0.4) (layers "F.Cu" "B.Cu") (net 4))
  (via (at 139.2 133.6) (size 0.8) (drill 0.4) (layers "F.Cu" "B.Cu") (net 4))
  (via (at 144 133.6) (size 0.8) (drill 0.4) (layers "F.Cu" "B.Cu") (net 4))
  (via (at 143.2 132.4) (size 0.8) (drill 0.4) (layers "F.Cu" "B.Cu") (net 4))
  (via (at 148 132.4) (size 0.8) (drill 0.4) (layers "F.Cu" "B.Cu") (net 4))
  (via (at 132.8 133.6) (size 0.8) (drill 0.4) (layers "F.Cu" "B.Cu") (net 4))
  (via (at 140.8 133.6) (size 0.8) (drill 0.4) (layers "F.Cu" "B.Cu") (net 4))
  (via (at 148.8 133.6) (size 0.8) (drill 0.4) (layers "F.Cu" "B.Cu") (net 4))
  (via (at 136.8 134.8) (size 0.8) (drill 0.4) (layers "F.Cu" "B.Cu") (net 4))
  (via (at 138.4 132.4) (size 0.8) (drill 0.4) (layers "F.Cu" "B.Cu") (net 4))
  (via (at 136 133.6) (size 0.8) (drill 0.4) (layers "F.Cu" "B.Cu") (net 4))
  (via (at 143.2 134.8) (size 0.8) (drill 0.4) (layers "F.Cu" "B.Cu") (net 4))
  (via (at 133.6 134.8) (size 0.8) (drill 0.4) (layers "F.Cu" "B.Cu") (net 4))
  (via (at 132 134.8) (size 0.8) (drill 0.4) (layers "F.Cu" "B.Cu") (net 4))
  (via (at 144 131.2) (size 0.8) (drill 0.4) (layers "F.Cu" "B.Cu") (net 4))
  (via (at 134.4 133.6) (size 0.8) (drill 0.4) (layers "F.Cu" "B.Cu") (net 4))
  (via (at 132.8 131.2) (size 0.8) (drill 0.4) (layers "F.Cu" "B.Cu") (net 4))
  (via (at 140 134.8) (size 0.8) (drill 0.4) (layers "F.Cu" "B.Cu") (net 4))
  (via (at 144.8 134.8) (size 0.8) (drill 0.4) (layers "F.Cu" "B.Cu") (net 4))
  (via (at 147.2 133.6) (size 0.8) (drill 0.4) (layers "F.Cu" "B.Cu") (net 4))
  (via (at 141.6 134.8) (size 0.8) (drill 0.4) (layers "F.Cu" "B.Cu") (net 4))
  (via (at 140 132.4) (size 0.8) (drill 0.4) (layers "F.Cu" "B.Cu") (net 4))
  (via (at 135.2 134.8) (size 0.8) (drill 0.4) (layers "F.Cu" "B.Cu") (net 4))
  (via (at 132 132.4) (size 0.8) (drill 0.4) (layers "F.Cu" "B.Cu") (net 4))
  (via (at 118.3 126.3) (size 0.8) (drill 0.4) (layers "F.Cu" "B.Cu") (net 4))
  (via (at 134.5 101.75) (size 0.8) (drill 0.4) (layers "F.Cu" "B.Cu") (net 4))
  (via (at 109.393695 127.3846) (size 0.8) (drill 0.4) (layers "F.Cu" "B.Cu") (net 4))
  (via (at 138.799695 122.8496) (size 0.8) (drill 0.4) (layers "F.Cu" "B.Cu") (net 4))
  (via (at 165.142 103.7) (size 0.8) (drill 0.4) (layers "F.Cu" "B.Cu") (net 4))
  (via (at 153.5 52.55) (size 0.8) (drill 0.4) (layers "F.Cu" "B.Cu") (free) (net 4))
  (via (at 124.9 136.1) (size 0.8) (drill 0.4) (layers "F.Cu" "B.Cu") (net 4))
  (via (at 158 59) (size 0.8) (drill 0.4) (layers "F.Cu" "B.Cu") (free) (net 4))
  (via (at 127.8 90.4) (size 0.8) (drill 0.4) (layers "F.Cu" "B.Cu") (free) (net 4))
  (via (at 160 67.5) (size 0.8) (drill 0.4) (layers "F.Cu" "B.Cu") (free) (net 4))
  (via (at 125 67.5) (size 0.8) (drill 0.4) (layers "F.Cu" "B.Cu") (free) (net 4))
  (via (at 131.6 108.708) (size 0.8) (drill 0.4) (layers "F.Cu" "B.Cu") (net 4))
  (via (at 123 66.5) (size 0.8) (drill 0.4) (layers "F.Cu" "B.Cu") (free) (net 4))
  (via (at 127.933695 112.525) (size 0.8) (drill 0.4) (layers "F.Cu" "B.Cu") (net 4))
  (via (at 175 73.5) (size 0.8) (drill 0.4) (layers "F.Cu" "B.Cu") (free) (net 4))
  (via (at 98.269695 141.2896) (size 0.8) (drill 0.4) (layers "F.Cu" "B.Cu") (net 4))
  (via (at 162.8 56.7) (size 0.8) (drill 0.4) (layers "F.Cu" "B.Cu") (free) (net 4))
  (via (at 107.5 65) (size 0.8) (drill 0.4) (layers "F.Cu" "B.Cu") (free) (net 4))
  (via (at 135.2 112) (size 0.8) (drill 0.4) (layers "F.Cu" "B.Cu") (net 4))
  (via (at 124.216 99.092) (size 0.8) (drill 0.4) (layers "F.Cu" "B.Cu") (free) (net 4))
  (via (at 116.809695 105.1366) (size 0.8) (drill 0.4) (layers "F.Cu" "B.Cu") (net 4))
  (via (at 123 64) (size 0.8) (drill 0.4) (layers "F.Cu" "B.Cu") (free) (net 4))
  (via (at 160 72.5) (size 0.8) (drill 0.4) (layers "F.Cu" "B.Cu") (free) (net 4))
  (via (at 156.65 103.725) (size 0.8) (drill 0.4) (layers "F.Cu" "B.Cu") (net 4))
  (via (at 170 58) (size 0.8) (drill 0.4) (layers "F.Cu" "B.Cu") (free) (net 4))
  (via (at 99.2 86.6) (size 0.8) (drill 0.4) (layers "F.Cu" "B.Cu") (free) (net 4))
  (via (at 135.349695 115.3336) (size 0.8) (drill 0.4) (layers "F.Cu" "B.Cu") (net 4))
  (via (at 177.5 72.5) (size 0.8) (drill 0.4) (layers "F.Cu" "B.Cu") (free) (net 4))
  (via (at 122 93.5) (size 0.8) (drill 0.4) (layers "F.Cu" "B.Cu") (free) (net 4))
  (via (at 125.5 93.5) (size 0.8) (drill 0.4) (layers "F.Cu" "B.Cu") (free) (net 4))
  (via (at 94.561695 119.0416) (size 0.8) (drill 0.4) (layers "F.Cu" "B.Cu") (net 4))
  (via (at 176.57 101.12) (size 0.6) (drill 0.25) (layers "F.Cu" "B.Cu") (net 4))
  (via (at 135.349695 119.0416) (size 0.8) (drill 0.4) (layers "F.Cu" "B.Cu") (net 4))
  (via (at 110.2 87.9) (size 0.8) (drill 0.4) (layers "F.Cu" "B.Cu") (net 4))
  (via (at 132.45 57.9) (size 0.8) (drill 0.4) (layers "F.Cu" "B.Cu") (free) (net 4))
  (via (at 173 97) (size 0.8) (drill 0.4) (layers "F.Cu" "B.Cu") (net 4))
  (via (at 131.5 96.5) (size 0.8) (drill 0.4) (layers "F.Cu" "B.Cu") (free) (net 4))
  (via (at 90.853695 116.2606) (size 0.8) (drill 0.4) (layers "F.Cu" "B.Cu") (net 4))
  (via (at 179.65 104.35) (size 0.6) (drill 0.25) (layers "F.Cu" "B.Cu") (net 4))
  (via (at 141 71.5) (size 0.8) (drill 0.4) (layers "F.Cu" "B.Cu") (free) (net 4))
  (via (at 172.429695 130.1656) (size 0.8) (drill 0.4) (layers "F.Cu" "B.Cu") (net 4))
  (via (at 106.1 66.2) (size 0.8) (drill 0.4) (layers "F.Cu" "B.Cu") (free) (net 4))
  (via (at 158 71.5) (size 0.8) (drill 0.4) (layers "F.Cu" "B.Cu") (free) (net 4))
  (via (at 143.95 52.45) (size 0.8) (drill 0.4) (layers "F.Cu" "B.Cu") (free) (net 4))
  (via (at 142.5 62.5) (size 0.8) (drill 0.4) (layers "F.Cu" "B.Cu") (free) (net 4))
  (via (at 107.8 126) (size 0.8) (drill 0.4) (layers "F.Cu" "B.Cu") (net 4))
  (via (at 131.6 105) (size 0.8) (drill 0.4) (layers "F.Cu" "B.Cu") (net 4))
  (via (at 141 76.5) (size 0.8) (drill 0.4) (layers "F.Cu" "B.Cu") (free) (net 4))
  (via (at 94.561695 115.9) (size 0.8) (drill 0.4) (layers "F.Cu" "B.Cu") (net 4))
  (via (at 124.2 75) (size 0.8) (drill 0.4) (layers "F.Cu" "B.Cu") (free) (net 4))
  (via (at 91 101.8) (size 0.8) (drill 0.4) (layers "F.Cu" "B.Cu") (net 4))
  (via (at 104.4 117.6) (size 0.8) (drill 0.4) (layers "F.Cu" "B.Cu") (net 4))
  (via (at 116.8 102.8) (size 0.8) (drill 0.4) (layers "F.Cu" "B.Cu") (net 4))
  (via (at 131 52.55) (size 0.8) (drill 0.4) (layers "F.Cu" "B.Cu") (free) (net 4))
  (via (at 143.05 115.2) (size 0.8) (drill 0.4) (layers "F.Cu" "B.Cu") (net 4))
  (via (at 189.115695 103.2826) (size 0.8) (drill 0.4) (layers "F.Cu" "B.Cu") (net 4))
  (via (at 167.85 52.45) (size 0.8) (drill 0.4) (layers "F.Cu" "B.Cu") (free) (net 4))
  (via (at 109.393695 112.5526) (size 0.8) (drill 0.4) (layers "F.Cu" "B.Cu") (net 4))
  (via (at 179.845695 140.3626) (size 0.8) (drill 0.4) (layers "F.Cu" "B.Cu") (net 4))
  (via (at 175 68.5) (size 0.8) (drill 0.4) (layers "F.Cu" "B.Cu") (free) (net 4))
  (via (at 114 96.5) (size 0.8) (drill 0.4) (layers "F.Cu" "B.Cu") (free) (net 4))
  (via (at 141.6 101.6) (size 0.8) (drill 0.4) (layers "F.Cu" "B.Cu") (free) (net 4))
  (via (at 131.641695 126.4576) (size 0.8) (drill 0.4) (layers "F.Cu" "B.Cu") (net 4))
  (via (at 161.35 52.45) (size 0.8) (drill 0.4) (layers "F.Cu" "B.Cu") (free) (net 4))
  (via (at 103.8 126) (size 0.8) (drill 0.4) (layers "F.Cu" "B.Cu") (net 4))
  (via (at 116.809695 112.5526) (size 0.8) (drill 0.4) (layers "F.Cu" "B.Cu") (net 4))
  (via (at 124.225695 122.7496) (size 0.8) (drill 0.4) (layers "F.Cu" "B.Cu") (net 4))
  (via (at 160.9 85.75) (size 0.6) (drill 0.25) (layers "F.Cu" "B.Cu") (net 4))
  (via (at 120.517695 112.5526) (size 0.8) (drill 0.4) (layers "F.Cu" "B.Cu") (net 4))
  (via (at 139.2 108.708) (size 0.8) (drill 0.4) (layers "F.Cu" "B.Cu") (net 4))
  (via (at 185.5 96.45) (size 0.8) (drill 0.4) (layers "F.Cu" "B.Cu") (net 4))
  (via (at 124.225695 119.0416) (size 0.8) (drill 0.4) (layers "F.Cu" "B.Cu") (net 4))
  (via (at 127.5 57.75) (size 0.8) (drill 0.4) (layers "F.Cu" "B.Cu") (free) (net 4))
  (via (at 120.517695 116.2606) (size 0.8) (drill 0.4) (layers "F.Cu" "B.Cu") (net 4))
  (via (at 118 96.5) (size 0.8) (drill 0.4) (layers "F.Cu" "B.Cu") (free) (net 4))
  (via (at 120.4 119.9) (size 0.8) (drill 0.4) (layers "F.Cu" "B.Cu") (net 4))
  (via (at 97.95 102.95) (size 0.8) (drill 0.4) (layers "F.Cu" "B.Cu") (net 4))
  (via (at 100.2 93.7) (size 0.6) (drill 0.25) (layers "F.Cu" "B.Cu") (net 4))
  (via (at 97.65 106.8) (size 0.8) (drill 0.4) (layers "F.Cu" "B.Cu") (net 4))
  (via (at 141 69) (size 0.8) (drill 0.4) (layers "F.Cu" "B.Cu") (free) (net 4))
  (via (at 120 58) (size 0.8) (drill 0.4) (layers "F.Cu" "B.Cu") (free) (net 4))
  (via (at 135.95 52.2) (size 0.8) (drill 0.4) (layers "F.Cu" "B.Cu") (free) (net 4))
  (via (at 119.4 122.2) (size 0.8) (drill 0.4) (layers "F.Cu" "B.Cu") (net 4))
  (via (at 166.2 58.05) (size 0.8) (drill 0.4) (layers "F.Cu" "B.Cu") (free) (net 4))
  (via (at 187.261695 136.6546) (size 0.8) (drill 0.4) (layers "F.Cu" "B.Cu") (net 4))
  (via (at 90.853695 148.7056) (size 0.8) (drill 0.4) (layers "F.Cu" "B.Cu") (net 4))
  (via (at 124.225695 112.5526) (size 0.8) (drill 0.4) (layers "F.Cu" "B.Cu") (net 4))
  (via (at 187.261695 132.9466) (size 0.8) (drill 0.4) (layers "F.Cu" "B.Cu") (net 4))
  (via (at 163.5 52.55) (size 0.8) (drill 0.4) (layers "F.Cu" "B.Cu") (free) (net 4))
  (via (at 168.75 55.85) (size 0.8) (drill 0.4) (layers "F.Cu" "B.Cu") (free) (net 4))
  (via (at 105.685695 112.5526) (size 0.8) (drill 0.4) (layers "F.Cu" "B.Cu") (net 4))
  (via (at 160 70) (size 0.8) (drill 0.4) (layers "F.Cu" "B.Cu") (free) (net 4))
  (via (at 158.5 52.55) (size 0.8) (drill 0.4) (layers "F.Cu" "B.Cu") (free) (net 4))
  (via (at 158 69) (size 0.8) (drill 0.4) (layers "F.Cu" "B.Cu") (free) (net 4))
  (via (at 143 90.55) (size 0.8) (drill 0.4) (layers "F.Cu" "B.Cu") (free) (net 4))
  (via (at 160.955 80.245) (size 0.6) (drill 0.25) (layers "F.Cu" "B.Cu") (net 4))
  (via (at 172.65 103.7) (size 0.8) (drill 0.4) (layers "F.Cu" "B.Cu") (net 4))
  (via (at 135.308 105) (size 0.8) (drill 0.4) (layers "F.Cu" "B.Cu") (net 4))
  (via (at 177.5 67.5) (size 0.8) (drill 0.4) (layers "F.Cu" "B.Cu") (free) (net 4))
  (via (at 143.25 126.35) (size 0.8) (drill 0.4) (layers "F.Cu" "B.Cu") (net 4))
  (via (at 148.55 56) (size 0.8) (drill 0.4) (layers "F.Cu" "B.Cu") (free) (net 4))
  (via (at 124.225695 126.4576) (size 0.8) (drill 0.4) (layers "F.Cu" "B.Cu") (net 4))
  (via (at 127.8 99.8) (size 0.8) (drill 0.4) (layers "F.Cu" "B.Cu") (free) (net 4))
  (via (at 106.297132 103.276324) (size 0.8) (drill 0.4) (layers "F.Cu" "B.Cu") (free) (net 4))
  (via (at 107.5 60) (size 0.8) (drill 0.4) (layers "F.Cu" "B.Cu") (free) (net 4))
  (via (at 93.4 90) (size 0.8) (drill 0.4) (layers "F.Cu" "B.Cu") (free) (net 4))
  (via (at 103 108) (size 0.8) (drill 0.4) (layers "F.Cu" "B.Cu") (free) (net 4))
  (via (at 127.933695 120.8956) (size 0.8) (drill 0.4) (layers "F.Cu" "B.Cu") (net 4))
  (via (at 99.2 87.6) (size 0.8) (drill 0.4) (layers "F.Cu" "B.Cu") (free) (net 4))
  (via (at 148.5 52.55) (size 0.8) (drill 0.4) (layers "F.Cu" "B.Cu") (free) (net 4))
  (via (at 122.85 133.35) (size 0.6) (drill 0.25) (layers "F.Cu" "B.Cu") (free) (net 4))
  (via (at 177.5 62.5) (size 0.8) (drill 0.4) (layers "F.Cu" "B.Cu") (free) (net 4))
  (via (at 177.5 65) (size 0.8) (drill 0.4) (layers "F.Cu" "B.Cu") (free) (net 4))
  (via (at 143 112) (size 0.8) (drill 0.4) (layers "F.Cu" "B.Cu") (net 4))
  (via (at 122 96.5) (size 0.8) (drill 0.4) (layers "F.Cu" "B.Cu") (free) (net 4))
  (via (at 129 93.5) (size 0.8) (drill 0.4) (layers "F.Cu" "B.Cu") (free) (net 4))
  (via (at 176.137695 137.5816) (size 0.8) (drill 0.4) (layers "F.Cu" "B.Cu") (net 4))
  (via (at 168.85 103.7) (size 0.8) (drill 0.4) (layers "F.Cu" "B.Cu") (net 4))
  (via (at 100.123695 132.9466) (size 0.8) (drill 0.4) (layers "F.Cu" "B.Cu") (net 4))
  (via (at 178.5 52.55) (size 0.8) (drill 0.4) (layers "F.Cu" "B.Cu") (free) (net 4))
  (via (at 98.269695 125.5306) (size 0.8) (drill 0.4) (layers "F.Cu" "B.Cu") (net 4))
  (via (at 123 61.5) (size 0.8) (drill 0.4) (layers "F.Cu" "B.Cu") (free) (net 4))
  (via (at 166 52.55) (size 0.8) (drill 0.4) (layers "F.Cu" "B.Cu") (free) (net 4))
  (via (at 176.4 86.6) (size 0.8) (drill 0.4) (layers "F.Cu" "B.Cu") (free) (net 4))
  (via (at 189.115695 99.5746) (size 0.8) (drill 0.4) (layers "F.Cu" "B.Cu") (net 4))
  (via (at 101.597132 98.076324) (size 0.8) (drill 0.4) (layers "F.Cu" "B.Cu") (free) (net 4))
  (via (at 94.708 105.492) (size 0.8) (drill 0.4) (layers "F.Cu" "B.Cu") (net 4))
  (via (at 127.3 85.8) (size 0.6) (drill 0.25) (layers "F.Cu" "B.Cu") (net 4))
  (via (at 94.708 109.2) (size 0.8) (drill 0.4) (layers "F.Cu" "B.Cu") (net 4))
  (via (at 136.5 93.45) (size 0.8) (drill 0.4) (layers "F.Cu" "B.Cu") (free) (net 4))
  (via (at 160.12 79.1) (size 0.8) (drill 0.4) (layers "F.Cu" "B.Cu") (free) (net 4))
  (via (at 107.5 72.5) (size 0.8) (drill 0.4) (layers "F.Cu" "B.Cu") (free) (net 4))
  (via (at 125 72.5) (size 0.8) (drill 0.4) (layers "F.Cu" "B.Cu") (free) (net 4))
  (via (at 127.933695 124.6036) (size 0.8) (drill 0.4) (layers "F.Cu" "B.Cu") (net 4))
  (via (at 112.9 126.3) (size 0.8) (drill 0.4) (layers "F.Cu" "B.Cu") (net 4))
  (via (at 136.2 55.1) (size 0.8) (drill 0.4) (layers "F.Cu" "B.Cu") (free) (net 4))
  (via (at 120.2 133.25) (size 0.6) (drill 0.25) (layers "F.Cu" "B.Cu") (free) (net 4))
  (via (at 138.75 101.75) (size 0.8) (drill 0.4) (layers "F.Cu" "B.Cu") (net 4))
  (via (at 118.5 52.35) (size 0.8) (drill 0.4) (layers "F.Cu" "B.Cu") (free) (net 4))
  (via (at 90.853695 141.2896) (size 0.8) (drill 0.4) (layers "F.Cu" "B.Cu") (net 4))
  (via (at 142.5 72.5) (size 0.8) (drill 0.4) (layers "F.Cu" "B.Cu") (free) (net 4))
  (via (at 98.269695 118.1146) (size 0.8) (drill 0.4) (layers "F.Cu" "B.Cu") (net 4))
  (via (at 91 105.492) (size 0.8) (drill 0.4) (layers "F.Cu" "B.Cu") (net 4))
  (via (at 90.853695 123.6766) (size 0.8) (drill 0.4) (layers "F.Cu" "B.Cu") (net 4))
  (via (at 144 55.85) (size 0.8) (drill 0.4) (layers "F.Cu" "B.Cu") (free) (net 4))
  (via (at 103.597132 98.076324) (size 0.8) (drill 0.4) (layers "F.Cu" "B.Cu") (free) (net 4))
  (via (at 179.845695 136.6546) (size 0.8) (drill 0.4) (layers "F.Cu" "B.Cu") (net 4))
  (via (at 107.5 67.5) (size 0.8) (drill 0.4) (layers "F.Cu" "B.Cu") (free) (net 4))
  (via (at 127.6 56.05) (size 0.8) (drill 0.4) (layers "F.Cu" "B.Cu") (free) (net 4))
  (via (at 164.45 57.95) (size 0.8) (drill 0.4) (layers "F.Cu" "B.Cu") (free) (net 4))
  (via (at 135.349695 122.7496) (size 0.8) (drill 0.4) (layers "F.Cu" "B.Cu") (net 4))
  (via (at 116.8 99.092) (size 0.8) (drill 0.4) (layers "F.Cu" "B.Cu") (free) (net 4))
  (via (at 94.561695 113) (size 0.8) (drill 0.4) (layers "F.Cu" "B.Cu") (net 4))
  (via (at 101.977695 127.3846) (size 0.8) (drill 0.4) (layers "F.Cu" "B.Cu") (net 4))
  (via (at 185.5 104.25) (size 0.8) (drill 0.4) (layers "F.Cu" "B.Cu") (net 4))
  (via (at 141 61.5) (size 0.8) (drill 0.4) (layers "F.Cu" "B.Cu") (free) (net 4))
  (via (at 94.561695 139.4356) (size 0.8) (drill 0.4) (layers "F.Cu" "B.Cu") (net 4))
  (via (at 131.5 93.5) (size 0.8) (drill 0.4) (layers "F.Cu" "B.Cu") (free) (net 4))
  (via (at 116.2 133.4) (size 0.6) (drill 0.25) (layers "F.Cu" "B.Cu") (free) (net 4))
  (via (at 102.597132 98.076324) (size 0.8) (drill 0.4) (layers "F.Cu" "B.Cu") (free) (net 4))
  (via (at 123.5 52.35) (size 0.8) (drill 0.4) (layers "F.Cu" "B.Cu") (free) (net 4))
  (via (at 117.65 135.1) (size 0.6) (drill 0.25) (layers "F.Cu" "B.Cu") (free) (net 4))
  (via (at 179.6 103.3) (size 0.6) (drill 0.25) (layers "F.Cu" "B.Cu") (net 4))
  (via (at 144.7 57.8) (size 0.8) (drill 0.4) (layers "F.Cu" "B.Cu") (free) (net 4))
  (via (at 105.597132 102.476324) (size 0.8) (drill 0.4) (layers "F.Cu" "B.Cu") (free) (net 4))
  (via (at 131.641695 119.0416) (size 0.8) (drill 0.4) (layers "F.Cu" "B.Cu") (net 4))
  (via (at 95.4 98) (size 0.8) (drill 0.4) (layers "F.Cu" "B.Cu") (net 4))
  (via (at 177.991695 148.7056) (size 0.8) (drill 0.4) (layers "F.Cu" "B.Cu") (net 4))
  (via (at 160 57.5) (size 0.8) (drill 0.4) (layers "F.Cu" "B.Cu") (free) (net 4))
  (via (at 106.6 118.8) (size 0.8) (drill 0.4) (layers "F.Cu" "B.Cu") (net 4))
  (via (at 141 99.2) (size 0.8) (drill 0.4) (layers "F.Cu" "B.Cu") (free) (net 4))
  (via (at 142.5 70) (size 0.8) (drill 0.4) (layers "F.Cu" "B.Cu") (free) (net 4))
  (via (at 110.15 80.1) (size 0.6) (drill 0.25) (layers "F.Cu" "B.Cu") (net 4))
  (via (at 139 96.5) (size 0.8) (drill 0.4) (layers "F.Cu" "B.Cu") (free) (net 4))
  (via (at 100.4 125) (size 0.8) (drill 0.4) (layers "F.Cu" "B.Cu") (net 4))
  (via (at 175 58.5) (size 0.8) (drill 0.4) (layers "F.Cu" "B.Cu") (free) (net 4))
  (via (at 109.85 131.15) (size 0.8) (drill 0.4) (layers "F.Cu" "B.Cu") (net 4))
  (via (at 116 52.35) (size 0.8) (drill 0.4) (layers "F.Cu" "B.Cu") (free) (net 4))
  (via (at 146.85 115.2) (size 0.8) (drill 0.4) (layers "F.Cu" "B.Cu") (net 4))
  (via (at 171 52.55) (size 0.8) (drill 0.4) (layers "F.Cu" "B.Cu") (free) (net 4))
  (via (at 90.853695 119.9686) (size 0.8) (drill 0.4) (layers "F.Cu" "B.Cu") (net 4))
  (via (at 107.5 77.5) (size 0.8) (drill 0.4) (layers "F.Cu" "B.Cu") (free) (net 4))
  (via (at 94.561695 126.4576) (size 0.8) (drill 0.4) (layers "F.Cu" "B.Cu") (net 4))
  (via (at 165.9 55.9) (size 0.8) (drill 0.4) (layers "F.Cu" "B.Cu") (free) (net 4))
  (via (at 139 112) (size 0.8) (drill 0.4) (layers "F.Cu" "B.Cu") (net 4))
  (via (at 179.845695 132.9466) (size 0.8) (drill 0.4) (layers "F.Cu" "B.Cu") (net 4))
  (via (at 125.6 89.7) (size 0.8) (drill 0.4) (layers "F.Cu" "B.Cu") (free) (net 4))
  (via (at 172.7 57.8) (size 0.8) (drill 0.4) (layers "F.Cu" "B.Cu") (free) (net 4))
  (via (at 125.5 96.5) (size 0.8) (drill 0.4) (layers "F.Cu" "B.Cu") (free) (net 4))
  (via (at 136 57.95) (size 0.8) (drill 0.4) (layers "F.Cu" "B.Cu") (free) (net 4))
  (via (at 107.7 78.75) (size 0.8) (drill 0.4) (layers "F.Cu" "B.Cu") (free) (net 4))
  (via (at 121.55 135.05) (size 0.6) (drill 0.25) (layers "F.Cu" "B.Cu") (free) (net 4))
  (via (at 135.308 108.708) (size 0.8) (drill 0.4) (layers "F.Cu" "B.Cu") (net 4))
  (via (at 93.634695 134.8006) (size 0.8) (drill 0.4) (layers "F.Cu" "B.Cu") (net 4))
  (via (at 90.853695 127.3846) (size 0.8) (drill 0.4) (layers "F.Cu" "B.Cu") (net 4))
  (via (at 123 74) (size 0.8) (drill 0.4) (layers "F.Cu" "B.Cu") (free) (net 4))
  (via (at 158 76.5) (size 0.8) (drill 0.4) (layers "F.Cu" "B.Cu") (free) (net 4))
  (via (at 113.5 52.55) (size 0.8) (drill 0.4) (layers "F.Cu" "B.Cu") (free) (net 4))
  (via (at 183.553695 140.3626) (size 0.8) (drill 0.4) (layers "F.Cu" "B.Cu") (net 4))
  (via (at 160 60) (size 0.8) (drill 0.4) (layers "F.Cu" "B.Cu") (free) (net 4))
  (via (at 101.050695 148.7056) (size 0.8) (drill 0.4) (layers "F.Cu" "B.Cu") (net 4))
  (via (at 178.2 90.9) (size 0.8) (drill 0.4) (layers "F.Cu" "B.Cu") (net 4))
  (via (at 133.45 52.2) (size 0.8) (drill 0.4) (layers "F.Cu" "B.Cu") (free) (net 4))
  (via (at 97.8 120.2) (size 0.8) (drill 0.4) (layers "F.Cu" "B.Cu") (net 4))
  (via (at 127.933695 132.0196) (size 0.8) (drill 0.4) (layers "F.Cu" "B.Cu") (net 4))
  (via (at 147.45 58) (size 0.8) (drill 0.4) (layers "F.Cu" "B.Cu") (free) (net 4))
  (via (at 118.05 93.7) (size 0.8) (drill 0.4) (layers "F.Cu" "B.Cu") (free) (net 4))
  (via (at 142.908 108.708) (size 0.8) (drill 0.4) (layers "F.Cu" "B.Cu") (net 4))
  (via (at 142.5 65) (size 0.8) (drill 0.4) (layers "F.Cu" "B.Cu") (free) (net 4))
  (via (at 115.05 57.9) (size 0.8) (drill 0.4) (layers "F.Cu" "B.Cu") (free) (net 4))
  (via (at 106.4 116.4) (size 0.8) (drill 0.4) (layers "F.Cu" "B.Cu") (net 4))
  (via (at 125 60) (size 0.8) (drill 0.4) (layers "F.Cu" "B.Cu") (free) (net 4))
  (via (at 141 59) (size 0.8) (drill 0.4) (layers "F.Cu" "B.Cu") (free) (net 4))
  (via (at 146.708 108.708) (size 0.8) (drill 0.4) (layers "F.Cu" "B.Cu") (net 4))
  (via (at 135.349695 126.4576) (size 0.8) (drill 0.4) (layers "F.Cu" "B.Cu") (net 4))
  (via (at 115.6 125.8) (size 0.8) (drill 0.4) (layers "F.Cu" "B.Cu") (net 4))
  (via (at 139.2 105) (size 0.8) (drill 0.4) (layers "F.Cu" "B.Cu") (net 4))
  (via (at 100.2 87.6) (size 0.8) (drill 0.4) (layers "F.Cu" "B.Cu") (free) (net 4))
  (via (at 105.597132 104.076324) (size 0.8) (drill 0.4) (layers "F.Cu" "B.Cu") (free) (net 4))
  (via (at 178.5 55.05) (size 0.8) (drill 0.4) (layers "F.Cu" "B.Cu") (free) (net 4))
  (via (at 172.429695 133.8736) (size 0.8) (drill 0.4) (layers "F.Cu" "B.Cu") (net 4))
  (via (at 106.1 63.7) (size 0.8) (drill 0.4) (layers "F.Cu" "B.Cu") (free) (net 4))
  (via (at 176.137695 133.8736) (size 0.8) (drill 0.4) (layers "F.Cu" "B.Cu") (net 4))
  (via (at 97.342695 148.7056) (size 0.8) (drill 0.4) (layers "F.Cu" "B.Cu") (net 4))
  (via (at 120.517695 105.1366) (size 0.8) (drill 0.4) (layers "F.Cu" "B.Cu") (net 4))
  (via (at 123 76.5) (size 0.8) (drill 0.4) (layers "F.Cu" "B.Cu") (free) (net 4))
  (via (at 127.4 104.2) (size 0.8) (drill 0.4) (layers "F.Cu" "B.Cu") (free) (net 4))
  (via (at 128.5 52.55) (size 0.8) (drill 0.4) (layers "F.Cu" "B.Cu") (free) (net 4))
  (via (at 160 65) (size 0.8) (drill 0.4) (layers "F.Cu" "B.Cu") (free) (net 4))
  (via (at 97.6 116.2) (size 0.8) (drill 0.4) (layers "F.Cu" "B.Cu") (net 4))
  (via (at 101.2 93.7) (size 0.6) (drill 0.25) (layers "F.Cu" "B.Cu") (net 4))
  (via (at 106.197132 101.576324) (size 0.8) (drill 0.4) (layers "F.Cu" "B.Cu") (free) (net 4))
  (via (at 183.553695 129.2386) (size 0.8) (drill 0.4) (layers "F.Cu" "B.Cu") (net 4))
  (via (at 179.845695 129.2386) (size 0.8) (drill 0.4) (layers "F.Cu" "B.Cu") (net 4))
  (via (at 142.5 67.5) (size 0.8) (drill 0.4) (layers "F.Cu" "B.Cu") (free) (net 4))
  (via (at 124.216 102.8) (size 0.8) (drill 0.4) (layers "F.Cu" "B.Cu") (net 4))
  (via (at 175 61) (size 0.8) (drill 0.4) (layers "F.Cu" "B.Cu") (free) (net 4))
  (via (at 98.3 112.8) (size 0.8) (drill 0.4) (layers "F.Cu" "B.Cu") (net 4))
  (via (at 145 91.5) (size 0.8) (drill 0.4) (layers "F.Cu" "B.Cu") (free) (net 4))
  (via (at 138.95 126.5) (size 0.8) (drill 0.4) (layers "F.Cu" "B.Cu") (net 4))
  (via (at 99.196695 144.9976) (size 0.8) (drill 0.4) (layers "F.Cu" "B.Cu") (net 4))
  (via (at 96.1 89.8) (size 0.8) (drill 0.4) (layers "F.Cu" "B.Cu") (free) (net 4))
  (via (at 113.101695 118.6) (size 0.8) (drill 0.4) (layers "F.Cu" "B.Cu") (net 4))
  (via (at 177.5 60) (size 0.8) (drill 0.4) (layers "F.Cu" "B.Cu") (free) (net 4))
  (via (at 158 74) (size 0.8) (drill 0.4) (layers "F.Cu" "B.Cu") (free) (net 4))
  (via (at 176.137695 141.2896) (size 0.8) (drill 0.4) (layers "F.Cu" "B.Cu") (net 4))
  (via (at 187.261695 148.7056) (size 0.8) (drill 0.4) (layers "F.Cu" "B.Cu") (net 4))
  (via (at 116.6 118.4) (size 0.8) (drill 0.4) (layers "F.Cu" "B.Cu") (net 4))
  (via (at 130.15 58) (size 0.8) (drill 0.4) (layers "F.Cu" "B.Cu") (free) (net 4))
  (via (at 176.55 90.55) (size 0.8) (drill 0.4) (layers "F.Cu" "B.Cu") (net 4))
  (via (at 125.5 91.75) (size 0.8) (drill 0.4) (layers "F.Cu" "B.Cu") (free) (net 4))
  (via (at 107.5 57.5) (size 0.8) (drill 0.4) (layers "F.Cu" "B.Cu") (free) (net 4))
  (via (at 152.5 58) (size 0.8) (drill 0.4) (layers "F.Cu" "B.Cu") (free) (net 4))
  (via (at 176.137695 130.1656) (size 0.8) (drill 0.4) (layers "F.Cu" "B.Cu") (net 4))
  (via (at 158 66.5) (size 0.8) (drill 0.4) (layers "F.Cu" "B.Cu") (free) (net 4))
  (via (at 98 123) (size 0.8) (drill 0.4) (layers "F.Cu" "B.Cu") (net 4))
  (via (at 91 98.092) (size 0.8) (drill 0.4) (layers "F.Cu" "B.Cu") (net 4))
  (via (at 187.261695 129.2386) (size 0.8) (drill 0.4) (layers "F.Cu" "B.Cu") (net 4))
  (via (at 101.597132 99.276324) (size 0.8) (drill 0.4) (layers "F.Cu" "B.Cu") (free) (net 4))
  (via (at 94.3 89.7) (size 0.8) (drill 0.4) (layers "F.Cu" "B.Cu") (free) (net 4))
  (via (at 173.75 55.85) (size 0.8) (drill 0.4) (layers "F.Cu" "B.Cu") (free) (net 4))
  (via (at 101.977695 137.5816) (size 0.8) (drill 0.4) (layers "F.Cu" "B.Cu") (net 4))
  (via (at 144.0775 80.2275) (size 0.6) (drill 0.25) (layers "F.Cu" "B.Cu") (net 4))
  (via (at 106.1 68.7) (size 0.8) (drill 0.4) (layers "F.Cu" "B.Cu") (free) (net 4))
  (via (at 147 122.6) (size 0.8) (drill 0.4) (layers "F.Cu" "B.Cu") (free) (net 4))
  (via (at 140.95 52.2) (size 0.8) (drill 0.4) (layers "F.Cu" "B.Cu") (free) (net 4))
  (via (at 172.429695 137.5816) (size 0.8) (drill 0.4) (layers "F.Cu" "B.Cu") (net 4))
  (via (at 151 52.55) (size 0.8) (drill 0.4) (layers "F.Cu" "B.Cu") (free) (net 4))
  (via (at 120.508 99.092) (size 0.8) (drill 0.4) (layers "F.Cu" "B.Cu") (free) (net 4))
  (via (at 139.5 93.5) (size 0.8) (drill 0.4) (layers "F.Cu" "B.Cu") (free) (net 4))
  (via (at 160 75) (size 0.8) (drill 0.4) (layers "F.Cu" "B.Cu") (free) (net 4))
  (via (at 141 66.5) (size 0.8) (drill 0.4) (layers "F.Cu" "B.Cu") (free) (net 4))
  (via (at 111 52.55) (size 0.8) (drill 0.4) (layers "F.Cu" "B.Cu") (free) (net 4))
  (via (at 112.55 57.9) (size 0.8) (drill 0.4) (layers "F.Cu" "B.Cu") (free) (net 4))
  (via (at 183.553695 136.6546) (size 0.8) (drill 0.4) (layers "F.Cu" "B.Cu") (net 4))
  (via (at 121 52.35) (size 0.8) (drill 0.4) (layers "F.Cu" "B.Cu") (free) (net 4))
  (via (at 111 135.35) (size 0.8) (drill 0.4) (layers "F.Cu" "B.Cu") (net 4))
  (via (at 94.561695 130.1656) (size 0.8) (drill 0.4) (layers "F.Cu" "B.Cu") (net 4))
  (via (at 142.5 77.5) (size 0.8) (drill 0.4) (layers "F.Cu" "B.Cu") (free) (net 4))
  (via (at 160 62.5) (size 0.8) (drill 0.4) (layers "F.Cu" "B.Cu") (free) (net 4))
  (via (at 176.43 84.99) (size 0.8) (drill 0.4) (layers "F.Cu" "B.Cu") (free) (net 4))
  (via (at 141 74) (size 0.8) (drill 0.4) (layers "F.Cu" "B.Cu") (free) (net 4))
  (via (at 95.2 90.1) (size 0.8) (drill 0.4) (layers "F.Cu" "B.Cu") (free) (net 4))
  (via (at 125 70) (size 0.8) (drill 0.4) (layers "F.Cu" "B.Cu") (free) (net 4))
  (via (at 107.5 70) (size 0.8) (drill 0.4) (layers "F.Cu" "B.Cu") (free) (net 4))
  (via (at 177.5 75) (size 0.8) (drill 0.4) (layers "F.Cu" "B.Cu") (free) (net 4))
  (via (at 115 135.9) (size 0.6) (drill 0.25) (layers "F.Cu" "B.Cu") (free) (net 4))
  (via (at 98.269695 129.2386) (size 0.8) (drill 0.4) (layers "F.Cu" "B.Cu") (net 4))
  (via (at 138.85 57.95) (size 0.8) (drill 0.4) (layers "F.Cu" "B.Cu") (free) (net 4))
  (via (at 104.6 139.2) (size 0.8) (drill 0.4) (layers "F.Cu" "B.Cu") (net 4))
  (via (at 123 69) (size 0.8) (drill 0.4) (layers "F.Cu" "B.Cu") (free) (net 4))
  (via (at 149.9 57.95) (size 0.8) (drill 0.4) (layers "F.Cu" "B.Cu") (free) (net 4))
  (via (at 183.553695 132.9466) (size 0.8) (drill 0.4) (layers "F.Cu" "B.Cu") (net 4))
  (via (at 105.685695 127.3846) (size 0.8) (drill 0.4) (layers "F.Cu" "B.Cu") (net 4))
  (via (at 106.85 73.8) (size 0.8) (drill 0.4) (layers "F.Cu" "B.Cu") (free) (net 4))
  (via (at 143.05 122.75) (size 0.8) (drill 0.4) (layers "F.Cu" "B.Cu") (net 4))
  (via (at 129 96.5) (size 0.8) (drill 0.4) (layers "F.Cu" "B.Cu") (free) (net 4))
  (via (at 176.25 55.85) (size 0.8) (drill 0.4) (layers "F.Cu" "B.Cu") (free) (net 4))
  (via (at 175 71) (size 0.8) (drill 0.4) (layers "F.Cu" "B.Cu") (free) (net 4))
  (via (at 138.5 55.05) (size 0.8) (drill 0.4) (layers "F.Cu" "B.Cu") (free) (net 4))
  (via (at 107.5 75) (size 0.8) (drill 0.4) (layers "F.Cu" "B.Cu") (free) (net 4))
  (via (at 131.641695 122.7496) (size 0.8) (drill 0.4) (layers "F.Cu" "B.Cu") (net 4))
  (via (at 110.2 88.85) (size 0.8) (drill 0.4) (layers "F.Cu" "B.Cu") (net 4))
  (via (at 154.5 58) (size 0.8) (drill 0.4) (layers "F.Cu" "B.Cu") (free) (net 4))
  (via (at 127.4 108) (size 0.8) (drill 0.4) (layers "F.Cu" "B.Cu") (net 4))
  (via (at 172.429695 141.2896) (size 0.8) (drill 0.4) (layers "F.Cu" "B.Cu") (net 4))
  (via (at 138.75 119) (size 0.8) (drill 0.4) (layers "F.Cu" "B.Cu") (net 4))
  (via (at 181.699695 148.7056) (size 0.8) (drill 0.4) (layers "F.Cu" "B.Cu") (net 4))
  (via (at 113.101695 116.2606) (size 0.8) (drill 0.4) (layers "F.Cu" "B.Cu") (net 4))
  (via (at 97.95 100.3) (size 0.8) (drill 0.4) (layers "F.Cu" "B.Cu") (net 4))
  (via (at 138.45 52.2) (size 0.8) (drill 0.4) (layers "F.Cu" "B.Cu") (free) (net 4))
  (via (at 160.23 90.31) (size 0.8) (drill 0.4) (layers "F.Cu" "B.Cu") (free) (net 4))
  (via (at 106.1 61.2) (size 0.8) (drill 0.4) (layers "F.Cu" "B.Cu") (free) (net 4))
  (via (at 127.933695 117.1876) (size 0.8) (drill 0.4) (layers "F.Cu" "B.Cu") (net 4))
  (via (at 175 66) (size 0.8) (drill 0.4) (layers "F.Cu" "B.Cu") (free) (net 4))
  (via (at 155.5 98) (size 0.6) (drill 0.25) (layers "F.Cu" "B.Cu") (net 4))
  (via (at 106.1 71.2) (size 0.8) (drill 0.4) (layers "F.Cu" "B.Cu") (free) (net 4))
  (via (at 121 55.05) (size 0.8) (drill 0.4) (layers "F.Cu" "B.Cu") (free) (net 4))
  (via (at 127.42 80.2) (size 0.6) (drill 0.25) (layers "F.Cu" "B.Cu") (net 4))
  (via (at 138.8 115.2) (size 0.8) (drill 0.4) (layers "F.Cu" "B.Cu") (net 4))
  (via (at 125 57.5) (size 0.8) (drill 0.4) (layers "F.Cu" "B.Cu") (free) (net 4))
  (via (at 97.5 96.8) (size 0.8) (drill 0.4) (layers "F.Cu" "B.Cu") (net 4))
  (via (at 110.4 118.6) (size 0.8) (drill 0.4) (layers "F.Cu" "B.Cu") (net 4))
  (via (at 123 71.5) (size 0.8) (drill 0.4) (layers "F.Cu" "B.Cu") (free) (net 4))
  (via (at 173.5 52.55) (size 0.8) (drill 0.4) (layers "F.Cu" "B.Cu") (free) (net 4))
  (via (at 177.5 70) (size 0.8) (drill 0.4) (layers "F.Cu" "B.Cu") (free) (net 4))
  (via (at 143.9775 85.9275) (size 0.6) (drill 0.25) (layers "F.Cu" "B.Cu") (net 4))
  (via (at 118.6 57.95) (size 0.8) (drill 0.4) (layers "F.Cu" "B.Cu") (free) (net 4))
  (via (at 189.115695 144.0706) (size 0.8) (drill 0.4) (layers "F.Cu" "B.Cu") (net 4))
  (via (at 142.908 105) (size 0.8) (drill 0.4) (layers "F.Cu" "B.Cu") (net 4))
  (via (at 98.269695 137.5816) (size 0.8) (drill 0.4) (layers "F.Cu" "B.Cu") (net 4))
  (via (at 105.685695 134.8006) (size 0.8) (drill 0.4) (layers "F.Cu" "B.Cu") (net 4))
  (via (at 176.6 88.75) (size 0.8) (drill 0.4) (layers "F.Cu" "B.Cu") (net 4))
  (via (at 110.05 85.85) (size 0.8) (drill 0.4) (layers "F.Cu" "B.Cu") (net 4))
  (via (at 127.933695 128.3116) (size 0.8) (drill 0.4) (layers "F.Cu" "B.Cu") (net 4))
  (via (at 108.6 110.6) (size 0.8) (drill 0.4) (layers "F.Cu" "B.Cu") (free) (net 4))
  (via (at 156 52.55) (size 0.8) (drill 0.4) (layers "F.Cu" "B.Cu") (free) (net 4))
  (via (at 111.05 56.15) (size 0.8) (drill 0.4) (layers "F.Cu" "B.Cu") (free) (net 4))
  (via (at 120.508 102.8) (size 0.8) (drill 0.4) (layers "F.Cu" "B.Cu") (net 4))
  (via (at 143.15 118.9) (size 0.8) (drill 0.4) (layers "F.Cu" "B.Cu") (net 4))
  (via (at 158 61.5) (size 0.8) (drill 0.4) (layers "F.Cu" "B.Cu") (free) (net 4))
  (via (at 108.95 52.55) (size 0.8) (drill 0.4) (layers "F.Cu" "B.Cu") (free) (net 4))
  (via (at 113.101695 112.5526) (size 0.8) (drill 0.4) (layers "F.Cu" "B.Cu") (net 4))
  (via (at 116.809695 116.2606) (size 0.8) (drill 0.4) (layers "F.Cu" "B.Cu") (net 4))
  (via (at 134.6 99) (size 0.8) (drill 0.4) (layers "F.Cu" "B.Cu") (free) (net 4))
  (via (at 135.5 96.5) (size 0.8) (drill 0.4) (layers "F.Cu" "B.Cu") (free) (net 4))
  (via (at 158 64) (size 0.8) (drill 0.4) (layers "F.Cu" "B.Cu") (free) (net 4))
  (via (at 120.361695 123.7) (size 0.8) (drill 0.4) (layers "F.Cu" "B.Cu") (net 4))
  (via (at 101.977695 141.2896) (size 0.8) (drill 0.4) (layers "F.Cu" "B.Cu") (net 4))
  (via (at 142.4 93) (size 0.8) (drill 0.4) (layers "F.Cu" "B.Cu") (free) (net 4))
  (via (at 107.5 62.5) (size 0.8) (drill 0.4) (layers "F.Cu" "B.Cu") (free) (net 4))
  (via (at 103.831695 131.0926) (size 0.8) (drill 0.4) (layers "F.Cu" "B.Cu") (net 4))
  (via (at 160 77.5) (size 0.8) (drill 0.4) (layers "F.Cu" "B.Cu") (free) (net 4))
  (via (at 187.261695 140.3626) (size 0.8) (drill 0.4) (layers "F.Cu" "B.Cu") (net 4))
  (via (at 126.3 52.25) (size 0.8) (drill 0.4) (layers "F.Cu" "B.Cu") (free) (net 4))
  (via (at 178.918695 144.9976) (size 0.8) (drill 0.4) (layers "F.Cu" "B.Cu") (net 4))
  (via (at 131.6 112.6) (size 0.8) (drill 0.4) (layers "F.Cu" "B.Cu") (free) (net 4))
  (via (at 98.416 109.2) (size 0.8) (drill 0.4) (layers "F.Cu" "B.Cu") (net 4))
  (via (at 146.8 112) (size 0.8) (drill 0.4) (layers "F.Cu" "B.Cu") (net 4))
  (via (at 110 57.6) (size 0.8) (drill 0.4) (layers "F.Cu" "B.Cu") (free) (net 4))
  (via (at 114 93.5) (size 0.8) (drill 0.4) (layers "F.Cu" "B.Cu") (free) (net 4))
  (via (at 141 64) (size 0.8) (drill 0.4) (layers "F.Cu" "B.Cu") (free) (net 4))
  (via (at 175 76) (size 0.8) (drill 0.4) (layers "F.Cu" "B.Cu") (free) (net 4))
  (via (at 146 52.55) (size 0.8) (drill 0.4) (layers "F.Cu" "B.Cu") (free) (net 4))
  (via (at 125 62.5) (size 0.8) (drill 0.4) (layers "F.Cu" "B.Cu") (free) (net 4))
  (via (at 155.5 96) (size 0.6) (drill 0.25) (layers "F.Cu" "B.Cu") (net 4))
  (via (at 125 65) (size 0.8) (drill 0.4) (layers "F.Cu" "B.Cu") (free) (net 4))
  (via (at 125.5 77.4) (size 0.8) (drill 0.4) (layers "F.Cu" "B.Cu") (free) (net 4))
  (via (at 106 52.55) (size 0.8) (drill 0.4) (layers "F.Cu" "B.Cu") (free) (net 4))
  (via (at 148.8 102.8) (size 0.8) (drill 0.4) (layers "F.Cu" "B.Cu") (net 4))
  (via (at 150.4 126.6) (size 0.8) (drill 0.4) (layers "F.Cu" "B.Cu") (free) (net 4))
  (via (at 147 126.4) (size 0.8) (drill 0.4) (layers "F.Cu" "B.Cu") (free) (net 4))
  (via (at 94.561695 122.7496) (size 0.8) (drill 0.4) (layers "F.Cu" "B.Cu") (net 4))
  (via (at 180.4 95.4) (size 0.6) (drill 0.25) (layers "F.Cu" "B.Cu") (net 4))
  (via (at 123 59) (size 0.8) (drill 0.4) (layers "F.Cu" "B.Cu") (free) (net 4))
  (via (at 142.5 60) (size 0.8) (drill 0.4) (layers "F.Cu" "B.Cu") (free) (net 4))
  (via (at 175.7 77.45) (size 0.8) (drill 0.4) (layers "F.Cu" "B.Cu") (free) (net 4))
  (via (at 140 75.25) (size 0.8) (drill 0.4) (layers "F.Cu" "B.Cu") (free) (net 4))
  (via (at 177.5 77.5) (size 0.8) (drill 0.4) (layers "F.Cu" "B.Cu") (free) (net 4))
  (via (at 113.7 133.4) (size 0.6) (drill 0.25) (layers "F.Cu" "B.Cu") (free) (net 4))
  (via (at 189.115695 95.8666) (size 0.8) (drill 0.4) (layers "F.Cu" "B.Cu") (net 4))
  (via (at 171.25 55.85) (size 0.8) (drill 0.4) (layers "F.Cu" "B.Cu") (free) (net 4))
  (via (at 91 109.2) (size 0.8) (drill 0.4) (layers "F.Cu" "B.Cu") (net 4))
  (via (at 109.393695 116.2606) (size 0.8) (drill 0.4) (layers "F.Cu" "B.Cu") (net 4))
  (via (at 90.853695 112.5526) (size 0.8) (drill 0.4) (layers "F.Cu" "B.Cu") (net 4))
  (via (at 142.5 57.5) (size 0.8) (drill 0.4) (layers "F.Cu" "B.Cu") (free) (net 4))
  (via (at 175 63.5) (size 0.8) (drill 0.4) (layers "F.Cu" "B.Cu") (free) (net 4))
  (via (at 105.685695 142.2166) (size 0.8) (drill 0.4) (layers "F.Cu" "B.Cu") (net 4))
  (via (at 131.641695 115.925) (size 0.8) (drill 0.4) (layers "F.Cu" "B.Cu") (net 4))
  (via (at 118.75 55.1) (size 0.8) (drill 0.4) (layers "F.Cu" "B.Cu") (free) (net 4))
  (segment (start 163.9375 121.45) (end 164.65 121.45) (width 0.25) (layer "F.Cu") (net 5))
  (segment (start 167.71499 124.44999) (end 168.715 125.45) (width 0.25) (layer "F.Cu") (net 5))
  (segment (start 166.34999 124.44999) (end 167.71499 124.44999) (width 0.25) (layer "F.Cu") (net 5))
  (segment (start 169.53 125.45) (end 170.065 124.915) (width 0.25) (layer "F.Cu") (net 5))
  (segment (start 168.715 125.45) (end 169.53 125.45) (width 0.25) (layer "F.Cu") (net 5))
  (segment (start 164.65 121.45) (end 165.9 122.7) (width 0.25) (layer "F.Cu") (net 5))
  (segment (start 165.9 122.7) (end 165.9 124) (width 0.25) (layer "F.Cu") (net 5))
  (segment (start 165.9 124) (end 166.34999 124.44999) (width 0.25) (layer "F.Cu") (net 5))
  (segment (start 168.5 117.935) (end 168.94 117.935) (width 0.25) (layer "F.Cu") (net 6))
  (segment (start 163.9375 118.45) (end 166.45 118.45) (width 0.25) (layer "F.Cu") (net 6))
  (segment (start 167.45 117.92) (end 168.485 117.92) (width 0.25) (layer "F.Cu") (net 6))
  (segment (start 166.98 117.92) (end 167.45 117.92) (width 0.25) (layer "F.Cu") (net 6))
  (segment (start 166.45 118.45) (end 166.98 117.92) (width 0.25) (layer "F.Cu") (net 6))
  (segment (start 168.94 117.935) (end 169.675 117.2) (width 0.25) (layer "F.Cu") (net 6))
  (segment (start 165.1 123.015) (end 164.535 123.015) (width 0.25) (layer "F.Cu") (net 7))
  (segment (start 156.0275 116.915) (end 156.0625 116.95) (width 0.25) (layer "F.Cu") (net 7))
  (segment (start 156.75 123.1375) (end 156.75 123.85) (width 0.25) (layer "F.Cu") (net 7))
  (segment (start 163.9375 121.95) (end 164.45 121.95) (width 0.25) (layer "F.Cu") (net 7))
  (segment (start 164 123.55) (end 164 125.3) (width 0.25) (layer "F.Cu") (net 7))
  (segment (start 165.1 122.6) (end 165.1 123.015) (width 0.25) (layer "F.Cu") (net 7))
  (segment (start 153.6 117) (end 154.415 117) (width 0.25) (layer "F.Cu") (net 7))
  (segment (start 164.45 121.95) (end 165.1 122.6) (width 0.25) (layer "F.Cu") (net 7))
  (segment (start 156.085 125.685) (end 156.1 125.7) (width 0.25) (layer "F.Cu") (net 7))
  (segment (start 164.535 123.015) (end 164 123.55) (width 0.25) (layer "F.Cu") (net 7))
  (segment (start 154.5 116.915) (end 156.0275 116.915) (width 0.25) (layer "F.Cu") (net 7))
  (segment (start 156.115 125.715) (end 156.1 125.7) (width 0.325) (layer "F.Cu") (net 7))
  (segment (start 156.115 126.8) (end 156.115 125.715) (width 0.325) (layer "F.Cu") (net 7))
  (segment (start 156.75 123.85) (end 156.085 124.515) (width 0.25) (layer "F.Cu") (net 7))
  (segment (start 156.085 124.7) (end 156.085 125.685) (width 0.25) (layer "F.Cu") (net 7))
  (via (at 156.1 125.7) (size 0.8) (drill 0.4) (layers "F.Cu" "B.Cu") (net 7))
  (via (at 164 125.35) (size 0.8) (drill 0.4) (layers "F.Cu" "B.Cu") (net 7))
  (via (at 153.6 117) (size 0.8) (drill 0.4) (layers "F.Cu" "B.Cu") (net 7))
  (segment (start 156.1 124.8) (end 153.6 122.3) (width 0.25) (layer "In2.Cu") (net 7))
  (segment (start 156.1 125.7) (end 156.9 126.5) (width 0.25) (layer "In2.Cu") (net 7))
  (segment (start 153.6 122.3) (end 153.6 117) (width 0.25) (layer "In2.Cu") (net 7))
  (segment (start 156.9 126.5) (end 162.8 126.5) (width 0.25) (layer "In2.Cu") (net 7))
  (segment (start 156.1 125.7) (end 156.1 124.8) (width 0.25) (layer "In2.Cu") (net 7))
  (segment (start 162.8 126.5) (end 164 125.3) (width 0.25) (layer "In2.Cu") (net 7))
  (segment (start 166.3 121.4) (end 168.9575 121.4) (width 0.25) (layer "F.Cu") (net 8))
  (segment (start 168.9575 121.4) (end 170.0425 121.4) (width 0.25) (layer "F.Cu") (net 8))
  (segment (start 163.9375 120.45) (end 165.35 120.45) (width 0.25) (layer "F.Cu") (net 8))
  (segment (start 171.2325 121.4) (end 170.0725 121.4) (width 0.25) (layer "F.Cu") (net 8))
  (segment (start 165.35 120.45) (end 166.3 121.4) (width 0.25) (layer "F.Cu") (net 8))
  (segment (start 165.4 115.9) (end 165.4 115.5) (width 0.25) (layer "F.Cu") (net 9))
  (segment (start 164.85 116.45) (end 165.4 115.9) (width 0.25) (layer "F.Cu") (net 9))
  (segment (start 163.9375 116.45) (end 164.85 116.45) (width 0.25) (layer "F.Cu") (net 9))
  (segment (start 183.85 112.6) (end 183.975 112.475) (width 0.325) (layer "F.Cu") (net 10))
  (segment (start 187.7 114.8) (end 188.585 114.8) (width 0.325) (layer "F.Cu") (net 10))
  (segment (start 183.2 115.35) (end 181.785 115.35) (width 0.325) (layer "F.Cu") (net 10))
  (segment (start 183.3 111.4) (end 183.3 111.8) (width 0.2) (layer "F.Cu") (net 10))
  (segment (start 184.95 114.8) (end 184.4 115.35) (width 0.325) (layer "F.Cu") (net 10))
  (segment (start 183.85 114.1) (end 183.85 112.6) (width 0.325) (layer "F.Cu") (net 10))
  (segment (start 182.8575 112.05) (end 183.05 112.05) (width 0.2) (layer "F.Cu") (net 10))
  (segment (start 183.975 112.475) (end 184.15 112.3) (width 0.325) (layer "F.Cu") (net 10))
  (segment (start 187.65 115.25) (end 187.7 115.2) (width 0.325) (layer "F.Cu") (net 10))
  (segment (start 183.2 115.35) (end 183.2 114.75) (width 0.325) (layer "F.Cu") (net 10))
  (segment (start 188.585 112.3) (end 187.6 112.3) (width 0.325) (layer "F.Cu") (net 10))
  (segment (start 183.25 111.35) (end 183.3 111.4) (width 0.2) (layer "F.Cu") (net 10))
  (segment (start 184.15 112.3) (end 185.615 112.3) (width 0.325) (layer "F.Cu") (net 10))
  (segment (start 187.7 115.2) (end 187.7 114.8) (width 0.325) (layer "F.Cu") (net 10))
  (segment (start 183.05 112.05) (end 183.3 111.8) (width 0.2) (layer "F.Cu") (net 10))
  (segment (start 183.975 112.475) (end 183.3 111.8) (width 0.325) (layer "F.Cu") (net 10))
  (segment (start 181.785 115.35) (end 181.685 115.25) (width 0.325) (layer "F.Cu") (net 10))
  (segment (start 183.2 114.75) (end 183.85 114.1) (width 0.325) (layer "F.Cu") (net 10))
  (segment (start 184.4 115.35) (end 183.2 115.35) (width 0.325) (layer "F.Cu") (net 10))
  (segment (start 185.615 114.8) (end 184.95 114.8) (width 0.325) (layer "F.Cu") (net 10))
  (segment (start 182.8575 111.35) (end 183.25 111.35) (width 0.2) (layer "F.Cu") (net 10))
  (via (at 187.65 115.25) (size 0.6) (drill 0.25) (layers "F.Cu" "B.Cu") (net 10))
  (via (at 187.6 112.3) (size 0.6) (drill 0.25) (layers "F.Cu" "B.Cu") (net 10))
  (via (at 184.4 115.35) (size 0.6) (drill 0.25) (layers "F.Cu" "B.Cu") (net 10))
  (segment (start 188.05 115.25) (end 187.65 115.25) (width 0.325) (layer "In2.Cu") (net 10))
  (segment (start 188.75 112.9) (end 188.75 114.55) (width 0.325) (layer "In2.Cu") (net 10))
  (segment (start 185.05 115.35) (end 184.4 115.35) (width 0.325) (layer "In2.Cu") (net 10))
  (segment (start 187.65 115.25) (end 187.35 115.55) (width 0.325) (layer "In2.Cu") (net 10))
  (segment (start 187.35 115.55) (end 185.25 115.55) (width 0.325) (layer "In2.Cu") (net 10))
  (segment (start 188.15 112.3) (end 188.75 112.9) (width 0.325) (layer "In2.Cu") (net 10))
  (segment (start 185.25 115.55) (end 185.05 115.35) (width 0.325) (layer "In2.Cu") (net 10))
  (segment (start 188.75 114.55) (end 188.05 115.25) (width 0.325) (layer "In2.Cu") (net 10))
  (segment (start 187.6 112.3) (end 188.15 112.3) (width 0.325) (layer "In2.Cu") (net 10))
  (segment (start 141.715 96.6) (end 141 96.6) (width 0.25) (layer "F.Cu") (net 11))
  (segment (start 97.5 105.3) (end 97.4 105.4) (width 0.25) (layer "F.Cu") (net 11))
  (segment (start 109.747132 100.526324) (end 108.247132 100.526324) (width 0.8) (layer "F.Cu") (net 11))
  (segment (start 97.5 104.4) (end 97.5 105.3) (width 0.25) (layer "F.Cu") (net 11))
  (via (at 157.2 134.8) (size 0.8) (drill 0.4) (layers "F.Cu" "B.Cu") (net 11))
  (via (at 155.6 134.8) (size 0.8) (drill 0.4) (layers "F.Cu" "B.Cu") (net 11))
  (via (at 163.6 134.8) (size 0.8) (drill 0.4) (layers "F.Cu" "B.Cu") (net 11))
  (via (at 160.4 134.8) (size 0.8) (drill 0.4) (layers "F.Cu" "B.Cu") (net 11))
  (via (at 158.8 134.8) (size 0.8) (drill 0.4) (layers "F.Cu" "B.Cu") (net 11))
  (via (at 162 134.8) (size 0.8) (drill 0.4) (layers "F.Cu" "B.Cu") (net 11))
  (via (at 170 134.8) (size 0.8) (drill 0.4) (layers "F.Cu" "B.Cu") (net 11))
  (via (at 166.8 134.8) (size 0.8) (drill 0.4) (layers "F.Cu" "B.Cu") (net 11))
  (via (at 165.2 134.8) (size 0.8) (drill 0.4) (layers "F.Cu" "B.Cu") (net 11))
  (via (at 168.4 134.8) (size 0.8) (drill 0.4) (layers "F.Cu" "B.Cu") (net 11))
  (via (at 159.6 133.6) (size 0.8) (drill 0.4) (layers "F.Cu" "B.Cu") (net 11))
  (via (at 169.2 133.6) (size 0.8) (drill 0.4) (layers "F.Cu" "B.Cu") (net 11))
  (via (at 167.6 133.6) (size 0.8) (drill 0.4) (layers "F.Cu" "B.Cu") (net 11))
  (via (at 158 133.6) (size 0.8) (drill 0.4) (layers "F.Cu" "B.Cu") (net 11))
  (via (at 164.4 133.6) (size 0.8) (drill 0.4) (layers "F.Cu" "B.Cu") (net 11))
  (via (at 154.8 133.6) (size 0.8) (drill 0.4) (layers "F.Cu" "B.Cu") (net 11))
  (via (at 153.2 133.6) (size 0.8) (drill 0.4) (layers "F.Cu" "B.Cu") (net 11))
  (via (at 161.2 133.6) (size 0.8) (drill 0.4) (layers "F.Cu" "B.Cu") (net 11))
  (via (at 166 133.6) (size 0.8) (drill 0.4) (layers "F.Cu" "B.Cu") (net 11))
  (via (at 162.8 133.6) (size 0.8) (drill 0.4) (layers "F.Cu" "B.Cu") (net 11))
  (via (at 156.4 133.6) (size 0.8) (drill 0.4) (layers "F.Cu" "B.Cu") (net 11))
  (via (at 152.4 132.4) (size 0.8) (drill 0.4) (layers "F.Cu" "B.Cu") (net 11))
  (via (at 160.4 132.4) (size 0.8) (drill 0.4) (layers "F.Cu" "B.Cu") (net 11))
  (via (at 158.8 132.4) (size 0.8) (drill 0.4) (layers "F.Cu" "B.Cu") (net 11))
  (via (at 168.4 132.4) (size 0.8) (drill 0.4) (layers "F.Cu" "B.Cu") (net 11))
  (via (at 163.6 132.4) (size 0.8) (drill 0.4) (layers "F.Cu" "B.Cu") (net 11))
  (via (at 170 132.4) (size 0.8) (drill 0.4) (layers "F.Cu" "B.Cu") (net 11))
  (via (at 155.6 132.4) (size 0.8) (drill 0.4) (layers "F.Cu" "B.Cu") (net 11))
  (via (at 166.8 132.4) (size 0.8) (drill 0.4) (layers "F.Cu" "B.Cu") (net 11))
  (via (at 165.2 132.4) (size 0.8) (drill 0.4) (layers "F.Cu" "B.Cu") (net 11))
  (via (at 162 132.4) (size 0.8) (drill 0.4) (layers "F.Cu" "B.Cu") (net 11))
  (via (at 157.2 132.4) (size 0.8) (drill 0.4) (layers "F.Cu" "B.Cu") (net 11))
  (via (at 154 132.4) (size 0.8) (drill 0.4) (layers "F.Cu" "B.Cu") (net 11))
  (via (at 153.2 131.2) (size 0.8) (drill 0.4) (layers "F.Cu" "B.Cu") (net 11))
  (via (at 164.4 131.2) (size 0.8) (drill 0.4) (layers "F.Cu" "B.Cu") (net 11))
  (via (at 161.2 131.2) (size 0.8) (drill 0.4) (layers "F.Cu" "B.Cu") (net 11))
  (via (at 158 131.2) (size 0.8) (drill 0.4) (layers "F.Cu" "B.Cu") (net 11))
  (via (at 159.6 131.2) (size 0.8) (drill 0.4) (layers "F.Cu" "B.Cu") (net 11))
  (via (at 156.4 131.2) (size 0.8) (drill 0.4) (layers "F.Cu" "B.Cu") (net 11))
  (via (at 166 131.2) (size 0.8) (drill 0.4) (layers "F.Cu" "B.Cu") (net 11))
  (via (at 162.8 131.2) (size 0.8) (drill 0.4) (layers "F.Cu" "B.Cu") (net 11))
  (via (at 169.2 131.2) (size 0.8) (drill 0.4) (layers "F.Cu" "B.Cu") (net 11))
  (via (at 167.6 131.2) (size 0.8) (drill 0.4) (layers "F.Cu" "B.Cu") (net 11))
  (via (at 154.8 131.2) (size 0.8) (drill 0.4) (layers "F.Cu" "B.Cu") (net 11))
  (via (at 120.5 90.2) (size 0.8) (drill 0.4) (layers "F.Cu" "B.Cu") (free) (net 11))
  (via (at 118.2 89.3) (size 0.8) (drill 0.4) (layers "F.Cu" "B.Cu") (free) (net 11))
  (via (at 99.15 84.7) (size 0.8) (drill 0.4) (layers "F.Cu" "B.Cu") (free) (net 11))
  (via (at 165.6 91.3) (size 0.8) (drill 0.4) (layers "F.Cu" "B.Cu") (free) (net 11))
  (via (at 183.6 91) (size 0.8) (drill 0.4) (layers "F.Cu" "B.Cu") (free) (net 11))
  (via (at 141.2 106.8) (size 0.8) (drill 0.4) (layers "F.Cu" "B.Cu") (free) (net 11))
  (via (at 137.7 90.4) (size 0.8) (drill 0.4) (layers "F.Cu" "B.Cu") (free) (net 11))
  (via (at 97.75 81.55) (size 0.8) (drill 0.4) (layers "F.Cu" "B.Cu") (free) (net 11))
  (via (at 145.4 124) (size 0.8) (drill 0.4) (layers "F.Cu" "B.Cu") (free) (net 11))
  (via (at 96.25 76.35) (size 0.8) (drill 0.4) (layers "F.Cu" "B.Cu") (free) (net 11))
  (via (at 114.8 100.6) (size 0.8) (drill 0.4) (layers "F.Cu" "B.Cu") (free) (net 11))
  (via (at 126 115.2) (size 0.8) (drill 0.4) (layers "F.Cu" "B.Cu") (free) (net 11))
  (via (at 132.9 92) (size 0.8) (drill 0.4) (layers "F.Cu" "B.Cu") (free) (net 11))
  (via (at 170.4 89.7) (size 0.8) (drill 0.4) (layers "F.Cu" "B.Cu") (free) (net 11))
  (via (at 130.75 101.75) (size 0.8) (drill 0.4) (layers "F.Cu" "B.Cu") (free) (net 11))
  (via (at 110 101.8) (size 0.8) (drill 0.4) (layers "F.Cu" "B.Cu") (free) (net 11))
  (via (at 152.4 134.8) (size 0.8) (drill 0.4) (layers "F.Cu" "B.Cu") (net 11))
  (via (at 182.15 91.25) (size 0.8) (drill 0.4) (layers "F.Cu" "B.Cu") (free) (net 11))
  (via (at 98.55 80.75) (size 0.8) (drill 0.4) (layers "F.Cu" "B.Cu") (free) (net 11))
  (via (at 119.7 91) (size 0.8) (drill 0.4) (layers "F.Cu" "B.Cu") (free) (net 11))
  (via (at 170.4 91.3) (size 0.8) (drill 0.4) (layers "F.Cu" "B.Cu") (free) (net 11))
  (via (at 151 91.6) (size 0.8) (drill 0.4) (layers "F.Cu" "B.Cu") (free) (net 11))
  (via (at 185.35 89.95) (size 0.8) (drill 0.4) (layers "F.Cu" "B.Cu") (free) (net 11))
  (via (at 98.45 83.9) (size 0.8) (drill 0.4) (layers "F.Cu" "B.Cu") (free) (net 11))
  (via (at 100.15 80.75) (size 0.8) (drill 0.4) (layers "F.Cu" "B.Cu") (free) (net 11))
  (via (at 96.95 80.75) (size 0.8) (drill 0.4) (layers "F.Cu" "B.Cu") (free) (net 11))
  (via (at 132.1 91.2) (size 0.8) (drill 0.4) (layers "F.Cu" "B.Cu") (free) (net 11))
  (via (at 112.4 102.8) (size 0.8) (drill 0.4) (layers "F.Cu" "B.Cu") (free) (net 11))
  (via (at 149.5 90.5) (size 0.8) (drill 0.4) (layers "F.Cu" "B.Cu") (free) (net 11))
  (via (at 133.4 110.4) (size 0.8) (drill 0.4) (layers "F.Cu" "B.Cu") (free) (net 11))
  (via (at 141 96.6) (size 0.8) (drill 0.4) (layers "F.Cu" "B.Cu") (net 11))
  (via (at 137 113.4) (size 0.8) (drill 0.4) (layers "F.Cu" "B.Cu") (free) (net 11))
  (via (at 171.2 88.9) (size 0.8) (drill 0.4) (layers "F.Cu" "B.Cu") (free) (net 11))
  (via (at 152.75 91.55) (size 0.8) (drill 0.4) (layers "F.Cu" "B.Cu") (free) (net 11))
  (via (at 136.25 91.85) (size 0.8) (drill 0.4) (layers "F.Cu" "B.Cu") (free) (net 11))
  (via (at 166.4 92.1) (size 0.8) (drill 0.4) (layers "F.Cu" "B.Cu") (free) (net 11))
  (via (at 167.9 90.45) (size 0.8) (drill 0.4) (layers "F.Cu" "B.Cu") (free) (net 11))
  (via (at 171.2 90.5) (size 0.8) (drill 0.4) (layers "F.Cu" "B.Cu") (free) (net 11))
  (via (at 136.9 91.2) (size 0.8) (drill 0.4) (layers "F.Cu" "B.Cu") (free) (net 11))
  (via (at 137 117) (size 0.8) (drill 0.4) (layers "F.Cu" "B.Cu") (free) (net 11))
  (via (at 151.9 91.1) (size 0.8) (drill 0.4) (layers "F.Cu" "B.Cu") (free) (net 11))
  (via (at 95.4 93.4) (size 0.8) (drill 0.4) (layers "F.Cu" "B.Cu") (free) (net 11))
  (via (at 96.25 79.55) (size 0.8) (drill 0.4) (layers "F.Cu" "B.Cu") (free) (net 11))
  (via (at 184.2 89.45) (size 0.8) (drill 0.4) (layers "F.Cu" "B.Cu") (free) (net 11))
  (via (at 95.4 95) (size 0.8) (drill 0.4) (layers "F.Cu" "B.Cu") (free) (net 11))
  (via (at 136.1 88.8) (size 0.8) (drill 0.4) (layers "F.Cu" "B.Cu") (free) (net 11))
  (via (at 96.15 81.55) (size 0.8) (drill 0.4) (layers "F.Cu" "B.Cu") (free) (net 11))
  (via (at 97.05 75.55) (size 0.8) (drill 0.4) (layers "F.Cu" "B.Cu") (free) (net 11))
  (via (at 152.25 88.9) (size 0.8) (drill 0.4) (layers "F.Cu" "B.Cu") (free) (net 11))
  (via (at 97.05 73.95) (size 0.8) (drill 0.4) (layers "F.Cu" "B.Cu") (free) (net 11))
  (via (at 131 99.2) (size 0.8) (drill 0.4) (layers "F.Cu" "B.Cu") (free) (net 11))
  (via (at 136.8 120.6) (size 0.8) (drill 0.4) (layers "F.Cu" "B.Cu") (free) (net 11))
  (via (at 132.9 90.4) (size 0.8) (drill 0.4) (layers "F.Cu" "B.Cu") (free) (net 11))
  (via (at 168.85 89.55) (size 0.8) (drill 0.4) (layers "F.Cu" "B.Cu") (free) (net 11))
  (via (at 135.3 91.4) (size 0.8) (drill 0.4) (layers "F.Cu" "B.Cu") (free) (net 11))
  (via (at 181.05 90.05) (size 0.8) (drill 0.4) (layers "F.Cu" "B.Cu") (free) (net 11))
  (via (at 98.45 82.3) (size 0.8) (drill 0.4) (layers "F.Cu" "B.Cu") (free) (net 11))
  (via (at 185.8 88.85) (size 0.8) (drill 0.4) (layers "F.Cu" "B.Cu") (free) (net 11))
  (via (at 149.5 91.7) (size 0.8) (drill 0.4) (layers "F.Cu" "B.Cu") (free) (net 11))
  (via (at 92.8 95) (size 0.8) (drill 0.4) (layers "F.Cu" "B.Cu") (free) (net 11))
  (via (at 114.9 91) (size 0.8) (drill 0.4) (layers "F.Cu" "B.Cu") (free) (net 11))
  (via (at 145 113.6) (size 0.8) (drill 0.4) (layers "F.Cu" "B.Cu") (free) (net 11))
  (via (at 145 106.8) (size 0.8) (drill 0.4) (layers "F.Cu" "B.Cu") (free) (net 11))
  (via (at 118.9 88.6) (size 0.8) (drill 0.4) (layers "F.Cu" "B.Cu") (free) (net 11))
  (via (at 183.65 88.6) (size 0.8) (drill 0.4) (layers "F.Cu" "B.Cu") (free) (net 11))
  (via (at 181.25 90.9) (size 0.8) (drill 0.4) (layers "F.Cu" "B.Cu") (free) (net 11))
  (via (at 133.4 125) (size 0.8) (drill 0.4) (layers "F.Cu" "B.Cu") (free) (net 11))
  (via (at 96.8 95) (size 0.8) (drill 0.4) (layers "F.Cu" "B.Cu") (free) (net 11))
  (via (at 116.5 91) (size 0.8) (drill 0.4) (layers "F.Cu" "B.Cu") (free) (net 11))
  (via (at 168.7 91.45) (size 0.8) (drill 0.4) (layers "F.Cu" "B.Cu") (free) (net 11))
  (via (at 136.9 89.6) (size 0.8) (drill 0.4) (layers "F.Cu" "B.Cu") (free) (net 11))
  (via (at 96.25 77.95) (size 0.8) (drill 0.4) (layers "F.Cu" "B.Cu") (free) (net 11))
  (via (at 167.2 91.3) (size 0.8) (drill 0.4) (layers "F.Cu" "B.Cu") (free) (net 11))
  (via (at 184.4 90.6) (size 0.8) (drill 0.4) (layers "F.Cu" "B.Cu") (free) (net 11))
  (via (at 97.05 77.15) (size 0.8) (drill 0.4) (layers "F.Cu" "B.Cu") (free) (net 11))
  (via (at 96.25 74.75) (size 0.8) (drill 0.4) (layers "F.Cu" "B.Cu") (free) (net 11))
  (via (at 114.45 90.25) (size 0.8) (drill 0.4) (layers "F.Cu" "B.Cu") (free) (net 11))
  (via (at 135.45 89.5) (size 0.8) (drill 0.4) (layers "F.Cu" "B.Cu") (free) (net 11))
  (via (at 111 100.2) (size 0.8) (drill 0.4) (layers "F.Cu" "B.Cu") (free) (net 11))
  (via (at 134.3 90.4) (size 0.8) (drill 0.4) (layers "F.Cu" "B.Cu") (free) (net 11))
  (via (at 137.7 88.8) (size 0.8) (drill 0.4) (layers "F.Cu" "B.Cu") (free) (net 11))
  (via (at 183 91.7) (size 0.8) (drill 0.4) (layers "F.Cu" "B.Cu") (free) (net 11))
  (via (at 115.7 90.2) (size 0.8) (drill 0.4) (layers "F.Cu" "B.Cu") (free) (net 11))
  (via (at 129.6 107) (size 0.8) (drill 0.4) (layers "F.Cu" "B.Cu") (free) (net 11))
  (via (at 166.4 90.5) (size 0.8) (drill 0.4) (layers "F.Cu" "B.Cu") (free) (net 11))
  (via (at 169.6 88.9) (size 0.8) (drill 0.4) (layers "F.Cu" "B.Cu") (free) (net 11))
  (via (at 110.2 104.4) (size 0.8) (drill 0.4) (layers "F.Cu" "B.Cu") (free) (net 11))
  (via (at 153.5 91.3) (size 0.8) (drill 0.4) (layers "F.Cu" "B.Cu") (free) (net 11))
  (via (at 150.3 91.15) (size 0.8) (drill 0.4) (layers "F.Cu" "B.Cu") (free) (net 11))
  (via (at 132.1 89.6) (size 0.8) (drill 0.4) (layers "F.Cu" "B.Cu") (free) (net 11))
  (via (at 117.1 90.2) (size 0.8) (drill 0.4) (layers "F.Cu" "B.Cu") (free) (net 11))
  (via (at 133.4 113.6) (size 0.8) (drill 0.4) (layers "F.Cu" "B.Cu") (free) (net 11))
  (via (at 112.4 100.2) (size 0.8) (drill 0.4) (layers "F.Cu" "B.Cu") (free) (net 11))
  (via (at 96.2 94.1) (size 0.8) (drill 0.4) (layers "F.Cu" "B.Cu") (free) (net 11))
  (via (at 124.2 109.2) (size 0.8) (drill 0.4) (layers "F.Cu" "B.Cu") (free) (net 11))
  (via (at 136.3 90.4) (size 0.8) (drill 0.4) (layers "F.Cu" "B.Cu") (free) (net 11))
  (via (at 99.35 81.55) (size 0.8) (drill 0.4) (layers "F.Cu" "B.Cu") (free) (net 11))
  (via (at 99.2 83) (size 0.8) (drill 0.4) (layers "F.Cu" "B.Cu") (free) (net 11))
  (via (at 97.2 82.85) (size 0.8) (drill 0.4) (layers "F.Cu" "B.Cu") (free) (net 11))
  (via (at 119.6 109) (size 0.8) (drill 0.4) (layers "F.Cu" "B.Cu") (free) (net 11))
  (via (at 119.1 90.2) (size 0.8) (drill 0.4) (layers "F.Cu" "B.Cu") (free) (net 11))
  (via (at 97.85 77.95) (size 0.8) (drill 0.4) (layers "F.Cu" "B.Cu") (free) (net 11))
  (via (at 148.6 90) (size 0.8) (drill 0.4) (layers "F.Cu" "B.Cu") (free) (net 11))
  (via (at 100.95 81.55) (size 0.8) (drill 0.4) (layers "F.Cu" "B.Cu") (free) (net 11))
  (via (at 153.5 89.7) (size 0.8) (drill 0.4) (layers "F.Cu" "B.Cu") (free) (net 11))
  (via (at 150.8 90.4) (size 0.8) (drill 0.4) (layers "F.Cu" "B.Cu") (free) (net 11))
  (via (at 150.6 129.2) (size 0.8) (drill 0.4) (layers "F.Cu" "B.Cu") (free) (net 11))
  (via (at 154 134.8) (size 0.8) (drill 0.4) (layers "F.Cu" "B.Cu") (net 11))
  (via (at 148.6 124.4) (size 0.8) (drill 0.4) (layers "F.Cu" "B.Cu") (free) (net 11))
  (via (at 94 95) (size 0.8) (drill 0.4) (layers "F.Cu" "B.Cu") (free) (net 11))
  (via (at 133.7 91.2) (size 0.8) (drill 0.4) (layers "F.Cu" "B.Cu") (free) (net 11))
  (via (at 137.6 106.8) (size 0.8) (drill 0.4) (layers "F.Cu" "B.Cu") (free) (net 11))
  (via (at 119.05 91.7) (size 0.8) (drill 0.4) (layers "F.Cu" "B.Cu") (free) (net 11))
  (via (at 145 120.6) (size 0.8) (drill 0.4) (layers "F.Cu" "B.Cu") (free) (net 11))
  (via (at 143.3 100.3) (size 0.8) (drill 0.4) (layers "F.Cu" "B.Cu") (net 11))
  (via (at 145 110.4) (size 0.8) (drill 0.4) (layers "F.Cu" "B.Cu") (free) (net 11))
  (via (at 120.5 88.6) (size 0.8) (drill 0.4) (layers "F.Cu" "B.Cu") (free) (net 11))
  (via (at 115 108.6) (size 0.8) (drill 0.4) (layers "F.Cu" "B.Cu") (free) (net 11))
  (via (at 152.85 90.35) (size 0.8) (drill 0.4) (layers "F.Cu" "B.Cu") (free) (net 11))
  (via (at 133.6 120.6) (size 0.8) (drill 0.4) (layers "F.Cu" "B.Cu") (free) (net 11))
  (via (at 154.3 90.3) (size 0.8) (drill 0.4) (layers "F.Cu" "B.Cu") (free) (net 11))
  (via (at 167.7 92) (size 0.8) (drill 0.4) (layers "F.Cu" "B.Cu") (free) (net 11))
  (via (at 97.85 76.35) (size 0.8) (drill 0.4) (layers "F.Cu" "B.Cu") (free) (net 11))
  (via (at 97.4 105.4) (size 0.8) (drill 0.4) (layers "F.Cu" "B.Cu") (net 11))
  (via (at 129.6 110.6) (size 0.8) (drill 0.4) (layers "F.Cu" "B.Cu") (free) (net 11))
  (via (at 183.15 90.2) (size 0.8) (drill 0.4) (layers "F.Cu" "B.Cu") (free) (net 11))
  (via (at 134.35 91.85) (size 0.8) (drill 0.4) (layers "F.Cu" "B.Cu") (free) (net 11))
  (via (at 97.85 74.75) (size 0.8) (drill 0.4) (layers "F.Cu" "B.Cu") (free) (net 11))
  (via (at 141 117) (size 0.8) (drill 0.4) (layers "F.Cu" "B.Cu") (free) (net 11))
  (via (at 111.6 101.4) (size 0.8) (drill 0.4) (layers "F.Cu" "B.Cu") (free) (net 11))
  (via (at 141.2 110.4) (size 0.8) (drill 0.4) (layers "F.Cu" "B.Cu") (free) (net 11))
  (via (at 137.6 98.6) (size 0.8) (drill 0.4) (layers "F.Cu" "B.Cu") (free) (net 11))
  (via (at 115.7 91.8) (size 0.8) (drill 0.4) (layers "F.Cu" "B.Cu") (free) (net 11))
  (via (at 145.2 117.2) (size 0.8) (drill 0.4) (layers "F.Cu" "B.Cu") (free) (net 11))
  (via (at 141.2 113.6) (size 0.8) (drill 0.4) (layers "F.Cu" "B.Cu") (free) (net 11))
  (via (at 169.65 90.45) (size 0.8) (drill 0.4) (layers "F.Cu" "B.Cu") (free) (net 11))
  (via (at 122.6 115) (size 0.8) (drill 0.4) (layers "F.Cu" "B.Cu") (free) (net 11))
  (via (at 133.6 117) (size 0.8) (drill 0.4) (layers "F.Cu" "B.Cu") (free) (net 11))
  (via (at 154.3 88.9) (size 0.8) (drill 0.4) (layers "F.Cu" "B.Cu") (free) (net 11))
  (via (at 118.1 91.25) (size 0.8) (drill 0.4) (layers "F.Cu" "B.Cu") (free) (net 11))
  (via (at 146 129) (size 0.8) (drill 0.4) (layers "F.Cu" "B.Cu") (free) (net 11))
  (via (at 114.9 89.4) (size 0.8) (drill 0.4) (layers "F.Cu" "B.Cu") (free) (net 11))
  (via (at 125 105.8) (size 0.8) (drill 0.4) (layers "F.Cu" "B.Cu") (free) (net 11))
  (via (at 133.4 106.8) (size 0.8) (drill 0.4) (layers "F.Cu" "B.Cu") (free) (net 11))
  (via (at 97.85 79.55) (size 0.8) (drill 0.4) (layers "F.Cu" "B.Cu") (free) (net 11))
  (via (at 141.6 128.8) (size 0.8) (drill 0.4) (layers "F.Cu" "B.Cu") (free) (net 11))
  (via (at 119.7 89.4) (size 0.8) (drill 0.4) (layers "F.Cu" "B.Cu") (free) (net 11))
  (via (at 169.85 92) (size 0.8) (drill 0.4) (layers "F.Cu" "B.Cu") (free) (net 11))
  (via (at 111 102.8) (size 0.8) (drill 0.4) (layers "F.Cu" "B.Cu") (free) (net 11))
  (via (at 137.6 110.4) (size 0.8) (drill 0.4) (layers "F.Cu" "B.Cu") (free) (net 11))
  (via (at 165.6 89.7) (size 0.8) (drill 0.4) (layers "F.Cu" "B.Cu") (free) (net 11))
  (via (at 97.05 78.75) (size 0.8) (drill 0.4) (layers "F.Cu" "B.Cu") (free) (net 11))
  (via (at 184.4 91.7) (size 0.8) (drill 0.4) (layers "F.Cu" "B.Cu") (free) (net 11))
  (via (at 93.4 94.2) (size 0.8) (drill 0.4) (layers "F.Cu" "B.Cu") (free) (net 11))
  (via (at 140.6 120.8) (size 0.8) (drill 0.4) (layers "F.Cu" "B.Cu") (free) (net 11))
  (via (at 111.6 104.4) (size 0.8) (drill 0.4) (layers "F.Cu" "B.Cu") (free) (net 11))
  (via (at 117.15 91.7) (size 0.8) (drill 0.4) (layers "F.Cu" "B.Cu") (free) (net 11))
  (segment (start 100.9 88.6) (end 101 88.7) (width 0.25) (layer "F.Cu") (net 12))
  (segment (start 101 89.9) (end 100.85 90.05) (width 0.25) (layer "F.Cu") (net 12))
  (segment (start 100.235 88.6) (end 100.9 88.6) (width 0.25) (layer "F.Cu") (net 12))
  (segment (start 101 88.7) (end 101 89.9) (width 0.25) (layer "F.Cu") (net 12))
  (segment (start 100.85 90.05) (end 99.85 90.05) (width 0.25) (layer "F.Cu") (net 12))
  (segment (start 97.25 91) (end 98.525 91) (width 0.25) (layer "F.Cu") (net 13))
  (segment (start 98.525 91) (end 98.95 90.575) (width 0.25) (layer "F.Cu") (net 13))
  (segment (start 99.265 89.085) (end 99.265 88.6) (width 0.25) (layer "F.Cu") (net 13))
  (segment (start 98.95 90.575) (end 98.95 89.4) (width 0.25) (layer "F.Cu") (net 13))
  (segment (start 98.95 89.4) (end 99.265 89.085) (width 0.25) (layer "F.Cu") (net 13))
  (segment (start 187.55 113.3) (end 188.585 113.3) (width 0.325) (layer "F.Cu") (net 14))
  (segment (start 179.65 113.2895) (end 179.8895 113.05) (width 0.325) (layer "F.Cu") (net 14))
  (segment (start 187.45 113.2) (end 187.55 113.3) (width 0.325) (layer "F.Cu") (net 14))
  (segment (start 185.615 113.8) (end 186.45 113.8) (width 0.325) (layer "F.Cu") (net 14))
  (segment (start 179.8895 113.05) (end 181.868 113.05) (width 0.325) (layer "F.Cu") (net 14))
  (segment (start 186.45 113.8) (end 187.05 113.2) (width 0.325) (layer "F.Cu") (net 14))
  (segment (start 177.426 116.579386) (end 177.426 116.574) (width 0.325) (layer "F.Cu") (net 14))
  (segment (start 181.9075 113.1) (end 182.8 113.1) (width 0.325) (layer "F.Cu") (net 14))
  (segment (start 177.426 116.574) (end 179.65 114.35) (width 0.325) (layer "F.Cu") (net 14))
  (segment (start 163.9375 118.95) (end 163.961499 118.973999) (width 0.325) (layer "F.Cu") (net 14))
  (segment (start 179.65 113.3395) (end 179.65 114.35) (width 0.325) (layer "F.Cu") (net 14))
  (segment (start 175.031387 118.973999) (end 177.426 116.579386) (width 0.325) (layer "F.Cu") (net 14))
  (segment (start 163.961499 118.973999) (end 175.031387 118.973999) (width 0.325) (layer "F.Cu") (net 14))
  (segment (start 187.45 113.2) (end 187.05 113.2) (width 0.325) (layer "F.Cu") (net 14))
  (via (at 187.45 113.2) (size 0.6) (drill 0.25) (layers "F.Cu" "B.Cu") (net 14))
  (via (at 182.8 113.15) (size 0.6) (drill 0.25) (layers "F.Cu" "B.Cu") (net 14))
  (segment (start 185.344615 112.074) (end 186.619614 113.348999) (width 0.325) (layer "B.Cu") (net 14))
  (segment (start 187.301001 113.348999) (end 187.45 113.2) (width 0.325) (layer "B.Cu") (net 14))
  (segment (start 182.8 113.15) (end 183.876 112.074) (width 0.325) (layer "B.Cu") (net 14))
  (segment (start 183.876 112.074) (end 185.344615 112.074) (width 0.325) (layer "B.Cu") (net 14))
  (segment (start 186.619614 113.348999) (end 187.301001 113.348999) (width 0.325) (layer "B.Cu") (net 14))
  (segment (start 180.3 114.35) (end 177.624 117.026) (width 0.325) (layer "F.Cu") (net 15))
  (segment (start 182.7 113.8) (end 182.8 113.9) (width 0.325) (layer "F.Cu") (net 15))
  (segment (start 177.624 117.026) (end 177.618614 117.026) (width 0.325) (layer "F.Cu") (net 15))
  (segment (start 163.9615 119.426) (end 163.9375 119.45) (width 0.325) (layer "F.Cu") (net 15))
  (segment (start 180.85 114.35) (end 180.3 114.35) (width 0.325) (layer "F.Cu") (net 15))
  (segment (start 184.55 113.55) (end 184.8 113.3) (width 0.325) (layer "F.Cu") (net 15))
  (segment (start 187.45 113.95) (end 187.6 113.8) (width 0.325) (layer "F.Cu") (net 15))
  (segment (start 181.9075 113.8) (end 181.387 113.8) (width 0.325) (layer "F.Cu") (net 15))
  (segment (start 184.8 113.3) (end 185.615 113.3) (width 0.325) (layer "F.Cu") (net 15))
  (segment (start 173.426 119.750059) (end 173.426 119.726) (width 0.325) (layer "F.Cu") (net 15))
  (segment (start 181.387 113.8) (end 181.387 113.813) (width 0.325) (layer "F.Cu") (net 15))
  (segment (start 173.126 119.426) (end 163.961499 119.426001) (width 0.325) (layer "F.Cu") (net 15))
  (segment (start 174.026 119.726) (end 174.026 119.750059) (width 0.325) (layer "F.Cu") (net 15))
  (segment (start 187.6 113.8) (end 188.585 113.8) (width 0.325) (layer "F.Cu") (net 15))
  (segment (start 181.9075 113.8) (end 182.7 113.8) (width 0.325) (layer "F.Cu") (net 15))
  (segment (start 181.387 113.813) (end 180.85 114.35) (width 0.325) (layer "F.Cu") (net 15))
  (segment (start 163.961499 119.426001) (end 163.9375 119.45) (width 0.325) (layer "F.Cu") (net 15))
  (segment (start 177.618614 117.026) (end 175.218614 119.426) (width 0.325) (layer "F.Cu") (net 15))
  (segment (start 175.218614 119.426) (end 174.326 119.426) (width 0.325) (layer "F.Cu") (net 15))
  (via (at 182.8 113.9) (size 0.6) (drill 0.25) (layers "F.Cu" "B.Cu") (net 15))
  (via (at 187.45 113.95) (size 0.6) (drill 0.25) (layers "F.Cu" "B.Cu") (net 15))
  (via (at 184.55 113.55) (size 0.6) (drill 0.25) (layers "F.Cu" "B.Cu") (net 15))
  (arc (start 173.426 119.726) (mid 173.338132 119.513868) (end 173.126 119.426) (width 0.325) (layer "F.Cu") (net 15))
  (arc (start 173.726 120.050059) (mid 173.513868 119.962191) (end 173.426 119.750059) (width 0.325) (layer "F.Cu") (net 15))
  (arc (start 174.326 119.426) (mid 174.113868 119.513868) (end 174.026 119.726) (width 0.325) (layer "F.Cu") (net 15))
  (arc (start 174.026 119.750059) (mid 173.938132 119.962191) (end 173.726 120.050059) (width 0.325) (layer "F.Cu") (net 15))
  (segment (start 185.740695 113.109305) (end 185.3 113.55) (width 0.325) (layer "B.Cu") (net 15))
  (segment (start 184.15 112.85) (end 185.48139 112.85) (width 0.325) (layer "B.Cu") (net 15))
  (segment (start 187.301001 113.801001) (end 187.45 113.95) (width 0.325) (layer "B.Cu") (net 15))
  (segment (start 183.1 113.9) (end 184.15 112.85) (width 0.325) (layer "B.Cu") (net 15))
  (segment (start 185.48139 112.85) (end 185.740695 113.109305) (width 0.325) (layer "B.Cu") (net 15))
  (segment (start 185.3 113.55) (end 184.55 113.55) (width 0.325) (layer "B.Cu") (net 15))
  (segment (start 185.740695 113.109305) (end 186.065695 113.434305) (width 0.325) (layer "B.Cu") (net 15))
  (segment (start 182.8 113.9) (end 183.1 113.9) (width 0.325) (layer "B.Cu") (net 15))
  (segment (start 186.432389 113.800999) (end 186.432388 113.801001) (width 0.325) (layer "B.Cu") (net 15))
  (segment (start 186.065695 113.434305) (end 186.432389 113.800999) (width 0.325) (layer "B.Cu") (net 15))
  (segment (start 186.432388 113.801001) (end 187.301001 113.801001) (width 0.325) (layer "B.Cu") (net 15))
  (segment (start 105.847132 96.226324) (end 106.197132 96.576324) (width 0.25) (layer "F.Cu") (net 16))
  (segment (start 104.647132 96.526324) (end 104.947132 96.226324) (width 0.25) (layer "F.Cu") (net 16))
  (segment (start 104.647132 97.041324) (end 104.647132 96.526324) (width 0.25) (layer "F.Cu") (net 16))
  (segment (start 104.947132 96.226324) (end 105.847132 96.226324) (width 0.25) (layer "F.Cu") (net 16))
  (segment (start 106.197132 96.576324) (end 106.197132 97.776324) (width 0.25) (layer "F.Cu") (net 16))
  (segment (start 161.3 98.9) (end 161.4 98.9) (width 0.25) (layer "F.Cu") (net 17))
  (segment (start 177.55 105.55) (end 177.335 105.335) (width 0.25) (layer "F.Cu") (net 17))
  (segment (start 181.62 104.17) (end 181.65 104.2) (width 0.2) (layer "F.Cu") (net 17))
  (segment (start 180.225 105.55) (end 177.55 105.55) (width 0.25) (layer "F.Cu") (net 17))
  (segment (start 181.65 104.2) (end 181.65 105.3) (width 0.2) (layer "F.Cu") (net 17))
  (segment (start 181.62 103.6) (end 181.62 104.17) (width 0.2) (layer "F.Cu") (net 17))
  (segment (start 178.335 97.865) (end 178.335 98.865) (width 0.25) (layer "F.Cu") (net 17))
  (segment (start 161 99.2) (end 161.3 98.9) (width 0.25) (layer "F.Cu") (net 17))
  (segment (start 180.05 96.15) (end 182.1 96.15) (width 0.25) (layer "F.Cu") (net 17))
  (segment (start 161.415 98.915) (end 162.265 98.915) (width 0.25) (layer "F.Cu") (net 17))
  (segment (start 182.1 96.15) (end 182.55 96.15) (width 0.25) (layer "F.Cu") (net 17))
  (segment (start 182.954 103.25) (end 184.175 103.25) (width 0.25) (layer "F.Cu") (net 17))
  (segment (start 153.075 102.1125) (end 153.075 99.175) (width 0.25) (layer "F.Cu") (net 17))
  (segment (start 160.7 98.9) (end 161.3 98.9) (width 0.25) (layer "F.Cu") (net 17))
  (segment (start 181.4 105.55) (end 180.225 105.55) (width 0.2) (layer "F.Cu") (net 17))
  (segment (start 183.25 95.45) (end 184.175 95.45) (width 0.25) (layer "F.Cu") (net 17))
  (segment (start 182.004 104.2) (end 182.954 103.25) (width 0.25) (layer "F.Cu") (net 17))
  (segment (start 178.335 98.915) (end 178.335 98.865) (width 0.25) (layer "F.Cu") (net 17))
  (segment (start 161 101.7) (end 161 99.2) (width 0.25) (layer "F.Cu") (net 17))
  (segment (start 180.05 96.15) (end 178.335 97.865) (width 0.25) (layer "F.Cu") (net 17))
  (segment (start 162.925 99.575) (end 172.625 99.575) (width 0.25) (layer "F.Cu") (net 17))
  (segment (start 161.4 98.9) (end 161.415 98.915) (width 0.25) (layer "F.Cu") (net 17))
  (segment (start 173.285 98.915) (end 178.335 98.915) (width 0.25) (layer "F.Cu") (net 17))
  (segment (start 181.65 104.2) (end 182.004 104.2) (width 0.25) (layer "F.Cu") (net 17))
  (segment (start 177.335 105.335) (end 177.335 103.85) (width 0.25) (layer "F.Cu") (net 17))
  (segment (start 181.65 105.3) (end 181.4 105.55) (width 0.2) (layer "F.Cu") (net 17))
  (segment (start 162.265 98.915) (end 162.925 99.575) (width 0.25) (layer "F.Cu") (net 17))
  (segment (start 182.17 95.6) (end 182.17 96.08) (width 0.2) (layer "F.Cu") (net 17))
  (segment (start 153.075 99.175) (end 153.35 98.9) (width 0.25) (layer "F.Cu") (net 17))
  (segment (start 182.17 96.08) (end 182.1 96.15) (width 0.2) (layer "F.Cu") (net 17))
  (segment (start 160.7 98.9) (end 161 99.2) (width 0.25) (layer "F.Cu") (net 17))
  (segment (start 177.35 101.95) (end 177.35 103.835) (width 0.25) (layer "F.Cu") (net 17))
  (segment (start 182.55 96.15) (end 183.25 95.45) (width 0.25) (layer "F.Cu") (net 17))
  (segment (start 172.625 99.575) (end 173.285 98.915) (width 0.25) (layer "F.Cu") (net 17))
  (segment (start 153.35 98.9) (end 160.7 98.9) (width 0.25) (layer "F.Cu") (net 17))
  (via (at 177.35 101.95) (size 0.6) (drill 0.25) (layers "F.Cu" "B.Cu") (net 17))
  (via (at 178.35 98.9) (size 0.6) (drill 0.25) (layers "F.Cu" "B.Cu") (net 17))
  (segment (start 177.35 101.95) (end 177.35 100.4) (width 0.25) (layer "In2.Cu") (net 17))
  (segment (start 177.35 100.4) (end 178.335 99.415) (width 0.25) (layer "In2.Cu") (net 17))
  (segment (start 178.335 99.415) (end 178.335 99.385) (width 0.25) (layer "In2.Cu") (net 17))
  (segment (start 178.335 98.915) (end 178.335 99.385) (width 0.25) (layer "In2.Cu") (net 17))
  (segment (start 153.725 104.125) (end 154.7 105.1) (width 0.25) (layer "F.Cu") (net 18))
  (segment (start 154.7 105.1) (end 160.1 105.1) (width 0.25) (layer "F.Cu") (net 18))
  (segment (start 175.6 100.35) (end 175.6 100.4) (width 0.25) (layer "F.Cu") (net 18))
  (segment (start 182.25 94.45) (end 177.75 94.45) (width 0.25) (layer "F.Cu") (net 18))
  (segment (start 175.6 100.4) (end 176.89 100.4) (width 0.25) (layer "F.Cu") (net 18))
  (segment (start 173.175 105.55) (end 175.85 105.55) (width 0.25) (layer "F.Cu") (net 18))
  (segment (start 175.25 100.35) (end 175.6 100.35) (width 0.25) (layer "F.Cu") (net 18))
  (segment (start 175.6 101.15) (end 176.065 101.615) (width 0.25) (layer "F.Cu") (net 18))
  (segment (start 182.17 94.9) (end 182.17 94.53) (width 0.2) (layer "F.Cu") (net 18))
  (segment (start 161.625 101.125) (end 161.625 102.12) (width 0.25) (layer "F.Cu") (net 18))
  (segment (start 160.1 105.1) (end 161.625 103.575) (width 0.25) (layer "F.Cu") (net 18))
  (segment (start 176.065 101.615) (end 176.065 103.85) (width 0.25) (layer "F.Cu") (net 18))
  (segment (start 175.25 100.35) (end 162.4 100.35) (width 0.25) (layer "F.Cu") (net 18))
  (segment (start 182.25 94.45) (end 184.175 94.45) (width 0.25) (layer "F.Cu") (net 18))
  (segment (start 175.85 105.55) (end 176.065 105.335) (width 0.25) (layer "F.Cu") (net 18))
  (segment (start 179.365 100.12) (end 177.17 100.12) (width 0.25) (layer "F.Cu") (net 18))
  (segment (start 176.89 100.4) (end 177.17 100.12) (width 0.25) (layer "F.Cu") (net 18))
  (segment (start 175.6 100.4) (end 175.6 101.15) (width 0.25) (layer "F.Cu") (net 18))
  (segment (start 177.15 95.05) (end 177.15 96.25) (width 0.25) (layer "F.Cu") (net 18))
  (segment (start 161.625 103.575) (end 161.625 102.12) (width 0.25) (layer "F.Cu") (net 18))
  (segment (start 176.065 105.335) (end 176.065 103.85) (width 0.25) (layer "F.Cu") (net 18))
  (segment (start 177.75 94.45) (end 177.15 95.05) (width 0.25) (layer "F.Cu") (net 18))
  (segment (start 153.725 102.1125) (end 153.725 104.125) (width 0.25) (layer "F.Cu") (net 18))
  (segment (start 177.15 96.25) (end 175.95 96.25) (width 0.25) (layer "F.Cu") (net 18))
  (segment (start 162.4 100.35) (end 161.625 101.125) (width 0.25) (layer "F.Cu") (net 18))
  (segment (start 182.17 94.53) (end 182.25 94.45) (width 0.2) (layer "F.Cu") (net 18))
  (via (at 177.15 96.25) (size 0.6) (drill 0.25) (layers "F.Cu" "B.Cu") (net 18))
  (via (at 175.6 100.4) (size 0.6) (drill 0.25) (layers "F.Cu" "B.Cu") (net 18))
  (segment (start 175.6 100) (end 175.6 100.35) (width 0.25) (layer "In2.Cu") (net 18))
  (segment (start 175.6 100) (end 175.6 97.9) (width 0.25) (layer "In2.Cu") (net 18))
  (segment (start 175.6 97.8) (end 175.6 97.9) (width 0.25) (layer "In2.Cu") (net 18))
  (segment (start 177.15 96.25) (end 175.6 97.8) (width 0.25) (layer "In2.Cu") (net 18))
  (segment (start 184.175 93.45) (end 181.95 93.45) (width 0.25) (layer "F.Cu") (net 19))
  (segment (start 182.25 100.85) (end 182.25 100) (width 0.25) (layer "F.Cu") (net 20))
  (segment (start 182.65 101.25) (end 182.25 100.85) (width 0.25) (layer "F.Cu") (net 20))
  (segment (start 184.175 101.25) (end 182.65 101.25) (width 0.25) (layer "F.Cu") (net 20))
  (segment (start 116.8 82.685) (end 116.8 83.955) (width 0.25) (layer "F.Cu") (net 21))
  (via (at 122.3 90.4) (size 0.8) (drill 0.4) (layers "F.Cu" "B.Cu") (free) (net 21))
  (via (at 123.8 90.4) (size 0.8) (drill 0.4) (layers "F.Cu" "B.Cu") (free) (net 21))
  (via (at 121.25 81.9) (size 0.8) (drill 0.4) (layers "F.Cu" "B.Cu") (free) (net 21))
  (via (at 116 86.3) (size 0.8) (drill 0.4) (layers "F.Cu" "B.Cu") (free) (net 21))
  (via (at 123.7 81.9) (size 0.8) (drill 0.4) (layers "F.Cu" "B.Cu") (free) (net 21))
  (via (at 118.65 85.4) (size 0.8) (drill 0.4) (layers "F.Cu" "B.Cu") (free) (net 21))
  (via (at 122.35 89.25) (size 0.8) (drill 0.4) (layers "F.Cu" "B.Cu") (free) (net 21))
  (via (at 122.95 88.05) (size 0.8) (drill 0.4) (layers "F.Cu" "B.Cu") (free) (net 21))
  (via (at 124.15 85.15) (size 0.8) (drill 0.4) (layers "F.Cu" "B.Cu") (free) (net 21))
  (via (at 120.7 82.8) (size 0.8) (drill 0.4) (layers "F.Cu" "B.Cu") (free) (net 21))
  (via (at 123.7 85.9) (size 0.8) (drill 0.4) (layers "F.Cu" "B.Cu") (free) (net 21))
  (via (at 122.5 81.9) (size 0.8) (drill 0.4) (layers "F.Cu" "B.Cu") (free) (net 21))
  (via (at 122.85 85.9) (size 0.8) (drill 0.4) (layers "F.Cu" "B.Cu") (free) (net 21))
  (via (at 123.3 85.15) (size 0.8) (drill 0.4) (layers "F.Cu" "B.Cu") (free) (net 21))
  (via (at 123.75 79.8) (size 0.8) (drill 0.4) (layers "F.Cu" "B.Cu") (free) (net 21))
  (via (at 121.3 79.8) (size 0.8) (drill 0.4) (layers "F.Cu" "B.Cu") (free) (net 21))
  (via (at 120 81.9) (size 0.8) (drill 0.4) (layers "F.Cu" "B.Cu") (free) (net 21))
  (via (at 113 85.5) (size 0.8) (drill 0.4) (layers "F.Cu" "B.Cu") (free) (net 21))
  (via (at 120.05 79.8) (size 0.8) (drill 0.4) (layers "F.Cu" "B.Cu") (free) (net 21))
  (via (at 123.1 82.8) (size 0.8) (drill 0.4) (layers "F.Cu" "B.Cu") (free) (net 21))
  (via (at 122.45 85.15) (size 0.8) (drill 0.4) (layers "F.Cu" "B.Cu") (free) (net 21))
  (via (at 122.3 91.58) (size 0.8) (drill 0.4) (layers "F.Cu" "B.Cu") (free) (net 21))
  (via (at 122.55 79.8) (size 0.8) (drill 0.4) (layers "F.Cu" "B.Cu") (free) (net 21))
  (via (at 122 85.9) (size 0.8) (drill 0.4) (layers "F.Cu" "B.Cu") (free) (net 21))
  (via (at 116.9 86.3) (size 0.8) (drill 0.4) (layers "F.Cu" "B.Cu") (free) (net 21))
  (via (at 123.8 91.62) (size 0.8) (drill 0.4) (layers "F.Cu" "B.Cu") (free) (net 21))
  (via (at 123.8 89.25) (size 0.8) (drill 0.4) (layers "F.Cu" "B.Cu") (free) (net 21))
  (via (at 114.8 85.5) (size 0.8) (drill 0.4) (layers "F.Cu" "B.Cu") (free) (net 21))
  (via (at 113.9 85.5) (size 0.8) (drill 0.4) (layers "F.Cu" "B.Cu") (free) (net 21))
  (via (at 120.75 85.55) (size 0.8) (drill 0.4) (layers "F.Cu" "B.Cu") (free) (net 21))
  (via (at 121.9 82.8) (size 0.8) (drill 0.4) (layers "F.Cu" "B.Cu") (free) (net 21))
  (via (at 113.85 82.95) (size 0.8) (drill 0.4) (layers "F.Cu" "B.Cu") (free) (net 21))
  (via (at 119.7 85.55) (size 0.8) (drill 0.4) (layers "F.Cu" "B.Cu") (free) (net 21))
  (via (at 124.15 88.05) (size 0.8) (drill 0.4) (layers "F.Cu" "B.Cu") (free) (net 21))
  (via (at 118.1 86.05) (size 0.8) (drill 0.4) (layers "F.Cu" "B.Cu") (free) (net 21))
  (via (at 114.85 82.9) (size 0.8) (drill 0.4) (layers "F.Cu" "B.Cu") (free) (net 21))
  (segment (start 134.12 82.785) (end 134.12 84.055) (width 0.25) (layer "F.Cu") (net 22))
  (via (at 138.3 79.88) (size 0.8) (drill 0.4) (layers "F.Cu" "B.Cu") (free) (net 22))
  (via (at 130.2 85.8) (size 0.8) (drill 0.4) (layers "F.Cu" "B.Cu") (free) (net 22))
  (via (at 137 81.98) (size 0.8) (drill 0.4) (layers "F.Cu" "B.Cu") (free) (net 22))
  (via (at 137 85.65) (size 0.8) (drill 0.4) (layers "F.Cu" "B.Cu") (free) (net 22))
  (via (at 138.9 82.88) (size 0.8) (drill 0.4) (layers "F.Cu" "B.Cu") (free) (net 22))
  (via (at 131.1 85.8) (size 0.8) (drill 0.4) (layers "F.Cu" "B.Cu") (free) (net 22))
  (via (at 139.95 88.13) (size 0.8) (drill 0.4) (layers "F.Cu" "B.Cu") (free) (net 22))
  (via (at 137.95 85.65) (size 0.8) (drill 0.4) (layers "F.Cu" "B.Cu") (free) (net 22))
  (via (at 135.85 85.7) (size 0.8) (drill 0.4) (layers "F.Cu" "B.Cu") (free) (net 22))
  (via (at 137.7 82.88) (size 0.8) (drill 0.4) (layers "F.Cu" "B.Cu") (free) (net 22))
  (via (at 139.85 85.98) (size 0.8) (drill 0.4) (layers "F.Cu" "B.Cu") (free) (net 22))
  (via (at 139.5 81.98) (size 0.8) (drill 0.4) (layers "F.Cu" "B.Cu") (free) (net 22))
  (via (at 140.8 89.33) (size 0.8) (drill 0.4) (layers "F.Cu" "B.Cu") (free) (net 22))
  (via (at 141.15 88.13) (size 0.8) (drill 0.4) (layers "F.Cu" "B.Cu") (free) (net 22))
  (via (at 139.3 91.66) (size 0.8) (drill 0.4) (layers "F.Cu" "B.Cu") (free) (net 22))
  (via (at 141.15 85.23) (size 0.8) (drill 0.4) (layers "F.Cu" "B.Cu") (free) (net 22))
  (via (at 138.25 81.98) (size 0.8) (drill 0.4) (layers "F.Cu" "B.Cu") (free) (net 22))
  (via (at 131.85 82.98) (size 0.8) (drill 0.4) (layers "F.Cu" "B.Cu") (free) (net 22))
  (via (at 134.1 86.6) (size 0.8) (drill 0.4) (layers "F.Cu" "B.Cu") (free) (net 22))
  (via (at 140.75 79.88) (size 0.8) (drill 0.4) (layers "F.Cu" "B.Cu") (free) (net 22))
  (via (at 140.3 85.23) (size 0.8) (drill 0.4) (layers "F.Cu" "B.Cu") (free) (net 22))
  (via (at 139.35 89.33) (size 0.8) (drill 0.4) (layers "F.Cu" "B.Cu") (free) (net 22))
  (via (at 140.1 82.88) (size 0.8) (drill 0.4) (layers "F.Cu" "B.Cu") (free) (net 22))
  (via (at 140.7 81.98) (size 0.8) (drill 0.4) (layers "F.Cu" "B.Cu") (free) (net 22))
  (via (at 139 85.98) (size 0.8) (drill 0.4) (layers "F.Cu" "B.Cu") (free) (net 22))
  (via (at 140.8 90.48) (size 0.8) (drill 0.4) (layers "F.Cu" "B.Cu") (free) (net 22))
  (via (at 133.2 86.6) (size 0.8) (drill 0.4) (layers "F.Cu" "B.Cu") (free) (net 22))
  (via (at 139.3 90.48) (size 0.8) (drill 0.4) (layers "F.Cu" "B.Cu") (free) (net 22))
  (via (at 135.3 86.35) (size 0.8) (drill 0.4) (layers "F.Cu" "B.Cu") (free) (net 22))
  (via (at 139.45 85.23) (size 0.8) (drill 0.4) (layers "F.Cu" "B.Cu") (free) (net 22))
  (via (at 139.55 79.88) (size 0.8) (drill 0.4) (layers "F.Cu" "B.Cu") (free) (net 22))
  (via (at 140.8 91.7) (size 0.8) (drill 0.4) (layers "F.Cu" "B.Cu") (free) (net 22))
  (via (at 137.05 79.88) (size 0.8) (drill 0.4) (layers "F.Cu" "B.Cu") (free) (net 22))
  (via (at 140.7 85.98) (size 0.8) (drill 0.4) (layers "F.Cu" "B.Cu") (free) (net 22))
  (via (at 132 85.8) (size 0.8) (drill 0.4) (layers "F.Cu" "B.Cu") (free) (net 22))
  (segment (start 142.929932 94.548) (end 143.577932 93.9) (width 0.25) (layer "F.Cu") (net 23))
  (segment (start 112.035 89.4) (end 112.05 89.415) (width 0.25) (layer "F.Cu") (net 23))
  (segment (start 155.5 93.9) (end 156.6 95) (width 0.25) (layer "F.Cu") (net 23))
  (segment (start 112.5 87.4) (end 112.5 88.35) (width 0.25) (layer "F.Cu") (net 23))
  (segment (start 156.6 94.85) (end 156.6 95) (width 0.25) (layer "F.Cu") (net 23))
  (segment (start 112.5 94) (end 113.048 94.548) (width 0.25) (layer "F.Cu") (net 23))
  (segment (start 112.5 88.35) (end 112.035 88.815) (width 0.25) (layer "F.Cu") (net 23))
  (segment (start 157.725 102.12) (end 157.725 100.975) (width 0.25) (layer "F.Cu") (net 23))
  (segment (start 110.085 86.8) (end 111.4 86.8) (width 0.25) (layer "F.Cu") (net 23))
  (segment (start 113.048 94.548) (end 142.929932 94.548) (width 0.25) (layer "F.Cu") (net 23))
  (segment (start 111.45 86.75) (end 111.45 85.85) (width 0.25) (layer "F.Cu") (net 23))
  (segment (start 111.2 86.8) (end 111.9 86.8) (width 0.25) (layer "F.Cu") (net 23))
  (segment (start 112.035 88.815) (end 112.035 89.4) (width 0.25) (layer "F.Cu") (net 23))
  (segment (start 111.4 86.8) (end 111.45 86.75) (width 0.25) (layer "F.Cu") (net 23))
  (segment (start 156.6 95) (end 156.6 97.4) (width 0.25) (layer "F.Cu") (net 23))
  (segment (start 157.2 94.25) (end 156.6 94.85) (width 0.25) (layer "F.Cu") (net 23))
  (segment (start 112.05 90.3) (end 112.5 90.75) (width 0.25) (layer "F.Cu") (net 23))
  (segment (start 111.9 86.8) (end 112.5 87.4) (width 0.25) (layer "F.Cu") (net 23))
  (segment (start 112.5 90.75) (end 112.5 94) (width 0.25) (layer "F.Cu") (net 23))
  (segment (start 157.725 100.975) (end 157.25 100.5) (width 0.25) (layer "F.Cu") (net 23))
  (segment (start 112.05 89.415) (end 112.05 90.3) (width 0.25) (layer "F.Cu") (net 23))
  (segment (start 143.577932 93.9) (end 155.5 93.9) (width 0.25) (layer "F.Cu") (net 23))
  (via (at 157.25 100.5) (size 0.6) (drill 0.25) (layers "F.Cu" "B.Cu") (net 23))
  (via (at 156.6 97.4) (size 0.6) (drill 0.25) (layers "F.Cu" "B.Cu") (net 23))
  (segment (start 156.6 97.4) (end 156.6 99.8) (width 0.25) (layer "In2.Cu") (net 23))
  (segment (start 156.6 99.8) (end 157.25 100.5) (width 0.25) (layer "In2.Cu") (net 23))
  (segment (start 158.050001 93.499999) (end 158.55 93) (width 0.25) (layer "F.Cu") (net 24))
  (segment (start 158.05 93.65) (end 158.050001 93.499999) (width 0.25) (layer "F.Cu") (net 24))
  (segment (start 130.852 94.152) (end 142.448 94.152) (width 0.25) (layer "F.Cu") (net 24))
  (segment (start 127.585 86.9) (end 127.485 87) (width 0.25) (layer "F.Cu") (net 24))
  (segment (start 129.385 88.815) (end 129.385 89.4) (width 0.25) (layer "F.Cu") (net 24))
  (segment (start 129.2 86.9) (end 129.8 87.5) (width 0.25) (layer "F.Cu") (net 24))
  (segment (start 128.75 86.85) (end 128.7 86.9) (width 0.25) (layer "F.Cu") (net 24))
  (segment (start 157.8 93.4) (end 158.05 93.65) (width 0.25) (layer "F.Cu") (net 24))
  (segment (start 129.8 87.5) (end 129.8 88.4) (width 0.25) (layer "F.Cu") (net 24))
  (segment (start 129.8 88.4) (end 129.385 88.815) (width 0.25) (layer "F.Cu") (net 24))
  (segment (start 158.375 93.975) (end 158.375 96.38) (width 0.25) (layer "F.Cu") (net 24))
  (segment (start 158.05 93.65) (end 158.375 93.975) (width 0.25) (layer "F.Cu") (net 24))
  (segment (start 128.75 85.95) (end 128.75 86.85) (width 0.25) (layer "F.Cu") (net 24))
  (segment (start 129.385 92.685) (end 130.852 94.152) (width 0.25) (layer "F.Cu") (net 24))
  (segment (start 129.385 89.4) (end 129.385 92.685) (width 0.25) (layer "F.Cu") (net 24))
  (segment (start 143.2 93.4) (end 157.8 93.4) (width 0.25) (layer "F.Cu") (net 24))
  (segment (start 128.7 86.9) (end 127.585 86.9) (width 0.25) (layer "F.Cu") (net 24))
  (segment (start 142.448 94.152) (end 143.2 93.4) (width 0.25) (layer "F.Cu") (net 24))
  (segment (start 128.7 86.9) (end 129.2 86.9) (width 0.25) (layer "F.Cu") (net 24))
  (segment (start 182.2 82.7858) (end 182.2 84.0558) (width 0.25) (layer "F.Cu") (net 25))
  (via (at 185.15 85.65) (size 0.8) (drill 0.4) (layers "F.Cu" "B.Cu") (free) (net 25))
  (via (at 185.45 82) (size 0.8) (drill 0.4) (layers "F.Cu" "B.Cu") (free) (net 25))
  (via (at 187.7 85.25) (size 0.8) (drill 0.4) (layers "F.Cu" "B.Cu") (free) (net 25))
  (via (at 189.05 89.35) (size 0.8) (drill 0.4) (layers "F.Cu" "B.Cu") (free) (net 25))
  (via (at 186.55 79.9) (size 0.8) (drill 0.4) (layers "F.Cu" "B.Cu") (free) (net 25))
  (via (at 188.35 82.9) (size 0.8) (drill 0.4) (layers "F.Cu" "B.Cu") (free) (net 25))
  (via (at 189 79.9) (size 0.8) (drill 0.4) (layers "F.Cu" "B.Cu") (free) (net 25))
  (via (at 189.05 90.5) (size 0.8) (drill 0.4) (layers "F.Cu" "B.Cu") (free) (net 25))
  (via (at 183.3 86.25) (size 0.8) (drill 0.4) (layers "F.Cu" "B.Cu") (free) (net 25))
  (via (at 186.15 85.65) (size 0.8) (drill 0.4) (layers "F.Cu" "B.Cu") (free) (net 25))
  (via (at 189.3 84.85) (size 0.8) (drill 0.4) (layers "F.Cu" "B.Cu") (free) (net 25))
  (via (at 182.3 86.75) (size 0.8) (drill 0.4) (layers "F.Cu" "B.Cu") (free) (net 25))
  (via (at 187.75 82) (size 0.8) (drill 0.4) (layers "F.Cu" "B.Cu") (free) (net 25))
  (via (at 187.9 88.15) (size 0.8) (drill 0.4) (layers "F.Cu" "B.Cu") (free) (net 25))
  (via (at 187.25 86) (size 0.8) (drill 0.4) (layers "F.Cu" "B.Cu") (free) (net 25))
  (via (at 187.15 82.9) (size 0.8) (drill 0.4) (layers "F.Cu" "B.Cu") (free) (net 25))
  (via (at 189.15 88.15) (size 0.8) (drill 0.4) (layers "F.Cu" "B.Cu") (free) (net 25))
  (via (at 186.6 82) (size 0.8) (drill 0.4) (layers "F.Cu" "B.Cu") (free) (net 25))
  (via (at 183.95 85.5) (size 0.8) (drill 0.4) (layers "F.Cu" "B.Cu") (free) (net 25))
  (via (at 188.1 86) (size 0.8) (drill 0.4) (layers "F.Cu" "B.Cu") (free) (net 25))
  (via (at 180.1 83) (size 0.8) (drill 0.4) (layers "F.Cu" "B.Cu") (free) (net 25))
  (via (at 188.95 86) (size 0.8) (drill 0.4) (layers "F.Cu" "B.Cu") (free) (net 25))
  (via (at 181.4 86.75) (size 0.8) (drill 0.4) (layers "F.Cu" "B.Cu") (free) (net 25))
  (via (at 187.8 79.9) (size 0.8) (drill 0.4) (layers "F.Cu" "B.Cu") (free) (net 25))
  (via (at 188.95 82) (size 0.8) (drill 0.4) (layers "F.Cu" "B.Cu") (free) (net 25))
  (via (at 179.35 87.15) (size 0.8) (drill 0.4) (layers "F.Cu" "B.Cu") (free) (net 25))
  (via (at 180.25 87.15) (size 0.8) (drill 0.4) (layers "F.Cu" "B.Cu") (free) (net 25))
  (via (at 188.55 85.25) (size 0.8) (drill 0.4) (layers "F.Cu" "B.Cu") (free) (net 25))
  (via (at 185.95 82.9) (size 0.8) (drill 0.4) (layers "F.Cu" "B.Cu") (free) (net 25))
  (via (at 188.1 89.35) (size 0.8) (drill 0.4) (layers "F.Cu" "B.Cu") (free) (net 25))
  (segment (start 161.762683 92.761883) (end 161.4 92.3992) (width 0.25) (layer "F.Cu") (net 26))
  (segment (start 177.65 89.265) (end 177.885 89.5) (width 0.25) (layer "F.Cu") (net 26))
  (segment (start 177.885 89.5) (end 177.885 90.015) (width 0.25) (layer "F.Cu") (net 26))
  (segment (start 177.6 87.85) (end 178.75 86.7) (width 0.25) (layer "F.Cu") (net 26))
  (segment (start 160.325 96.38) (end 160.325 95.283683) (width 0.25) (layer "F.Cu") (net 26))
  (segment (start 177.6 87.85) (end 177.65 87.9) (width 0.25) (layer "F.Cu") (net 26))
  (segment (start 176.865 91.385) (end 176.865 92) (width 0.25) (layer "F.Cu") (net 26))
  (segment (start 175.854 93.846) (end 161.762683 93.846) (width 0.25) (layer "F.Cu") (net 26))
  (segment (start 177.4 90.85) (end 176.865 91.385) (width 0.25) (layer "F.Cu") (net 26))
  (segment (start 176.9 92.8) (end 176.9 92.035) (width 0.25) (layer "F.Cu") (net 26))
  (segment (start 177.5 87.75) (end 176.6 87.75) (width 0.25) (layer "F.Cu") (net 26))
  (segment (start 161.762683 93.846) (end 161.762683 92.761883) (width 0.25) (layer "F.Cu") (net 26))
  (segment (start 178.75 86.7) (end 178.75 86.135) (width 0.25) (layer "F.Cu") (net 26))
  (segment (start 160.325 95.283683) (end 161.762683 93.846) (width 0.25) (layer "F.Cu") (net 26))
  (segment (start 177.4 90.5) (end 177.4 90.85) (width 0.25) (layer "F.Cu") (net 26))
  (segment (start 177.885 90.015) (end 177.4 90.5) (width 0.25) (layer "F.Cu") (net 26))
  (segment (start 176.9 92.035) (end 176.865 92) (width 0.25) (layer "F.Cu") (net 26))
  (segment (start 177.6 87.85) (end 177.5 87.75) (width 0.25) (layer "F.Cu") (net 26))
  (segment (start 176.9 92.8) (end 175.854 93.846) (width 0.25) (layer "F.Cu") (net 26))
  (segment (start 177.65 87.9) (end 177.65 89.265) (width 0.25) (layer "F.Cu") (net 26))
  (segment (start 167.7 82.785) (end 167.7 84.055) (width 0.25) (layer "F.Cu") (net 27))
  (via (at 166.8 86.6) (size 0.8) (drill 0.4) (layers "F.Cu" "B.Cu") (free) (net 27))
  (via (at 173.8 82.88) (size 0.8) (drill 0.4) (layers "F.Cu" "B.Cu") (free) (net 27))
  (via (at 164.7 85.8) (size 0.8) (drill 0.4) (layers "F.Cu" "B.Cu") (free) (net 27))
  (via (at 174 85.23) (size 0.8) (drill 0.4) (layers "F.Cu" "B.Cu") (free) (net 27))
  (via (at 168.9 86.35) (size 0.8) (drill 0.4) (layers "F.Cu" "B.Cu") (free) (net 27))
  (via (at 170.7 81.98) (size 0.8) (drill 0.4) (layers "F.Cu" "B.Cu") (free) (net 27))
  (via (at 172 79.88) (size 0.8) (drill 0.4) (layers "F.Cu" "B.Cu") (free) (net 27))
  (via (at 173 90.48) (size 0.8) (drill 0.4) (layers "F.Cu" "B.Cu") (free) (net 27))
  (via (at 171.55 85.6) (size 0.8) (drill 0.4) (layers "F.Cu" "B.Cu") (free) (net 27))
  (via (at 171.95 81.98) (size 0.8) (drill 0.4) (layers "F.Cu" "B.Cu") (free) (net 27))
  (via (at 173.25 79.88) (size 0.8) (drill 0.4) (layers "F.Cu" "B.Cu") (free) (net 27))
  (via (at 173 91.66) (size 0.8) (drill 0.4) (layers "F.Cu" "B.Cu") (free) (net 27))
  (via (at 174.45 79.88) (size 0.8) (drill 0.4) (layers "F.Cu" "B.Cu") (free) (net 27))
  (via (at 174.85 88.13) (size 0.8) (drill 0.4) (layers "F.Cu" "B.Cu") (free) (net 27))
  (via (at 163.8 85.8) (size 0.8) (drill 0.4) (layers "F.Cu" "B.Cu") (free) (net 27))
  (via (at 173.2 81.98) (size 0.8) (drill 0.4) (layers "F.Cu" "B.Cu") (free) (net 27))
  (via (at 165.6 85.8) (size 0.8) (drill 0.4) (layers "F.Cu" "B.Cu") (free) (net 27))
  (via (at 173.05 89.33) (size 0.8) (drill 0.4) (layers "F.Cu" "B.Cu") (free) (net 27))
  (via (at 167.7 86.6) (size 0.8) (drill 0.4) (layers "F.Cu" "B.Cu") (free) (net 27))
  (via (at 172.7 85.98) (size 0.8) (drill 0.4) (layers "F.Cu" "B.Cu") (free) (net 27))
  (via (at 173.55 85.98) (size 0.8) (drill 0.4) (layers "F.Cu" "B.Cu") (free) (net 27))
  (via (at 174.5 90.48) (size 0.8) (drill 0.4) (layers "F.Cu" "B.Cu") (free) (net 27))
  (via (at 171.4 82.88) (size 0.8) (drill 0.4) (layers "F.Cu" "B.Cu") (free) (net 27))
  (via (at 174.4 81.98) (size 0.8) (drill 0.4) (layers "F.Cu" "B.Cu") (free) (net 27))
  (via (at 165.55 82.98) (size 0.8) (drill 0.4) (layers "F.Cu" "B.Cu") (free) (net 27))
  (via (at 169.45 85.7) (size 0.8) (drill 0.4) (layers "F.Cu" "B.Cu") (free) (net 27))
  (via (at 172.6 82.88) (size 0.8) (drill 0.4) (layers "F.Cu" "B.Cu") (free) (net 27))
  (via (at 174.5 89.33) (size 0.8) (drill 0.4) (layers "F.Cu" "B.Cu") (free) (net 27))
  (via (at 174.85 85.23) (size 0.8) (drill 0.4) (layers "F.Cu" "B.Cu") (free) (net 27))
  (via (at 170.6 85.65) (size 0.8) (drill 0.4) (layers "F.Cu" "B.Cu") (free) (net 27))
  (via (at 173.65 88.13) (size 0.8) (drill 0.4) (layers "F.Cu" "B.Cu") (free) (net 27))
  (via (at 170.75 79.88) (size 0.8) (drill 0.4) (layers "F.Cu" "B.Cu") (free) (net 27))
  (via (at 174.5 91.7) (size 0.8) (drill 0.4) (layers "F.Cu" "B.Cu") (free) (net 27))
  (via (at 174.4 85.98) (size 0.8) (drill 0.4) (layers "F.Cu" "B.Cu") (free) (net 27))
  (via (at 173.15 85.23) (size 0.8) (drill 0.4) (layers "F.Cu" "B.Cu") (free) (net 27))
  (segment (start 150.7275 84.0825) (end 150.7275 82.8125) (width 0.25) (layer "F.Cu") (net 28))
  (via (at 156.5 82.05) (size 0.8) (drill 0.4) (layers "F.Cu" "B.Cu") (free) (net 28))
  (via (at 157.3 85.3) (size 0.8) (drill 0.4) (layers "F.Cu" "B.Cu") (free) (net 28))
  (via (at 158.15 88.2) (size 0.8) (drill 0.4) (layers "F.Cu" "B.Cu") (free) (net 28))
  (via (at 146.8 85.9) (size 0.8) (drill 0.4) (layers "F.Cu" "B.Cu") (free) (net 28))
  (via (at 151.9 86.45) (size 0.8) (drill 0.4) (layers "F.Cu" "B.Cu") (free) (net 28))
  (via (at 157.1 82.95) (size 0.8) (drill 0.4) (layers "F.Cu" "B.Cu") (free) (net 28))
  (via (at 155.9 82.95) (size 0.8) (drill 0.4) (layers "F.Cu" "B.Cu") (free) (net 28))
  (via (at 156.25 90.3) (size 0.8) (drill 0.4) (layers "F.Cu" "B.Cu") (free) (net 28))
  (via (at 157.75 90.4) (size 0.8) (drill 0.4) (layers "F.Cu" "B.Cu") (free) (net 28))
  (via (at 154.05 79.95) (size 0.8) (drill 0.4) (layers "F.Cu" "B.Cu") (free) (net 28))
  (via (at 153.7 85.7) (size 0.8) (drill 0.4) (layers "F.Cu" "B.Cu") (free) (net 28))
  (via (at 155.3 79.95) (size 0.8) (drill 0.4) (layers "F.Cu" "B.Cu") (free) (net 28))
  (via (at 157.75 79.95) (size 0.8) (drill 0.4) (layers "F.Cu" "B.Cu") (free) (net 28))
  (via (at 148.85 83.05) (size 0.8) (drill 0.4) (layers "F.Cu" "B.Cu") (free) (net 28))
  (via (at 156.45 85.3) (size 0.8) (drill 0.4) (layers "F.Cu" "B.Cu") (free) (net 28))
  (via (at 156.35 89.15) (size 0.8) (drill 0.4) (layers "F.Cu" "B.Cu") (free) (net 28))
  (via (at 155.25 82.05) (size 0.8) (drill 0.4) (layers "F.Cu" "B.Cu") (free) (net 28))
  (via (at 152.45 85.8) (size 0.8) (drill 0.4) (layers "F.Cu" "B.Cu") (free) (net 28))
  (via (at 157.7 82.05) (size 0.8) (drill 0.4) (layers "F.Cu" "B.Cu") (free) (net 28))
  (via (at 156 86.05) (size 0.8) (drill 0.4) (layers "F.Cu" "B.Cu") (free) (net 28))
  (via (at 147.7 85.9) (size 0.8) (drill 0.4) (layers "F.Cu" "B.Cu") (free) (net 28))
  (via (at 154.7 82.95) (size 0.8) (drill 0.4) (layers "F.Cu" "B.Cu") (free) (net 28))
  (via (at 148.6 85.9) (size 0.8) (drill 0.4) (layers "F.Cu" "B.Cu") (free) (net 28))
  (via (at 154 82.05) (size 0.8) (drill 0.4) (layers "F.Cu" "B.Cu") (free) (net 28))
  (via (at 147.8 83.05) (size 0.8) (drill 0.4) (layers "F.Cu" "B.Cu") (free) (net 28))
  (via (at 156.55 79.95) (size 0.8) (drill 0.4) (layers "F.Cu" "B.Cu") (free) (net 28))
  (via (at 150.7 86.7) (size 0.8) (drill 0.4) (layers "F.Cu" "B.Cu") (free) (net 28))
  (via (at 157.7 86.05) (size 0.8) (drill 0.4) (layers "F.Cu" "B.Cu") (free) (net 28))
  (via (at 158.15 85.3) (size 0.8) (drill 0.4) (layers "F.Cu" "B.Cu") (free) (net 28))
  (via (at 156.95 88.2) (size 0.8) (drill 0.4) (layers "F.Cu" "B.Cu") (free) (net 28))
  (via (at 149.8 86.7) (size 0.8) (drill 0.4) (layers "F.Cu" "B.Cu") (free) (net 28))
  (via (at 156.85 86.05) (size 0.8) (drill 0.4) (layers "F.Cu" "B.Cu") (free) (net 28))
  (via (at 157.8 89.2) (size 0.8) (drill 0.4) (layers "F.Cu" "B.Cu") (free) (net 28))
  (via (at 154.7 85.7) (size 0.8) (drill 0.4) (layers "F.Cu" "B.Cu") (free) (net 28))
  (segment (start 160.85 93.55) (end 160.87 93.57) (width 0.25) (layer "F.Cu") (net 29))
  (segment (start 163 87) (end 163.5 87.5) (width 0.25) (layer "F.Cu") (net 29))
  (segment (start 160.15 93.7992) (end 159.675 94.2742) (width 0.25) (layer "F.Cu") (net 29))
  (segment (start 160.15 93.55) (end 160.15 93.7992) (width 0.25) (layer "F.Cu") (net 29))
  (segment (start 162.785 89.815) (end 160.15 92.45) (width 0.25) (layer "F.Cu") (net 29))
  (segment (start 162.785 89.5) (end 162.785 89.815) (width 0.25) (layer "F.Cu") (net 29))
  (segment (start 163.5 87.5) (end 163.5 88.35) (width 0.25) (layer "F.Cu") (net 29))
  (segment (start 160.15 93.55) (end 160.85 93.55) (width 0.25) (layer "F.Cu") (net 29))
  (segment (start 160.15 92.45) (end 160.15 93.55) (width 0.25) (layer "F.Cu") (net 29))
  (segment (start 162.3 86) (end 162.3 86.9) (width 0.25) (layer "F.Cu") (net 29))
  (segment (start 162.4 87) (end 163 87) (width 0.25) (layer "F.Cu") (net 29))
  (segment (start 162.785 89.065) (end 162.785 89.5) (width 0.25) (layer "F.Cu") (net 29))
  (segment (start 159.675 94.2742) (end 159.675 96.38) (width 0.25) (layer "F.Cu") (net 29))
  (segment (start 163.5 88.35) (end 162.785 89.065) (width 0.25) (layer "F.Cu") (net 29))
  (segment (start 162.3 86.9) (end 162.4 87) (width 0.25) (layer "F.Cu") (net 29))
  (segment (start 162.4 87) (end 160.985 87) (width 0.25) (layer "F.Cu") (net 29))
  (segment (start 155.7508 92.9492) (end 156.55 92.15) (width 0.25) (layer "F.Cu") (net 30))
  (segment (start 159 94.416041) (end 159.35 94.066041) (width 0.25) (layer "F.Cu") (net 30))
  (segment (start 145.35 85.95) (end 145.35 86.95) (width 0.25) (layer "F.Cu") (net 30))
  (segment (start 159.35 91.8492) (end 159.8 91.3992) (width 0.25) (layer "F.Cu") (net 30))
  (segment (start 145.35 86.95) (end 145.4 87) (width 0.25) (layer "F.Cu") (net 30))
  (segment (start 159.35 94.066041) (end 159.35 92.15) (width 0.25) (layer "F.Cu") (net 30))
  (segment (start 159.35 92.15) (end 159.35 91.8492) (width 0.25) (layer "F.Cu") (net 30))
  (segment (start 145.4 87) (end 145.904 87) (width 0.25) (layer "F.Cu") (net 30))
  (segment (start 146.385 89.5) (end 146.385 92.185) (width 0.25) (layer "F.Cu") (net 30))
  (segment (start 146.385 87.481) (end 146.385 89.5) (width 0.25) (layer "F.Cu") (net 30))
  (segment (start 159 96.355) (end 159 94.416041) (width 0.25) (layer "F.Cu") (net 30))
  (segment (start 147.1492 92.9492) (end 155.7508 92.9492) (width 0.25) (layer "F.Cu") (net 30))
  (segment (start 156.55 92.15) (end 159.35 92.15) (width 0.25) (layer "F.Cu") (net 30))
  (segment (start 143.985 87) (end 145.4 87) (width 0.25) (layer "F.Cu") (net 30))
  (segment (start 145.904 87) (end 146.385 87.481) (width 0.25) (layer "F.Cu") (net 30))
  (segment (start 146.385 92.185) (end 147.1492 92.9492) (width 0.25) (layer "F.Cu") (net 30))
  (segment (start 163.9375 117.45) (end 165.75 117.45) (width 0.25) (layer "F.Cu") (net 31))
  (segment (start 165.75 117.45) (end 168.1 115.1) (width 0.25) (layer "F.Cu") (net 31))
  (segment (start 168.1 115.1) (end 169.415 115.1) (width 0.25) (layer "F.Cu") (net 31))
  (segment (start 107.147132 99.326324) (end 106.647132 98.826324) (width 0.25) (layer "F.Cu") (net 32))
  (segment (start 105.645331 98.826324) (end 105.447132 98.628125) (width 0.25) (layer "F.Cu") (net 32))
  (segment (start 107.147132 100.376324) (end 107.147132 99.326324) (width 0.25) (layer "F.Cu") (net 32))
  (segment (start 106.647132 98.826324) (end 105.645331 98.826324) (width 0.25) (layer "F.Cu") (net 32))
  (segment (start 105.447132 98.226324) (end 105.232132 98.011324) (width 0.25) (layer "F.Cu") (net 32))
  (segment (start 105.232132 98.011324) (end 104.647132 98.011324) (width 0.25) (layer "F.Cu") (net 32))
  (segment (start 105.447132 98.628125) (end 105.447132 98.226324) (width 0.25) (layer "F.Cu") (net 32))
  (segment (start 163.5 114.225) (end 163.5 112.4) (width 0.25) (layer "F.Cu") (net 33))
  (segment (start 163.25 114.475) (end 163.5 114.225) (width 0.25) (layer "F.Cu") (net 33))
  (segment (start 163.5 112.4) (end 162.8 111.7) (width 0.25) (layer "F.Cu") (net 33))
  (segment (start 163.25 115.2625) (end 163.25 114.475) (width 0.25) (layer "F.Cu") (net 33))
  (segment (start 150.35 105.05) (end 150.35 103.77) (width 0.25) (layer "F.Cu") (net 34))
  (segment (start 150.42 103.7) (end 150.42 102.1675) (width 0.25) (layer "F.Cu") (net 34))
  (segment (start 181.3 110.8) (end 181.75 110.35) (width 0.25) (layer "F.Cu") (net 35))
  (segment (start 180.3 110.6) (end 180.5 110.8) (width 0.25) (layer "F.Cu") (net 35))
  (segment (start 180.5 110.8) (end 181.3 110.8) (width 0.25) (layer "F.Cu") (net 35))
  (segment (start 181.75 110.35) (end 181.75 109.2) (width 0.25) (layer "F.Cu") (net 35))
  (segment (start 180.3 110.135) (end 180.3 110.6) (width 0.25) (layer "F.Cu") (net 35))
  (segment (start 111.55 53.65) (end 112.9 53.65) (width 0.325) (layer "F.Cu") (net 36))
  (segment (start 129.15 53.85) (end 130.5 53.85) (width 0.325) (layer "F.Cu") (net 37))
  (segment (start 96.985 133.315) (end 96.4 133.315) (width 0.25) (layer "F.Cu") (net 38))
  (segment (start 98 133.05) (end 97.25 133.05) (width 0.25) (layer "F.Cu") (net 38))
  (segment (start 97.25 133.05) (end 96.985 133.315) (width 0.25) (layer "F.Cu") (net 38))
  (segment (start 98 134.55) (end 99.9 134.55) (width 0.25) (layer "F.Cu") (net 39))
  (segment (start 146.65 53.85) (end 148 53.85) (width 0.325) (layer "F.Cu") (net 40))
  (segment (start 114.9 53.65) (end 115.9 54.65) (width 0.25) (layer "F.Cu") (net 41))
  (segment (start 115.9 54.65) (end 115.9 59.95) (width 0.25) (layer "F.Cu") (net 41))
  (segment (start 116.8 81.415) (end 116.8 80.145) (width 0.25) (layer "F.Cu") (net 41))
  (segment (start 114.3 53.65) (end 114.9 53.65) (width 0.25) (layer "F.Cu") (net 41))
  (segment (start 149.8 53.85) (end 151.2 55.25) (width 0.25) (layer "F.Cu") (net 42))
  (segment (start 151.2 55.25) (end 151.2 59.7) (width 0.25) (layer "F.Cu") (net 42))
  (segment (start 150.7275 81.5425) (end 150.7275 80.2725) (width 0.25) (layer "F.Cu") (net 42))
  (segment (start 149.4 53.85) (end 149.8 53.85) (width 0.25) (layer "F.Cu") (net 42))
  (segment (start 183 59.8) (end 181.6 58.4) (width 0.325) (layer "F.Cu") (net 43))
  (segment (start 182.2 81.5158) (end 182.2 80.2458) (width 0.25) (layer "F.Cu") (net 43))
  (segment (start 181.6 58.4) (end 181.6 56.45) (width 0.325) (layer "F.Cu") (net 43))
  (segment (start 133.35 54.7) (end 133.35 59.95) (width 0.25) (layer "F.Cu") (net 44))
  (segment (start 134.12 80.245) (end 134.12 81.515) (width 0.25) (layer "F.Cu") (net 44))
  (segment (start 132.5 53.85) (end 133.35 54.7) (width 0.25) (layer "F.Cu") (net 44))
  (segment (start 131.9 53.85) (end 132.5 53.85) (width 0.25) (layer "F.Cu") (net 44))
  (segment (start 168.152 56.852) (end 168.152 60.148) (width 0.25) (layer "F.Cu") (net 45))
  (segment (start 167.65 56.35) (end 168.152 56.852) (width 0.25) (layer "F.Cu") (net 45))
  (segment (start 166.7 53.85) (end 167.1 53.85) (width 0.25) (layer "F.Cu") (net 45))
  (segment (start 167.65 54.4) (end 167.65 56.35) (width 0.25) (layer "F.Cu") (net 45))
  (segment (start 167.7 80.245) (end 167.7 81.515) (width 0.25) (layer "F.Cu") (net 45))
  (segment (start 167.1 53.85) (end 167.65 54.4) (width 0.25) (layer "F.Cu") (net 45))
  (segment (start 111.5 94.3) (end 111.5 91.5) (width 0.25) (layer "F.Cu") (net 46))
  (segment (start 109.2004 82.6992) (end 109.2004 82.3504) (width 0.25) (layer "F.Cu") (net 46))
  (segment (start 148.502 95.398) (end 148.5 95.4) (width 0.25) (layer "F.Cu") (net 46))
  (segment (start 109.2004 82.3504) (end 108.85 82) (width 0.25) (layer "F.Cu") (net 46))
  (segment (start 111.5 91.5) (end 108.1 88.1) (width 0.25) (layer "F.Cu") (net 46))
  (segment (start 146.9 95.4) (end 146.6 95.7) (width 0.25) (layer "F.Cu") (net 46))
  (segment (start 146.6 95.7) (end 112.9 95.7) (width 0.25) (layer "F.Cu") (net 46))
  (segment (start 109.3142 82.685) (end 111.9 82.685) (width 0.25) (layer "F.Cu") (net 46))
  (segment (start 148.5 95.4) (end 146.9 95.4) (width 0.25) (layer "F.Cu") (net 46))
  (segment (start 108.1 88.1) (end 108.1 83.7996) (width 0.25) (layer "F.Cu") (net 46))
  (segment (start 151.598 95.398) (end 148.502 95.398) (width 0.25) (layer "F.Cu") (net 46))
  (segment (start 151.775 95.802197) (end 151.775 95.575) (width 0.25) (layer "F.Cu") (net 46))
  (segment (start 151.775 95.575) (end 151.598 95.398) (width 0.25) (layer "F.Cu") (net 46))
  (segment (start 108.1 83.7996) (end 109.2004 82.6992) (width 0.25) (layer "F.Cu") (net 46))
  (segment (start 112.9 95.7) (end 111.5 94.3) (width 0.25) (layer "F.Cu") (net 46))
  (segment (start 125.47 83.7492) (end 125.47 87.67) (width 0.25) (layer "F.Cu") (net 47))
  (segment (start 126.47 82.7492) (end 129.1842 82.7492) (width 0.25) (layer "F.Cu") (net 47))
  (segment (start 125.47 87.67) (end 125.6 87.8) (width 0.25) (layer "F.Cu") (net 47))
  (segment (start 126.4 81.95) (end 126.4 82.6792) (width 0.25) (layer "F.Cu") (net 47))
  (segment (start 152.425 95.225) (end 152.1 94.9) (width 0.25) (layer "F.Cu") (net 47))
  (segment (start 126.4 82.6792) (end 126.47 82.7492) (width 0.25) (layer "F.Cu") (net 47))
  (segment (start 146.7 94.9) (end 146.4 95.2) (width 0.25) (layer "F.Cu") (net 47))
  (segment (start 152.1 94.9) (end 146.7 94.9) (width 0.25) (layer "F.Cu") (net 47))
  (segment (start 146.4 95.2) (end 126.6 95.2) (width 0.25) (layer "F.Cu") (net 47))
  (segment (start 126.6 95.2) (end 126.5 95.1) (width 0.25) (layer "F.Cu") (net 47))
  (segment (start 152.425 95.802197) (end 152.425 95.225) (width 0.25) (layer "F.Cu") (net 47))
  (segment (start 125.47 83.7492) (end 126.47 82.7492) (width 0.25) (layer "F.Cu") (net 47))
  (via (at 126.5 95.1) (size 0.6) (drill 0.25) (layers "F.Cu" "B.Cu") (net 47))
  (via (at 125.6 87.8) (size 0.6) (drill 0.25) (layers "F.Cu" "B.Cu") (net 47))
  (segment (start 126.5 88.7) (end 126.5 95.1) (width 0.25) (layer "In2.Cu") (net 47))
  (segment (start 125.6 87.8) (end 126.5 88.7) (width 0.25) (layer "In2.Cu") (net 47))
  (segment (start 142.6917 82.4917) (end 142.6917 82.8125) (width 0.25) (layer "F.Cu") (net 48))
  (segment (start 144 94.4) (end 152.3 94.4) (width 0.25) (layer "F.Cu") (net 48))
  (segment (start 145.8275 82.8125) (end 142.6917 82.8125) (width 0.25) (layer "F.Cu") (net 48))
  (segment (start 142.1 87.6) (end 142.1 83.4042) (width 0.25) (layer "F.Cu") (net 48))
  (segment (start 142.4 87.9) (end 142.1 87.6) (width 0.25) (layer "F.Cu") (net 48))
  (segment (start 142.35 82.15) (end 142.6917 82.4917) (width 0.25) (layer "F.Cu") (net 48))
  (segment (start 152.3 94.4) (end 153.075 95.175) (width 0.25) (layer "F.Cu") (net 48))
  (segment (start 143.8 94.6) (end 144 94.4) (width 0.25) (layer "F.Cu") (net 48))
  (segment (start 142.1 83.4042) (end 142.6775 82.8267) (width 0.25) (layer "F.Cu") (net 48))
  (segment (start 144 87.9) (end 142.4 87.9) (width 0.25) (layer "F.Cu") (net 48))
  (segment (start 153.075 95.175) (end 153.075 95.802197) (width 0.25) (layer "F.Cu") (net 48))
  (via (at 144 87.9) (size 0.8) (drill 0.4) (layers "F.Cu" "B.Cu") (net 48))
  (via (at 143.8 94.6) (size 0.6) (drill 0.25) (layers "F.Cu" "B.Cu") (net 48))
  (segment (start 144.5 89.7) (end 144.5 88.4) (width 0.25) (layer "In2.Cu") (net 48))
  (segment (start 143.8 94.6) (end 143.8 90.4) (width 0.25) (layer "In2.Cu") (net 48))
  (segment (start 144.5 88.4) (end 144 87.9) (width 0.25) (layer "In2.Cu") (net 48))
  (segment (start 143.8 90.4) (end 144.5 89.7) (width 0.25) (layer "In2.Cu") (net 48))
  (segment (start 159.1 83.15) (end 159.45 82.8) (width 0.25) (layer "F.Cu") (net 49))
  (segment (start 158.52 91.3) (end 159.1 90.72) (width 0.25) (layer "F.Cu") (net 49))
  (segment (start 159.35 82.67) (end 159.465 82.785) (width 0.25) (layer "F.Cu") (net 49))
  (segment (start 153.725 96.3875) (end 153.725 94.925) (width 0.25) (layer "F.Cu") (net 49))
  (segment (start 153.725 94.925) (end 153.7 94.9) (width 0.25) (layer "F.Cu") (net 49))
  (segment (start 162.8 82.785) (end 159.465 82.785) (width 0.25) (layer "F.Cu") (net 49))
  (segment (start 159.1 90.72) (end 159.1 83.15) (width 0.25) (layer "F.Cu") (net 49))
  (segment (start 155.6 91.3) (end 158.52 91.3) (width 0.25) (layer "F.Cu") (net 49))
  (segment (start 159.35 82) (end 159.35 82.67) (width 0.25) (layer "F.Cu") (net 49))
  (via (at 153.7 94.9) (size 0.6) (drill 0.25) (layers "F.Cu" "B.Cu") (net 49))
  (via (at 155.6 91.3) (size 0.6) (drill 0.25) (layers "F.Cu" "B.Cu") (net 49))
  (segment (start 153.7 94.9) (end 155.6 93) (width 0.25) (layer "In2.Cu") (net 49))
  (segment (start 155.6 93) (end 155.6 91.3) (width 0.25) (layer "In2.Cu") (net 49))
  (segment (start 171.85 93.3) (end 174.35 93.3) (width 0.25) (layer "F.Cu") (net 50))
  (segment (start 154.375 95.175) (end 154.7 94.85) (width 0.25) (layer "F.Cu") (net 50))
  (segment (start 163.6 93.45) (end 171.7 93.45) (width 0.25) (layer "F.Cu") (net 50))
  (segment (start 171.7 93.45) (end 171.85 93.3) (width 0.25) (layer "F.Cu") (net 50))
  (segment (start 176.2142 82.7858) (end 177.3 82.7858) (width 0.25) (layer "F.Cu") (net 50))
  (segment (start 175.6 82.25) (end 175.55 82.2) (width 0.25) (layer "F.Cu") (net 50))
  (segment (start 162.4 92.25) (end 163.6 93.45) (width 0.25) (layer "F.Cu") (net 50))
  (segment (start 162.4 92.2) (end 162.4 92.25) (width 0.25) (layer "F.Cu") (net 50))
  (segment (start 175.6 83.4) (end 176.2142 82.7858) (width 0.25) (layer "F.Cu") (net 50))
  (segment (start 175.6 83.1) (end 175.6 82.25) (width 0.25) (layer "F.Cu") (net 50))
  (segment (start 154.375 96.3875) (end 154.375 95.175) (width 0.25) (layer "F.Cu") (net 50))
  (segment (start 175.6 83.1) (end 175.6 83.4) (width 0.25) (layer "F.Cu") (net 50))
  (segment (start 175.6 92.05) (end 175.6 83.1) (width 0.25) (layer "F.Cu") (net 50))
  (segment (start 174.35 93.3) (end 175.6 92.05) (width 0.25) (layer "F.Cu") (net 50))
  (via (at 162.4 92.2) (size 0.6) (drill 0.25) (layers "F.Cu" "B.Cu") (net 50))
  (via (at 154.7 94.85) (size 0.6) (drill 0.25) (layers "F.Cu" "B.Cu") (net 50))
  (segment (start 159.75 94.85) (end 154.7 94.85) (width 0.25) (layer "In2.Cu") (net 50))
  (segment (start 162.4 92.2) (end 159.75 94.85) (width 0.25) (layer "In2.Cu") (net 50))
  (segment (start 93.5 136.5) (end 107 136.5) (width 0.25) (layer "F.Cu") (net 51))
  (segment (start 107 138) (end 107 136.5) (width 0.25) (layer "F.Cu") (net 51))
  (via (at 107 138) (size 0.6) (drill 0.25) (layers "F.Cu" "B.Cu") (net 51))
  (segment (start 109.28 138.78) (end 109.28 142.775) (width 0.6) (layer "B.Cu") (net 51))
  (segment (start 108.5 138) (end 109.28 138.78) (width 0.6) (layer "B.Cu") (net 51))
  (segment (start 107 138) (end 108.5 138) (width 0.6) (layer "B.Cu") (net 51))
  (segment (start 163.95 53.85) (end 165.3 53.85) (width 0.325) (layer "F.Cu") (net 52))
  (segment (start 181.6 55.05) (end 181.6 53.45) (width 0.25) (layer "F.Cu") (net 53))
  (segment (start 102.05 135.55) (end 103.765 135.55) (width 0.25) (layer "F.Cu") (net 54))
  (segment (start 123.4508 132.4992) (end 123.45 132.5) (width 0.25) (layer "F.Cu") (net 55))
  (segment (start 123.4508 131.4) (end 123.4508 132.4992) (width 0.25) (layer "F.Cu") (net 55))
  (via (at 123.45 132.5) (size 0.6) (drill 0.25) (layers "F.Cu" "B.Cu") (net 55))
  (segment (start 123.45 140.45) (end 123.45 132.5) (width 0.25) (layer "B.Cu") (net 55))
  (segment (start 109.28 137.8308) (end 108.9 137.4508) (width 0.25) (layer "F.Cu") (net 56))
  (segment (start 109.28 142.775) (end 109.28 137.8308) (width 0.25) (layer "F.Cu") (net 56))
  (segment (start 110.55 142.775) (end 110.55 137.7) (width 0.25) (layer "F.Cu") (net 57))
  (segment (start 110.55 137.7) (end 110.25 137.4) (width 0.25) (layer "F.Cu") (net 57))
  (segment (start 111.82 142.775) (end 111.82 137.5692) (width 0.25) (layer "F.Cu") (net 58))
  (segment (start 113.09 142.775) (end 113.09 137.4392) (width 0.25) (layer "F.Cu") (net 59))
  (segment (start 118.17 142.775) (end 118.17 137.5808) (width 0.25) (layer "F.Cu") (net 60))
  (segment (start 116.9 142.775) (end 116.9 137.5) (width 0.25) (layer "F.Cu") (net 61))
  (segment (start 115.63 142.775) (end 115.63 137.4708) (width 0.25) (layer "F.Cu") (net 62))
  (segment (start 114.36 142.775) (end 114.36 137.44) (width 0.25) (layer "F.Cu") (net 63))
  (segment (start 123.25 142.775) (end 123.25 137.5992) (width 0.25) (layer "F.Cu") (net 64))
  (segment (start 121.98 142.775) (end 121.98 137.605) (width 0.25) (layer "F.Cu") (net 65))
  (segment (start 120.71 142.775) (end 120.71 137.5408) (width 0.25) (layer "F.Cu") (net 66))
  (segment (start 119.44 142.775) (end 119.44 137.56) (width 0.25) (layer "F.Cu") (net 67))
  (segment (start 122.1508 132.4992) (end 122.15 132.5) (width 0.25) (layer "F.Cu") (net 68))
  (segment (start 122.1508 131.4) (end 122.1508 132.4992) (width 0.25) (layer "F.Cu") (net 68))
  (via (at 122.15 132.5) (size 0.6) (drill 0.25) (layers "F.Cu" "B.Cu") (net 68))
  (segment (start 122.15 140.6) (end 122.15 132.5) (width 0.25) (layer "B.Cu") (net 68))
  (segment (start 119.5 131.4) (end 119.5 132.5) (width 0.25) (layer "F.Cu") (net 69))
  (via (at 119.5 132.5) (size 0.6) (drill 0.25) (layers "F.Cu" "B.Cu") (net 69))
  (segment (start 119.5 132.5) (end 119.5 142.715) (width 0.25) (layer "B.Cu") (net 69))
  (segment (start 120.8508 132.4992) (end 120.85 132.5) (width 0.25) (layer "F.Cu") (net 70))
  (segment (start 120.8508 131.4) (end 120.8508 132.4992) (width 0.25) (layer "F.Cu") (net 70))
  (via (at 120.85 132.5) (size 0.6) (drill 0.25) (layers "F.Cu" "B.Cu") (net 70))
  (segment (start 120.71 136.11) (end 120.71 142.775) (width 0.25) (layer "B.Cu") (net 70))
  (segment (start 120.85 135.97) (end 120.71 136.11) (width 0.25) (layer "B.Cu") (net 70))
  (segment (start 120.85 132.5) (end 120.85 135.97) (width 0.25) (layer "B.Cu") (net 70))
  (segment (start 116.9 131.4) (end 116.9 132.5) (width 0.25) (layer "F.Cu") (net 71))
  (via (at 116.9 132.5) (size 0.6) (drill 0.25) (layers "F.Cu" "B.Cu") (net 71))
  (segment (start 116.9 132.5) (end 116.9 142.775) (width 0.25) (layer "B.Cu") (net 71))
  (segment (start 114.3 132.5) (end 114.3 131.4) (width 0.25) (layer "F.Cu") (net 72))
  (via (at 114.3 132.5) (size 0.6) (drill 0.25) (layers "F.Cu" "B.Cu") (net 72))
  (segment (start 114.36 132.56) (end 114.3 132.5) (width 0.25) (layer "B.Cu") (net 72))
  (segment (start 114.36 142.775) (end 114.36 132.56) (width 0.25) (layer "B.Cu") (net 72))
  (segment (start 115.6 131.4) (end 115.6 132.5) (width 0.25) (layer "F.Cu") (net 73))
  (via (at 115.6 132.5) (size 0.6) (drill 0.25) (layers "F.Cu" "B.Cu") (net 73))
  (segment (start 115.63 142.775) (end 115.63 132.53) (width 0.25) (layer "B.Cu") (net 73))
  (segment (start 115.63 132.53) (end 115.6 132.5) (width 0.25) (layer "B.Cu") (net 73))
  (segment (start 118.2 131.4) (end 118.2 132.5) (width 0.25) (layer "F.Cu") (net 74))
  (via (at 118.2 132.5) (size 0.6) (drill 0.25) (layers "F.Cu" "B.Cu") (net 74))
  (segment (start 118.17 138.93) (end 118.3 138.8) (width 0.25) (layer "B.Cu") (net 74))
  (segment (start 118.3 138.8) (end 118.3 132.6) (width 0.25) (layer "B.Cu") (net 74))
  (segment (start 118.3 132.6) (end 118.2 132.5) (width 0.25) (layer "B.Cu") (net 74))
  (segment (start 118.17 142.775) (end 118.17 138.93) (width 0.25) (layer "B.Cu") (net 74))
  (segment (start 113 132.5) (end 113 131.4) (width 0.25) (layer "F.Cu") (net 75))
  (via (at 113 132.5) (size 0.6) (drill 0.25) (layers "F.Cu" "B.Cu") (net 75))
  (segment (start 113.09 142.775) (end 113.09 132.59) (width 0.25) (layer "B.Cu") (net 75))
  (segment (start 113.09 132.59) (end 113 132.5) (width 0.25) (layer "B.Cu") (net 75))
  (segment (start 174.3925 122.25) (end 173.5425 121.4) (width 0.25) (layer "F.Cu") (net 76))
  (segment (start 160.25 123.1375) (end 160.25 124.665) (width 0.25) (layer "F.Cu") (net 76))
  (segment (start 172.095 117.2) (end 172.13 117.165) (width 0.25) (layer "F.Cu") (net 76))
  (segment (start 174.795 108.75) (end 174.795 110.54) (width 0.4) (layer "F.Cu") (net 76))
  (segment (start 157.25 123.1375) (end 157.25 124.665) (width 0.25) (layer "F.Cu") (net 76))
  (segment (start 174.785 110.55) (end 174.785 111.41) (width 0.25) (layer "F.Cu") (net 76))
  (segment (start 154.5 119.43) (end 154.5 118.4) (width 0.25) (layer "F.Cu") (net 76))
  (segment (start 154.5 119.43) (end 156.0425 119.43) (width 0.25) (layer "F.Cu") (net 76))
  (segment (start 170.385 115.1) (end 171.2 115.1) (width 0.25) (layer "F.Cu") (net 76))
  (segment (start 180.335 109.165) (end 180.3 109.165) (width 0.25) (layer "F.Cu") (net 76))
  (segment (start 162.67 113.03) (end 162.7 113) (width 0.25) (layer "F.Cu") (net 76))
  (segment (start 166.65 113.015) (end 168.6 113.015) (width 0.25) (layer "F.Cu") (net 76))
  (segment (start 162.75 115.2625) (end 162.75 113.98) (width 0.25) (layer "F.Cu") (net 76))
  (segment (start 180.35 109.15) (end 180.335 109.165) (width 0.25) (layer "F.Cu") (net 76))
  (segment (start 162.67 113.9) (end 162.67 113.03) (width 0.25) (layer "F.Cu") (net 76))
  (segment (start 156.0425 119.43) (end 156.0625 119.45) (width 0.25) (layer "F.Cu") (net 76))
  (segment (start 160.285 124.7) (end 161.2 124.7) (width 0.25) (layer "F.Cu") (net 76))
  (segment (start 180.35 108.54) (end 180.35 109.15) (width 0.25) (layer "F.Cu") (net 76))
  (segment (start 157.215 124.7) (end 157.215 125.615) (width 0.25) (layer "F.Cu") (net 76))
  (segment (start 173.5425 121.4) (end 172.6825 121.4) (width 0.25) (layer "F.Cu") (net 76))
  (segment (start 154.5 118.4) (end 154.7 118.2) (width 0.25) (layer "F.Cu") (net 76))
  (segment (start 157.215 125.615) (end 157.3 125.7) (width 0.25) (layer "F.Cu") (net 76))
  (segment (start 171.125 117.2) (end 172.095 117.2) (width 0.25) (layer "F.Cu") (net 76))
  (via (at 179.15 124.825) (size 0.8) (drill 0.4) (layers "F.Cu" "B.Cu") (free) (net 76))
  (via (at 154.7 118.2) (size 0.8) (drill 0.4) (layers "F.Cu" "B.Cu") (net 76))
  (via (at 180.35 108.54) (size 0.6) (drill 0.25) (layers "F.Cu" "B.Cu") (free) (net 76))
  (via (at 172.13 117.165) (size 0.8) (drill 0.4) (layers "F.Cu" "B.Cu") (net 76))
  (via (at 157.3 125.7) (size 0.8) (drill 0.4) (layers "F.Cu" "B.Cu") (net 76))
  (via (at 168.6 113.015) (size 0.8) (drill 0.4) (layers "F.Cu" "B.Cu") (net 76))
  (via (at 174.8 111.325) (size 0.6) (drill 0.25) (layers "F.Cu" "B.Cu") (net 76))
  (via (at 180.65 126.425) (size 0.8) (drill 0.4) (layers "F.Cu" "B.Cu") (free) (net 76))
  (via (at 180.65 124.825) (size 0.8) (drill 0.4) (layers "F.Cu" "B.Cu") (free) (net 76))
  (via (at 161.2 124.7) (size 0.8) (drill 0.4) (layers "F.Cu" "B.Cu") (net 76))
  (via (at 171.2 115.1) (size 0.6) (drill 0.25) (layers "F.Cu" "B.Cu") (net 76))
  (via (at 174.3925 122.25) (size 0.6) (drill 0.25) (layers "F.Cu" "B.Cu") (net 76))
  (via (at 162.7 113) (size 0.8) (drill 0.4) (layers "F.Cu" "B.Cu") (net 76))
  (via (at 179.95 125.625) (size 0.8) (drill 0.4) (layers "F.Cu" "B.Cu") (free) (net 76))
  (via (at 179.15 126.425) (size 0.8) (drill 0.4) (layers "F.Cu" "B.Cu") (free) (net 76))
  (segment (start 185.05 119.5) (end 185.05 120.875) (width 0.325) (layer "F.Cu") (net 77))
  (segment (start 157.085 126.8) (end 157.085 127.785) (width 0.325) (layer "F.Cu") (net 77))
  (segment (start 167.45 116.95) (end 168.485 116.95) (width 0.25) (layer "F.Cu") (net 77))
  (segment (start 159.315 124.7) (end 158.7 124.7) (width 0.25) (layer "F.Cu") (net 77))
  (segment (start 157.75 124.265) (end 158.185 124.7) (width 0.25) (layer "F.Cu") (net 77))
  (segment (start 158.7 124.7) (end 158.7 125.6) (width 0.25) (layer "F.Cu") (net 77))
  (segment (start 157.75 123.1375) (end 157.75 124.265) (width 0.25) (layer "F.Cu") (net 77))
  (segment (start 180.6 113.45) (end 180.8675 113.45) (width 0.2) (layer "F.Cu") (net 77))
  (segment (start 158.7 124.7) (end 158.185 124.7) (width 0.25) (layer "F.Cu") (net 77))
  (segment (start 187.2 116.3) (end 188.585 116.3) (width 0.325) (layer "F.Cu") (net 77))
  (segment (start 180.3 113.75) (end 180.6 113.45) (width 0.2) (layer "F.Cu") (net 77))
  (via (at 176.1 115.5) (size 0.8) (drill 0.4) (layers "F.Cu" "B.Cu") (free) (net 77))
  (via (at 178.95 118.65) (size 0.8) (drill 0.4) (layers "F.Cu" "B.Cu") (free) (net 77))
  (via (at 177.75 118.35) (size 0.8) (drill 0.4) (layers "F.Cu" "B.Cu") (free) (net 77))
  (via (at 174.8 116.7) (size 0.8) (drill 0.4) (layers "F.Cu" "B.Cu") (free) (net 77))
  (via (at 185.05 119.5) (size 0.6) (drill 0.25) (layers "F.Cu" "B.Cu") (net 77))
  (via (at 180.45 116.3) (size 0.8) (drill 0.4) (layers "F.Cu" "B.Cu") (net 77))
  (via (at 173.75 112.6) (size 0.8) (drill 0.4) (layers "F.Cu" "B.Cu") (free) (net 77))
  (via (at 174.75 112.6) (size 0.8) (drill 0.4) (layers "F.Cu" "B.Cu") (free) (net 77))
  (via (at 177.75 119.6) (size 0.8) (drill 0.4) (layers "F.Cu" "B.Cu") (free) (net 77))
  (via (at 176 116.6) (size 0.8) (drill 0.4) (layers "F.Cu" "B.Cu") (free) (net 77))
  (via (at 187.05 110.7) (size 0.8) (drill 0.4) (layers "F.Cu" "B.Cu") (free) (net 77))
  (via (at 187.2 116.3) (size 0.8) (drill 0.4) (layers "F.Cu" "B.Cu") (free) (net 77))
  (via (at 179 112.55) (size 0.6) (drill 0.25) (layers "F.Cu" "B.Cu") (free) (net 77))
  (via (at 180.3 113.75) (size 0.6) (drill 0.25) (layers "F.Cu" "B.Cu") (free) (net 77))
  (via (at 185.7 107.75) (size 0.8) (drill 0.4) (layers "F.Cu" "B.Cu") (free) (net 77))
  (segment (start 184.3 110.05) (end 185.15 110.9) (width 0.325) (layer "In2.Cu") (net 77))
  (segment (start 186.85 110.9) (end 187.05 110.7) (width 0.325) (layer "In2.Cu") (net 77))
  (segment (start 184.3 116.8) (end 184.3 118.75) (width 0.325) (layer "In2.Cu") (net 77))
  (segment (start 184.8 116.3) (end 184.3 116.8) (width 0.325) (layer "In2.Cu") (net 77))
  (segment (start 183.773 116.273) (end 180.477 116.273) (width 0.325) (layer "In2.Cu") (net 77))
  (segment (start 184.3 118.75) (end 185.05 119.5) (width 0.325) (layer "In2.Cu") (net 77))
  (segment (start 185.15 110.9) (end 186.85 110.9) (width 0.325) (layer "In2.Cu") (net 77))
  (segment (start 184.3 109.15) (end 184.3 110.05) (width 0.325) (layer "In2.Cu") (net 77))
  (segment (start 179.1 112.55) (end 180.3 113.75) (width 0.2) (layer "In2.Cu") (net 77))
  (segment (start 185.7 107.75) (end 184.3 109.15) (width 0.325) (layer "In2.Cu") (net 77))
  (segment (start 184.3 116.8) (end 183.773 116.273) (width 0.325) (layer "In2.Cu") (net 77))
  (segment (start 180.477 116.273) (end 180.45 116.3) (width 0.325) (layer "In2.Cu") (net 77))
  (segment (start 179 112.55) (end 179.1 112.55) (width 0.2) (layer "In2.Cu") (net 77))
  (segment (start 187.2 116.3) (end 184.8 116.3) (width 0.325) (layer "In2.Cu") (net 77))
  (segment (start 94.95 101.6) (end 96.1 101.6) (width 0.25) (layer "F.Cu") (net 78))
  (segment (start 96.1 99) (end 94.95 99) (width 0.25) (layer "F.Cu") (net 79))
  (segment (start 172 113.6) (end 172.3 113.6) (width 0.25) (layer "F.Cu") (net 80))
  (segment (start 171.8 113.6) (end 172.05 113.35) (width 0.25) (layer "F.Cu") (net 80))
  (segment (start 173.175 106.95) (end 174.965 106.95) (width 0.25) (layer "F.Cu") (net 80))
  (segment (start 176.06 113.19) (end 176.06 112.25) (width 0.25) (layer "F.Cu") (net 80))
  (segment (start 172.05 113.55) (end 172 113.6) (width 0.25) (layer "F.Cu") (net 80))
  (segment (start 172.05 113.35) (end 172.3 113.6) (width 0.25) (layer "F.Cu") (net 80))
  (segment (start 165.4 114.1) (end 165.4 112.65) (width 0.25) (layer "F.Cu") (net 80))
  (segment (start 165.4 112.65) (end 166 112.05) (width 0.25) (layer "F.Cu") (net 80))
  (segment (start 166 112.05) (end 169.35 112.05) (width 0.25) (layer "F.Cu") (net 80))
  (segment (start 172.3 113.6) (end 175.65 113.6) (width 0.25) (layer "F.Cu") (net 80))
  (segment (start 164.6 114.9) (end 165.4 114.1) (width 0.25) (layer "F.Cu") (net 80))
  (segment (start 172.05 112.6) (end 172.05 113.3) (width 0.25) (layer "F.Cu") (net 80))
  (segment (start 172.05 113.3) (end 172.05 113.55) (width 0.25) (layer "F.Cu") (net 80))
  (segment (start 170.9 113.6) (end 171.8 113.6) (width 0.25) (layer "F.Cu") (net 80))
  (segment (start 164.55 115.95) (end 164.6 115.9) (width 0.25) (layer "F.Cu") (net 80))
  (segment (start 164.6 115.9) (end 164.6 114.9) (width 0.25) (layer "F.Cu") (net 80))
  (segment (start 174.965 106.95) (end 176.065 108.05) (width 0.25) (layer "F.Cu") (net 80))
  (segment (start 171.8 113.6) (end 172 113.6) (width 0.25) (layer "F.Cu") (net 80))
  (segment (start 175.65 113.6) (end 176.06 113.19) (width 0.25) (layer "F.Cu") (net 80))
  (segment (start 176.065 108.05) (end 176.065 108.75) (width 0.25) (layer "F.Cu") (net 80))
  (segment (start 176.065 108.75) (end 176.065 112.245) (width 0.25) (layer "F.Cu") (net 80))
  (segment (start 169.35 112.05) (end 170.9 113.6) (width 0.25) (layer "F.Cu") (net 80))
  (segment (start 172.05 113.35) (end 172.05 113.3) (width 0.25) (layer "F.Cu") (net 80))
  (segment (start 165.4 114.1) (end 166.535 114.1) (width 0.25) (layer "F.Cu") (net 80))
  (segment (start 163.9375 115.95) (end 164.55 115.95) (width 0.25) (layer "F.Cu") (net 80))
  (segment (start 166.535 114.1) (end 166.65 113.985) (width 0.25) (layer "F.Cu") (net 80))
  (segment (start 168.385 113.985) (end 168.6 114.2) (width 0.25) (layer "F.Cu") (net 81))
  (segment (start 163.9375 116.95) (end 165.25 116.95) (width 0.25) (layer "F.Cu") (net 81))
  (segment (start 177.335 108.05) (end 177.335 108.75) (width 0.25) (layer "F.Cu") (net 81))
  (segment (start 177.335 108.75) (end 177.335 112.245) (width 0.25) (layer "F.Cu") (net 81))
  (segment (start 167.65 113.985) (end 168.385 113.985) (width 0.25) (layer "F.Cu") (net 81))
  (segment (start 172.45 114.25) (end 172.5 114.2) (width 0.25) (layer "F.Cu") (net 81))
  (segment (start 172.45 115.1) (end 172.45 114.45) (width 0.25) (layer "F.Cu") (net 81))
  (segment (start 172.65 114.25) (end 172.65 114.2) (width 0.25) (layer "F.Cu") (net 81))
  (segment (start 172.45 114.45) (end 172.25 114.25) (width 0.25) (layer "F.Cu") (net 81))
  (segment (start 165.25 116.95) (end 167.65 114.55) (width 0.25) (layer "F.Cu") (net 81))
  (segment (start 172.25 114.25) (end 172.25 114.2) (width 0.25) (layer "F.Cu") (net 81))
  (segment (start 167.65 114.55) (end 167.65 113.985) (width 0.25) (layer "F.Cu") (net 81))
  (segment (start 180.225 106.95) (end 178.435 106.95) (width 0.25) (layer "F.Cu") (net 81))
  (segment (start 172.25 114.2) (end 172.5 114.2) (width 0.25) (layer "F.Cu") (net 81))
  (segment (start 172.45 114.45) (end 172.45 114.25) (width 0.25) (layer "F.Cu") (net 81))
  (segment (start 176.65 114.2) (end 177.33 113.52) (width 0.25) (layer "F.Cu") (net 81))
  (segment (start 172.45 114.45) (end 172.65 114.25) (width 0.25) (layer "F.Cu") (net 81))
  (segment (start 172.65 114.2) (end 176.65 114.2) (width 0.25) (layer "F.Cu") (net 81))
  (segment (start 172.5 114.2) (end 172.65 114.2) (width 0.25) (layer "F.Cu") (net 81))
  (segment (start 178.435 106.95) (end 177.335 108.05) (width 0.25) (layer "F.Cu") (net 81))
  (segment (start 168.6 114.2) (end 172.25 114.2) (width 0.25) (layer "F.Cu") (net 81))
  (segment (start 177.33 113.52) (end 177.33 112.25) (width 0.25) (layer "F.Cu") (net 81))
  (segment (start 96.1 104.4) (end 94.95 104.4) (width 0.25) (layer "F.Cu") (net 82))
  (segment (start 113.3 92.7) (end 113 92.4) (width 0.2) (layer "F.Cu") (net 83))
  (segment (start 113.65 90.685) (end 113.085 90.685) (width 0.2) (layer "F.Cu") (net 83))
  (segment (start 120.65 92.7) (end 113.3 92.7) (width 0.2) (layer "F.Cu") (net 83))
  (segment (start 121.2 92.15) (end 120.65 92.7) (width 0.2) (layer "F.Cu") (net 83))
  (segment (start 113 89.2) (end 113.3 88.9) (width 0.2) (layer "F.Cu") (net 83))
  (segment (start 121.2 91.985) (end 121.2 92.15) (width 0.2) (layer "F.Cu") (net 83))
  (segment (start 113.615 91.85) (end 113 91.85) (width 0.2) (layer "F.Cu") (net 83))
  (segment (start 113 90.77) (end 113 89.2) (width 0.2) (layer "F.Cu") (net 83))
  (segment (start 113 91.85) (end 113 90.77) (width 0.2) (layer "F.Cu") (net 83))
  (segment (start 113.55 87.45) (end 113.55 86.8) (width 0.2) (layer "F.Cu") (net 83))
  (segment (start 113.3 87.7) (end 113.55 87.45) (width 0.2) (layer "F.Cu") (net 83))
  (segment (start 113 90.77) (end 113.085 90.685) (width 0.2) (layer "F.Cu") (net 83))
  (segment (start 113.3 88.9) (end 113.3 87.7) (width 0.2) (layer "F.Cu") (net 83))
  (segment (start 113 92.4) (end 113 91.85) (width 0.2) (layer "F.Cu") (net 83))
  (segment (start 130.95 90.885) (end 130.215 90.885) (width 0.25) (layer "F.Cu") (net 84))
  (segment (start 130.2 88.35) (end 130.85 87.7) (width 0.25) (layer "F.Cu") (net 84))
  (segment (start 130.2 92) (end 130.2 90.9) (width 0.25) (layer "F.Cu") (net 84))
  (segment (start 130.45 92.75) (end 130.2 92.5) (width 0.25) (layer "F.Cu") (net 84))
  (segment (start 130.85 87.7) (end 130.85 86.9) (width 0.25) (layer "F.Cu") (net 84))
  (segment (start 130.25 92.05) (end 130.2 92) (width 0.2) (layer "F.Cu") (net 84))
  (segment (start 130.215 90.885) (end 130.2 90.9) (width 0.25) (layer "F.Cu") (net 84))
  (segment (start 130.915 92.05) (end 130.25 92.05) (width 0.2) (layer "F.Cu") (net 84))
  (segment (start 130.2 90.9) (end 130.2 88.35) (width 0.25) (layer "F.Cu") (net 84))
  (segment (start 138.45 92.6) (end 138.3 92.75) (width 0.25) (layer "F.Cu") (net 84))
  (segment (start 130.2 92.5) (end 130.2 92) (width 0.25) (layer "F.Cu") (net 84))
  (segment (start 138.3 92.75) (end 130.45 92.75) (width 0.25) (layer "F.Cu") (net 84))
  (segment (start 138.45 92.235) (end 138.45 92.6) (width 0.25) (layer "F.Cu") (net 84))
  (segment (start 163.55 92.05) (end 163.55 91.1) (width 0.2) (layer "F.Cu") (net 85))
  (segment (start 171.873 92.727) (end 163.677 92.727) (width 0.2) (layer "F.Cu") (net 85))
  (segment (start 163.677 92.727) (end 163.55 92.6) (width 0.2) (layer "F.Cu") (net 85))
  (segment (start 163.6 92.1) (end 163.55 92.05) (width 0.2) (layer "F.Cu") (net 85))
  (segment (start 164.4 88.85) (end 164.4 86.95) (width 0.2) (layer "F.Cu") (net 85))
  (segment (start 172.1 92.185) (end 172.1 92.5) (width 0.2) (layer "F.Cu") (net 85))
  (segment (start 163.565 91.085) (end 163.55 91.1) (width 0.2) (layer "F.Cu") (net 85))
  (segment (start 163.55 92.6) (end 163.55 92.05) (width 0.2) (layer "F.Cu") (net 85))
  (segment (start 164.3 91.085) (end 163.565 91.085) (width 0.2) (layer "F.Cu") (net 85))
  (segment (start 163.55 91.1) (end 163.55 89.7) (width 0.2) (layer "F.Cu") (net 85))
  (segment (start 163.55 89.7) (end 164.4 88.85) (width 0.2) (layer "F.Cu") (net 85))
  (segment (start 172.1 92.5) (end 171.873 92.727) (width 0.2) (layer "F.Cu") (net 85))
  (segment (start 164.265 92.1) (end 163.6 92.1) (width 0.2) (layer "F.Cu") (net 85))
  (segment (start 154.558 92.327) (end 148.742 92.327) (width 0.2) (layer "F.Cu") (net 86))
  (segment (start 147.65 91.95) (end 147.65 91.085) (width 0.2) (layer "F.Cu") (net 86))
  (segment (start 147.45 88) (end 147.45 86.95) (width 0.2) (layer "F.Cu") (net 86))
  (segment (start 147.085 91.085) (end 146.95 90.95) (width 0.2) (layer "F.Cu") (net 86))
  (segment (start 147.65 91.085) (end 147.085 91.085) (width 0.2) (layer "F.Cu") (net 86))
  (segment (start 146.95 90.95) (end 146.95 88.5) (width 0.2) (layer "F.Cu") (net 86))
  (segment (start 154.6 92.285) (end 154.558 92.327) (width 0.2) (layer "F.Cu") (net 86))
  (segment (start 148.742 92.327) (end 148.7 92.285) (width 0.2) (layer "F.Cu") (net 86))
  (segment (start 148.7 92.285) (end 147.985 92.285) (width 0.2) (layer "F.Cu") (net 86))
  (segment (start 146.95 88.5) (end 147.45 88) (width 0.2) (layer "F.Cu") (net 86))
  (segment (start 147.985 92.285) (end 147.65 91.95) (width 0.2) (layer "F.Cu") (net 86))
  (segment (start 185.696 91.2) (end 186.35 91.2) (width 0.2) (layer "F.Cu") (net 87))
  (segment (start 178.7 89.5) (end 178.7 88.65) (width 0.2) (layer "F.Cu") (net 87))
  (segment (start 185.3 92.5) (end 185.3 91.596) (width 0.2) (layer "F.Cu") (net 87))
  (segment (start 179.615 92.1) (end 179.615 91.815) (width 0.2) (layer "F.Cu") (net 87))
  (segment (start 179.55 91.7) (end 179.3 91.45) (width 0.2) (layer "F.Cu") (net 87))
  (segment (start 185.3 91.596) (end 185.696 91.2) (width 0.2) (layer "F.Cu") (net 87))
  (segment (start 185.05 92.75) (end 185.3 92.5) (width 0.2) (layer "F.Cu") (net 87))
  (segment (start 179.615 92.515) (end 179.85 92.75) (width 0.2) (layer "F.Cu") (net 87))
  (segment (start 179.3 90.1) (end 178.7 89.5) (width 0.2) (layer "F.Cu") (net 87))
  (segment (start 186.35 91.2) (end 186.55 91) (width 0.2) (layer "F.Cu") (net 87))
  (segment (start 179.3 91.45) (end 179.3 90.1) (width 0.2) (layer "F.Cu") (net 87))
  (segment (start 180 91.3175) (end 180 91.185) (width 0.2) (layer "F.Cu") (net 87))
  (segment (start 179.85 92.75) (end 185.05 92.75) (width 0.2) (layer "F.Cu") (net 87))
  (segment (start 179.6175 91.7) (end 180 91.3175) (width 0.2) (layer "F.Cu") (net 87))
  (segment (start 179.615 92.1) (end 179.615 92.515) (width 0.2) (layer "F.Cu") (net 87))
  (segment (start 186.55 91) (end 186.55 90.585) (width 0.2) (layer "F.Cu") (net 87))
  (segment (start 186.7 97.75) (end 186.7 92.15) (width 0.25) (layer "F.Cu") (net 89))
  (segment (start 145.735 96.59) (end 147.34 96.59) (width 0.25) (layer "F.Cu") (net 90))
  (segment (start 149.825 96.3875) (end 147.5425 96.3875) (width 0.25) (layer "F.Cu") (net 90))
  (segment (start 147.5425 96.3875) (end 147.38 96.55) (width 0.25) (layer "F.Cu") (net 90))
  (segment (start 147.34 96.59) (end 147.38 96.55) (width 0.25) (layer "F.Cu") (net 90))
  (segment (start 186.7 99.95) (end 186.7 105.55) (width 0.25) (layer "F.Cu") (net 91))
  (segment (start 121.24 90.975) (end 121.24 87.535) (width 0.2) (layer "F.Cu") (net 93))
  (segment (start 121.2 91.015) (end 121.24 90.975) (width 0.2) (layer "F.Cu") (net 93))
  (segment (start 130.95 88.2) (end 131.25 87.9) (width 0.2) (layer "F.Cu") (net 94))
  (segment (start 130.95 89.915) (end 130.95 88.2) (width 0.2) (layer "F.Cu") (net 94))
  (segment (start 134.45 87.9) (end 134.64 88.09) (width 0.2) (layer "F.Cu") (net 94))
  (segment (start 134.64 88.09) (end 134.64 88.685) (width 0.2) (layer "F.Cu") (net 94))
  (segment (start 131.25 87.9) (end 134.45 87.9) (width 0.2) (layer "F.Cu") (net 94))
  (segment (start 150.95 87.9) (end 151.2175 88.1675) (width 0.2) (layer "F.Cu") (net 95))
  (segment (start 147.65 90.115) (end 147.65 88.85) (width 0.2) (layer "F.Cu") (net 95))
  (segment (start 151.2175 88.1675) (end 151.2175 88.8625) (width 0.2) (layer "F.Cu") (net 95))
  (segment (start 147.65 88.85) (end 148.6 87.9) (width 0.2) (layer "F.Cu") (net 95))
  (segment (start 148.6 87.9) (end 150.95 87.9) (width 0.2) (layer "F.Cu") (net 95))
  (segment (start 165.55 87.8) (end 168.05 87.8) (width 0.2) (layer "F.Cu") (net 96))
  (segment (start 168.05 87.8) (end 168.29 88.04) (width 0.2) (layer "F.Cu") (net 96))
  (segment (start 164.3 89.75) (end 165.15 88.9) (width 0.2) (layer "F.Cu") (net 96))
  (segment (start 165.15 88.9) (end 165.15 88.2) (width 0.2) (layer "F.Cu") (net 96))
  (segment (start 164.3 90.115) (end 164.3 89.75) (width 0.2) (layer "F.Cu") (net 96))
  (segment (start 168.29 88.04) (end 168.29 88.635) (width 0.2) (layer "F.Cu") (net 96))
  (segment (start 165.15 88.2) (end 165.55 87.8) (width 0.2) (layer "F.Cu") (net 96))
  (segment (start 182.78 88.38) (end 182.78 89.0208) (width 0.2) (layer "F.Cu") (net 97))
  (segment (start 182.4 88) (end 182.78 88.38) (width 0.2) (layer "F.Cu") (net 97))
  (segment (start 180.35 88) (end 182.4 88) (width 0.2) (layer "F.Cu") (net 97))
  (segment (start 180 88.35) (end 180.35 88) (width 0.2) (layer "F.Cu") (net 97))
  (segment (start 180 90.215) (end 180 88.35) (width 0.2) (layer "F.Cu") (net 97))
  (segment (start 113.65 88.15) (end 114.25 87.55) (width 0.2) (layer "F.Cu") (net 98))
  (segment (start 114.25 87.55) (end 117.3 87.55) (width 0.2) (layer "F.Cu") (net 98))
  (segment (start 113.65 89.715) (end 113.65 88.15) (width 0.2) (layer "F.Cu") (net 98))
  (segment (start 117.49 87.74) (end 117.49 88.335) (width 0.2) (layer "F.Cu") (net 98))
  (segment (start 117.3 87.55) (end 117.49 87.74) (width 0.2) (layer "F.Cu") (net 98))
  (segment (start 181.65 102.2) (end 184.125 102.2) (width 0.25) (layer "F.Cu") (net 99))
  (segment (start 180.335 101.695) (end 180.335 101.12) (width 0.2) (layer "F.Cu") (net 99))
  (segment (start 181.65 102.2) (end 180.84 102.2) (width 0.2) (layer "F.Cu") (net 99))
  (segment (start 180.335 101.12) (end 180.335 100.12) (width 0.2) (layer "F.Cu") (net 99))
  (segment (start 180.84 102.2) (end 180.335 101.695) (width 0.2) (layer "F.Cu") (net 99))
  (segment (start 181.62 102.23) (end 181.65 102.2) (width 0.2) (layer "F.Cu") (net 99))
  (segment (start 181.62 102.9) (end 181.62 102.23) (width 0.2) (layer "F.Cu") (net 99))
  (segment (start 138.49 91.175) (end 138.49 87.735) (width 0.2) (layer "F.Cu") (net 100))
  (segment (start 138.4 91.265) (end 138.49 91.175) (width 0.2) (layer "F.Cu") (net 100))
  (segment (start 155.1675 87.6625) (end 155.1675 90.7475) (width 0.2) (layer "F.Cu") (net 101))
  (segment (start 155.1675 90.7475) (end 154.6 91.315) (width 0.2) (layer "F.Cu") (net 101))
  (segment (start 172.09 91.075) (end 172.09 87.635) (width 0.2) (layer "F.Cu") (net 102))
  (segment (start 172 91.165) (end 172.09 91.075) (width 0.2) (layer "F.Cu") (net 102))
  (segment (start 186.55 87.6758) (end 186.59 87.6358) (width 0.2) (layer "F.Cu") (net 103))
  (segment (start 186.55 89.615) (end 186.55 87.6758) (width 0.2) (layer "F.Cu") (net 103))
  (segment (start 163.9375 119.95) (end 166.365 119.95) (width 0.25) (layer "F.Cu") (net 104))
  (segment (start 166.365 119.95) (end 166.815 120.4) (width 0.25) (layer "F.Cu") (net 104))
  (segment (start 165.75 95.4) (end 165.35 95) (width 0.25) (layer "F.Cu") (net 105))
  (segment (start 166.85 96.015) (end 165.75 96.015) (width 0.25) (layer "F.Cu") (net 105))
  (segment (start 165.35 95) (end 162.55 95) (width 0.25) (layer "F.Cu") (net 105))
  (segment (start 165.75 96.015) (end 165.75 95.4) (width 0.25) (layer "F.Cu") (net 105))
  (segment (start 162.275 95.275) (end 162.55 95) (width 0.25) (layer "F.Cu") (net 105))
  (segment (start 162.275 96.38) (end 162.275 95.275) (width 0.25) (layer "F.Cu") (net 105))
  (segment (start 169.05 96.015) (end 167.95 96.015) (width 0.25) (layer "F.Cu") (net 106))
  (segment (start 167.95 96.015) (end 167.95 95.1) (width 0.25) (layer "F.Cu") (net 106))
  (segment (start 161.625 95.175) (end 161.625 96.38) (width 0.25) (layer "F.Cu") (net 106))
  (segment (start 167.95 95.1) (end 167.45 94.6) (width 0.25) (layer "F.Cu") (net 106))
  (segment (start 162.2 94.6) (end 161.625 95.175) (width 0.25) (layer "F.Cu") (net 106))
  (segment (start 167.45 94.6) (end 162.2 94.6) (width 0.25) (layer "F.Cu") (net 106))
  (segment (start 160.975 95.166841) (end 160.975 96.38) (width 0.25) (layer "F.Cu") (net 107))
  (segment (start 160.975 95.166841) (end 161.918841 94.223) (width 0.25) (layer "F.Cu") (net 107))
  (segment (start 161.918841 94.223) (end 169.223 94.223) (width 0.25) (layer "F.Cu") (net 107))
  (segment (start 169.223 94.223) (end 170.15 95.15) (width 0.25) (layer "F.Cu") (net 107))
  (segment (start 171.25 96.015) (end 170.15 96.015) (width 0.25) (layer "F.Cu") (net 107))
  (segment (start 170.15 95.15) (end 170.15 96.015) (width 0.25) (layer "F.Cu") (net 107))
  (segment (start 160.325 102.12) (end 160.325 103.76) (width 0.25) (layer "F.Cu") (net 108))
  (segment (start 145.735 99.985) (end 145.75 100) (width 0.25) (layer "F.Cu") (net 109))
  (segment (start 152.425 100.641828) (end 152.425 102.1125) (width 0.25) (layer "F.Cu") (net 109))
  (segment (start 145.735 98.5) (end 145.735 99.515) (width 0.25) (layer "F.Cu") (net 109))
  (segment (start 145.75 100.515) (end 145.75 100) (width 0.25) (layer "F.Cu") (net 109))
  (segment (start 146.87701 99.12299) (end 150.906162 99.12299) (width 0.25) (layer "F.Cu") (net 109))
  (segment (start 146.485 99.515) (end 145.735 99.515) (width 0.25) (layer "F.Cu") (net 109))
  (segment (start 146.87701 99.12299) (end 146.485 99.515) (width 0.25) (layer "F.Cu") (net 109))
  (segment (start 145.735 99.515) (end 145.735 99.985) (width 0.25) (layer "F.Cu") (net 109))
  (segment (start 150.906162 99.12299) (end 152.425 100.641828) (width 0.25) (layer "F.Cu") (net 109))
  (segment (start 148.75 99.5) (end 150.75 99.5) (width 0.25) (layer "F.Cu") (net 110))
  (segment (start 147.25 99.5) (end 148.75 99.5) (width 0.25) (layer "F.Cu") (net 110))
  (segment (start 148.75 100.515) (end 148.75 99.5) (width 0.25) (layer "F.Cu") (net 110))
  (segment (start 146.75 100) (end 147.25 99.5) (width 0.25) (layer "F.Cu") (net 110))
  (segment (start 146.75 100.515) (end 146.75 100) (width 0.25) (layer "F.Cu") (net 110))
  (segment (start 150.75 99.5) (end 151.775 100.525) (width 0.25) (layer "F.Cu") (net 110))
  (segment (start 151.775 100.525) (end 151.775 102.1125) (width 0.25) (layer "F.Cu") (net 110))
  (segment (start 102.35 91.95) (end 99.85 91.95) (width 0.25) (layer "F.Cu") (net 111))
  (segment (start 107.147132 96.496324) (end 108.147132 96.496324) (width 0.25) (layer "F.Cu") (net 112))
  (segment (start 108.097132 97.776324) (end 108.097132 96.546324) (width 0.25) (layer "F.Cu") (net 112))
  (segment (start 186.75 115.25) (end 186.95 115.05) (width 0.2) (layer "F.Cu") (net 113))
  (segment (start 184.312448 116.4) (end 185.462448 115.25) (width 0.2) (layer "F.Cu") (net 113))
  (segment (start 186.95 115.05) (end 186.95 114.6) (width 0.2) (layer "F.Cu") (net 113))
  (segment (start 184.3 118.265) (end 184.3 117.3) (width 0.25) (layer "F.Cu") (net 113))
  (segment (start 184.3 117.3) (end 184.3 116.4) (width 0.2) (layer "F.Cu") (net 113))
  (segment (start 186.95 114.6) (end 186.65 114.3) (width 0.2) (layer "F.Cu") (net 113))
  (segment (start 184.3 116.4) (end 184.312448 116.4) (width 0.2) (layer "F.Cu") (net 113))
  (segment (start 186.65 114.3) (end 185.615 114.3) (width 0.2) (layer "F.Cu") (net 113))
  (segment (start 185.462448 115.25) (end 186.75 115.25) (width 0.2) (layer "F.Cu") (net 113))
  (segment (start 189.4 112.8) (end 189.6 112.6) (width 0.2) (layer "F.Cu") (net 114))
  (segment (start 189.6 112.6) (end 189.6 108.1) (width 0.2) (layer "F.Cu") (net 114))
  (segment (start 187.885 107.65) (end 189.15 107.65) (width 0.25) (layer "F.Cu") (net 114))
  (segment (start 188.585 112.8) (end 189.4 112.8) (width 0.2) (layer "F.Cu") (net 114))
  (segment (start 189.6 108.1) (end 189.15 107.65) (width 0.2) (layer "F.Cu") (net 114))
  (segment (start 166.315 103.726) (end 166.315 102.085) (width 0.25) (layer "F.Cu") (net 115))
  (segment (start 169.307 102.085) (end 166.315 102.085) (width 0.25) (layer "F.Cu") (net 115))
  (segment (start 164.275 109.975) (end 164.475 109.975) (width 0.25) (layer "F.Cu") (net 116))
  (segment (start 164.5 109.95) (end 164.475 109.975) (width 0.25) (layer "F.Cu") (net 116))
  (segment (start 164.5 109.6) (end 164.5 109.95) (width 0.25) (layer "F.Cu") (net 116))
  (segment (start 164.5 107) (end 164.5 109.6) (width 0.25) (layer "F.Cu") (net 116))
  (segment (start 164.475 109.975) (end 164.675 109.975) (width 0.25) (layer "F.Cu") (net 116))
  (segment (start 159.25 112.25) (end 161.525 109.975) (width 0.25) (layer "F.Cu") (net 116))
  (segment (start 164.5 109.75) (end 164.275 109.975) (width 0.25) (layer "F.Cu") (net 116))
  (segment (start 164.5 109.75) (end 164.675 109.925) (width 0.25) (layer "F.Cu") (net 116))
  (segment (start 164.5 109.6) (end 164.5 109.75) (width 0.25) (layer "F.Cu") (net 116))
  (segment (start 164.675 109.975) (end 166.315 109.975) (width 0.25) (layer "F.Cu") (net 116))
  (segment (start 164.675 109.925) (end 164.675 109.975) (width 0.25) (layer "F.Cu") (net 116))
  (segment (start 161.525 109.975) (end 164.275 109.975) (width 0.25) (layer "F.Cu") (net 116))
  (segment (start 159.25 115.2625) (end 159.25 112.25) (width 0.25) (layer "F.Cu") (net 116))
  (segment (start 186.3 111.5) (end 184.55 111.5) (width 0.2) (layer "F.Cu") (net 117))
  (segment (start 184.55 111.5) (end 184.2 111.15) (width 0.2) (layer "F.Cu") (net 117))
  (segment (start 186.25 112.8) (end 186.55 112.5) (width 0.2) (layer "F.Cu") (net 117))
  (segment (start 185.615 112.8) (end 186.25 112.8) (width 0.2) (layer "F.Cu") (net 117))
  (segment (start 186.55 112.5) (end 186.6 112.45) (width 0.2) (layer "F.Cu") (net 117))
  (segment (start 186.6 111.8) (end 186.3 111.5) (width 0.2) (layer "F.Cu") (net 117))
  (segment (start 186.6 112.45) (end 186.6 111.8) (width 0.2) (layer "F.Cu") (net 117))
  (segment (start 189.55 119.3) (end 189.3 119.55) (width 0.2) (layer "F.Cu") (net 118))
  (segment (start 189.3 114.3) (end 189.55 114.55) (width 0.2) (layer "F.Cu") (net 118))
  (segment (start 189.55 114.55) (end 189.55 119.3) (width 0.2) (layer "F.Cu") (net 118))
  (segment (start 188.585 114.3) (end 189.3 114.3) (width 0.2) (layer "F.Cu") (net 118))
  (segment (start 166.915 123.15) (end 166.915 123.8) (width 0.25) (layer "F.Cu") (net 125))
  (segment (start 169.67701 124.07299) (end 170.065 123.685) (width 0.25) (layer "F.Cu") (net 125))
  (segment (start 166.915 123.8) (end 167.18799 124.07299) (width 0.25) (layer "F.Cu") (net 125))
  (segment (start 167.18799 124.07299) (end 169.67701 124.07299) (width 0.25) (layer "F.Cu") (net 125))
  (segment (start 164.85 120.95) (end 166.915 123.015) (width 0.25) (layer "F.Cu") (net 125))
  (segment (start 163.9375 120.95) (end 164.85 120.95) (width 0.25) (layer "F.Cu") (net 125))
  (segment (start 187.825 108.845) (end 186.375 108.845) (width 0.25) (layer "F.Cu") (net 136))
  (segment (start 183.55 110.2) (end 184.4825 110.2) (width 0.25) (layer "F.Cu") (net 136))
  (segment (start 186.375 118.255) (end 187.825 118.255) (width 0.25) (layer "F.Cu") (net 136))
  (segment (start 185.67 117.55) (end 186.375 118.255) (width 0.25) (layer "F.Cu") (net 136))
  (segment (start 183.2 109.175) (end 183.2 109.85) (width 0.25) (layer "F.Cu") (net 136))
  (segment (start 187.825 118.255) (end 188.53 117.55) (width 0.25) (layer "F.Cu") (net 136))
  (segment (start 188.53 109.55) (end 187.825 108.845) (width 0.25) (layer "F.Cu") (net 136))
  (segment (start 184.4825 110.2) (end 185.2325 109.45) (width 0.25) (layer "F.Cu") (net 136))
  (segment (start 183.2 109.85) (end 183.55 110.2) (width 0.25) (layer "F.Cu") (net 136))
  (segment (start 186.375 108.845) (end 185.67 109.55) (width 0.25) (layer "F.Cu") (net 136))
  (segment (start 188.53 117.55) (end 188.53 109.55) (width 0.25) (layer "B.Cu") (net 136))
  (segment (start 104.3 73.1) (end 101.7 70.5) (width 0.25) (layer "F.Cu") (net 137))
  (segment (start 101.7 70.5) (end 99.75 70.5) (width 0.25) (layer "F.Cu") (net 137))
  (segment (start 107.75 79.95) (end 107.05 79.95) (width 0.25) (layer "F.Cu") (net 137))
  (segment (start 105.85 78.75) (end 104.3 77.2) (width 0.25) (layer "F.Cu") (net 137))
  (segment (start 104.3 77.2) (end 104.3 73.1) (width 0.25) (layer "F.Cu") (net 137))
  (segment (start 107.05 79.95) (end 105.85 78.75) (width 0.25) (layer "F.Cu") (net 137))
  (segment (start 144.765 96.59) (end 142.695 96.59) (width 0.25) (layer "F.Cu") (net 144))
  (segment (start 142.695 96.59) (end 142.685 96.6) (width 0.25) (layer "F.Cu") (net 144))
  (segment (start 142.685 96.6) (end 142.685 97.6) (width 0.25) (layer "F.Cu") (net 144))
  (segment (start 171.107 103.883) (end 171.107 102.834) (width 0.25) (layer "F.Cu") (net 145))
  (segment (start 164.5 105.6) (end 169.39 105.6) (width 0.25) (layer "F.Cu") (net 145))
  (segment (start 169.39 105.6) (end 171.107 103.883) (width 0.25) (layer "F.Cu") (net 145))
  (segment (start 179.365 101.12) (end 178.7 101.12) (width 0.25) (layer "F.Cu") (net 145))
  (via (at 171.107 103.89) (size 0.6) (drill 0.25) (layers "F.Cu" "B.Cu") (net 145))
  (via (at 178.7 101.12) (size 0.6) (drill 0.25) (layers "F.Cu" "B.Cu") (net 145))
  (segment (start 178.06 102.66) (end 172.337 102.66) (width 0.25) (layer "In2.Cu") (net 145))
  (segment (start 172.337 102.66) (end 171.107 103.89) (width 0.25) (layer "In2.Cu") (net 145))
  (segment (start 178.7 101.12) (end 178.7 102.02) (width 0.25) (layer "In2.Cu") (net 145))
  (segment (start 178.7 102.02) (end 178.06 102.66) (width 0.25) (layer "In2.Cu") (net 145))
  (segment (start 167.584 109.975) (end 169.315 109.975) (width 0.25) (layer "F.Cu") (net 147))
  (segment (start 92.75 132.1) (end 90.65 132.1) (width 0.25) (layer "F.Cu") (net 167))
  (segment (start 92.75 139.4) (end 90.65 139.4) (width 0.25) (layer "F.Cu") (net 167))
  (segment (start 90.65 139.4) (end 90.65 132.1) (width 0.25) (layer "F.Cu") (net 167))

  (zone (net 77) (net_name "GNDD") (layer "F.Cu") (hatch edge 0.508)
    (priority 2)
    (connect_pads yes (clearance 0.2))
    (min_thickness 0.254) (filled_areas_thickness no)
    (fill yes (thermal_gap 0.508) (thermal_bridge_width 0.508))
    (polygon
      (pts
        (xy 189.95 128.5)
        (xy 155 128.5)
        (xy 151.2 119.7)
        (xy 151.2 106.65)
        (xy 190 106.65)
      )
    )
  )
  (zone (net 76) (net_name "VCC3V3_USB") (layer "F.Cu") (hatch edge 0.508)
    (priority 3)
    (connect_pads yes (clearance 0.254))
    (min_thickness 0.254) (filled_areas_thickness no)
    (fill yes (thermal_gap 0.508) (thermal_bridge_width 0.508))
    (polygon
      (pts
        (xy 186.45 126.85)
        (xy 178.75 126.85)
        (xy 178.75 124.425)
        (xy 185.55 124.425)
        (xy 185.55 123.025)
        (xy 186.45 123.025)
      )
    )
  )
  (zone (net 32) (net_name "Net-(U4-SW)") (layer "F.Cu") (hatch edge 0.508)
    (priority 1)
    (connect_pads yes (clearance 0.254))
    (min_thickness 0.254) (filled_areas_thickness no)
    (fill yes (thermal_gap 0.508) (thermal_bridge_width 0.508))
    (polygon
      (pts
        (xy 106.797132 99.776324)
        (xy 107.497132 99.776324)
        (xy 107.497132 101.026324)
        (xy 108.447132 102.026324)
        (xy 109.247132 102.026324)
        (xy 109.247132 107.826324)
        (xy 106.807132 107.826324)
      )
    )
  )
  (zone (net 1) (net_name "VCC3V3") (layer "F.Cu") (hatch edge 0.508)
    (priority 2)
    (connect_pads yes (clearance 0.254))
    (min_thickness 0.254) (filled_areas_thickness no)
    (fill yes (thermal_gap 0.508) (thermal_bridge_width 0.508))
    (polygon
      (pts
        (xy 99.850002 94.95)
        (xy 101.99989 94.712097)
        (xy 102 87.8)
        (xy 100.35 85.9)
        (xy 100.25 84.8)
        (xy 100.3 83.6)
        (xy 100.35 82.7)
        (xy 102.35 82.7)
        (xy 103.65 84.1)
        (xy 104.8 87)
        (xy 106.199885 94.708092)
        (xy 107.607132 94.706324)
        (xy 107.607132 96.026324)
        (xy 106.447132 96.026324)
        (xy 105.647132 96.826324)
        (xy 105.647132 97.506324)
        (xy 101.007132 97.506324)
        (xy 101.007132 100.006324)
        (xy 105.107132 100.006324)
        (xy 105.06 106.33)
        (xy 98.703044 106.396383)
        (xy 98.8 95.95)
      )
    )
  )
  (zone (net 13) (net_name "Net-(U15-SW)") (layer "F.Cu") (hatch edge 0.508)
    (priority 1)
    (connect_pads yes (clearance 0.254))
    (min_thickness 0.254) (filled_areas_thickness no)
    (fill yes (thermal_gap 0.508) (thermal_bridge_width 0.508))
    (polygon
      (pts
        (xy 92.1 90.6)
        (xy 95.3 90.6)
        (xy 97.9 90.6)
        (xy 97.9 91.35)
        (xy 96.5 91.35)
        (xy 94.4 93.5)
        (xy 90.5 93.5)
        (xy 90.5 89.6)
        (xy 92.1 89.6)
      )
    )
  )
  (zone (net 2) (net_name "VCC5V0") (layer "F.Cu") (hatch edge 0.508)
    (priority 1)
    (connect_pads yes (clearance 0.254))
    (min_thickness 0.254) (filled_areas_thickness no)
    (fill yes (thermal_gap 0.508) (thermal_bridge_width 0.508))
    (polygon
      (pts
        (xy 90.5 89.2)
        (xy 90.5 84.2)
        (xy 90.6 68.5)
        (xy 95.8 68.5)
        (xy 95.8 73)
        (xy 93 73.05)
        (xy 93 80.2)
        (xy 97.2 84)
        (xy 97.4 84.2)
        (xy 97.4 89.2)
      )
    )
  )
  (zone (net 11) (net_name "VCC12V0") (layer "F.Cu") (hatch edge 0.508)
    (priority 1)
    (connect_pads yes (clearance 0.25))
    (min_thickness 0.254) (filled_areas_thickness no)
    (fill yes (thermal_gap 0.508) (thermal_bridge_width 0.508))
    (polygon
      (pts
        (xy 171 138.5)
        (xy 161.4 138.5)
        (xy 161.4 135.7)
        (xy 160.7 135.7)
        (xy 160.7 138.5)
        (xy 151.2 138.5)
        (xy 151.2 130)
        (xy 171 130)
      )
    )
  )
  (zone (net 4) (net_name "GND") (layer "F.Cu") (hatch edge 0.508)
    (connect_pads yes (clearance 0.3))
    (min_thickness 0.254) (filled_areas_thickness no)
    (fill yes (thermal_gap 0.508) (thermal_bridge_width 0.508))
    (polygon
      (pts
        (xy 190 150)
        (xy 90 150)
        (xy 90 50)
        (xy 190 50)
      )
    )
  )
  (zone (net 21) (net_name "C_MEAS_1") (layer "F.Cu") (hatch edge 0.508)
    (priority 1)
    (connect_pads yes (clearance 0.254))
    (min_thickness 0.254) (filled_areas_thickness no)
    (fill yes (thermal_gap 0.508) (thermal_bridge_width 0.508))
    (polygon
      (pts
        (xy 124.8 92.425)
        (xy 121.4 92.4)
        (xy 121.5 86.55)
        (xy 118.1 86.55)
        (xy 118.1 87.4)
        (xy 110.85 87.4)
        (xy 110.85 82.3)
        (xy 119.19 82.3)
        (xy 119.19 78)
        (xy 124.775 78.025)
      )
    )
  )
  (zone (net 27) (net_name "C_MEAS_4") (layer "F.Cu") (hatch edge 0.508)
    (priority 1)
    (connect_pads yes (clearance 0.254))
    (min_thickness 0.254) (filled_areas_thickness no)
    (fill yes (thermal_gap 0.508) (thermal_bridge_width 0.508))
    (polygon
      (pts
        (xy 175.524679 92.595384)
        (xy 172.225019 92.570128)
        (xy 172.2 86.6)
        (xy 168.85 86.6)
        (xy 168.85 87.6)
        (xy 161.475585 87.6)
        (xy 161.475585 82.39216)
        (xy 170.065585 82.39216)
        (xy 170.065585 78.09216)
        (xy 175.500245 78.117416)
      )
    )
  )
  (zone (net 43) (net_name "LOAD_5") (layer "F.Cu") (hatch edge 0.508)
    (priority 1)
    (connect_pads yes (clearance 0.2))
    (min_thickness 0.254) (filled_areas_thickness no)
    (fill yes (thermal_gap 0.508) (thermal_bridge_width 0.508))
    (polygon
      (pts
        (xy 189.502238 77.100453)
        (xy 187.122826 77.087339)
        (xy 184.470321 80.369461)
        (xy 184.420321 82.009461)
        (xy 179.7 82)
        (xy 179.7 79.2)
        (xy 182.7 76.2)
        (xy 182.7 59.6)
        (xy 189.5 59.6)
      )
    )
  )
  (zone (net 0) (net_name "") (layer "F.Cu") (hatch edge 0.508)
    (connect_pads yes (clearance 0))
    (min_thickness 0.254) (filled_areas_thickness no)
    (keepout (tracks not_allowed) (vias not_allowed) (pads allowed) (copperpour not_allowed) (footprints allowed))
    (fill (thermal_gap 0.508) (thermal_bridge_width 0.508))
    (polygon
      (pts
        (xy 185.45 106.65)
        (xy 152 106.65)
        (xy 152 106)
        (xy 185.45 106)
      )
    )
  )
  (zone (net 22) (net_name "C_MEAS_2") (layer "F.Cu") (hatch edge 0.508)
    (priority 1)
    (connect_pads yes (clearance 0.254))
    (min_thickness 0.254) (filled_areas_thickness no)
    (fill yes (thermal_gap 0.508) (thermal_bridge_width 0.508))
    (polygon
      (pts
        (xy 142.085585 92.54716)
        (xy 138.635585 92.52216)
        (xy 138.635585 86.7)
        (xy 135.5 86.7)
        (xy 135.5 87.67216)
        (xy 127.935585 87.67216)
        (xy 127.935585 82.42216)
        (xy 136.475585 82.42216)
        (xy 136.475585 78.12216)
        (xy 142.060585 78.14716)
      )
    )
  )
  (zone (net 25) (net_name "C_MEAS_5") (layer "F.Cu") (hatch edge 0.508)
    (priority 1)
    (connect_pads yes (clearance 0.254))
    (min_thickness 0.254) (filled_areas_thickness no)
    (fill yes (thermal_gap 0.508) (thermal_bridge_width 0.508))
    (polygon
      (pts
        (xy 190.155315 91.134473)
        (xy 186.855315 91.10929)
        (xy 186.849989 86.549823)
        (xy 183.499989 86.550007)
        (xy 183.5 87.650001)
        (xy 178.895585 87.65)
        (xy 178.895585 82.35216)
        (xy 184.915585 82.35216)
        (xy 184.915585 80.71)
        (xy 187.437378 77.542646)
        (xy 190.117963 77.529806)
      )
    )
  )
  (zone (net 11) (net_name "VCC12V0") (layer "F.Cu") (hatch edge 0.508)
    (priority 1)
    (connect_pads yes (clearance 0.2))
    (min_thickness 0.254) (filled_areas_thickness no)
    (fill yes (thermal_gap 0.508) (thermal_bridge_width 0.508))
    (polygon
      (pts
        (xy 121.1 92.3)
        (xy 113.2 92.3)
        (xy 113.2 87.7)
        (xy 118.65 87.7)
        (xy 118.65 87)
        (xy 121.1 87)
      )
    )
  )
  (zone (net 0) (net_name "") (layer "F.Cu") (hatch edge 0.508)
    (connect_pads yes (clearance 0))
    (min_thickness 0.254) (filled_areas_thickness no)
    (keepout (tracks not_allowed) (vias not_allowed) (pads not_allowed) (copperpour not_allowed) (footprints allowed))
    (fill (thermal_gap 0.508) (thermal_bridge_width 0.508))
    (polygon
      (pts
        (xy 189.7 106.65)
        (xy 187.9 106.65)
        (xy 187.9 106)
        (xy 189.7 106)
      )
    )
  )
  (zone (net 28) (net_name "C_MEAS_3") (layer "F.Cu") (hatch edge 0.508)
    (priority 1)
    (connect_pads yes (clearance 0.254))
    (min_thickness 0.254) (filled_areas_thickness no)
    (fill yes (thermal_gap 0.508) (thermal_bridge_width 0.508))
    (polygon
      (pts
        (xy 158.755608 91.183827)
        (xy 155.455584 91.156957)
        (xy 155.399976 86.69813)
        (xy 151.8 86.7)
        (xy 151.8 87.74216)
        (xy 144.595585 87.74216)
        (xy 144.595585 82.44216)
        (xy 153.135585 82.44216)
        (xy 153.135585 78.14216)
        (xy 158.720585 78.16716)
      )
    )
  )
  (zone (net 11) (net_name "VCC12V0") (layer "F.Cu") (hatch edge 0.508)
    (priority 1)
    (connect_pads yes (clearance 0.2))
    (min_thickness 0.254) (filled_areas_thickness no)
    (fill yes (thermal_gap 0.508) (thermal_bridge_width 0.508))
    (polygon
      (pts
        (xy 186.45 91.1)
        (xy 185.3 91.1)
        (xy 185.3 92.7)
        (xy 178.4 92.7)
        (xy 178.5 89.7)
        (xy 178.5 88.1)
        (xy 184.1 88.1)
        (xy 184.1 87)
        (xy 186.45 87)
      )
    )
  )
  (zone (net 45) (net_name "LOAD_4") (layer "F.Cu") (hatch edge 0.508)
    (priority 1)
    (connect_pads yes (clearance 0.2))
    (min_thickness 0.254) (filled_areas_thickness no)
    (fill yes (thermal_gap 0.508) (thermal_bridge_width 0.508))
    (polygon
      (pts
        (xy 173.08 77.69)
        (xy 169.662827 77.691257)
        (xy 169.658596 82.082484)
        (xy 165.080769 82.081227)
        (xy 165.080769 59.481227)
        (xy 173.080769 59.481227)
      )
    )
  )
  (zone (net 41) (net_name "LOAD_1") (layer "F.Cu") (hatch edge 0.508)
    (priority 1)
    (connect_pads yes (clearance 0.2))
    (min_thickness 0.254) (filled_areas_thickness no)
    (fill yes (thermal_gap 0.508) (thermal_bridge_width 0.508))
    (polygon
      (pts
        (xy 122.219231 77.608773)
        (xy 118.802058 77.61003)
        (xy 118.797827 82.001257)
        (xy 114.22 82)
        (xy 114.22 59.4)
        (xy 122.22 59.4)
      )
    )
  )
  (zone (net 11) (net_name "VCC12V0") (layer "F.Cu") (hatch edge 0.508)
    (priority 2)
    (connect_pads yes (clearance 0.3))
    (min_thickness 0.254) (filled_areas_thickness no)
    (fill yes (thermal_gap 0.508) (thermal_bridge_width 0.508))
    (polygon
      (pts
        (xy 98.8 94.65)
        (xy 97.8 95.6)
        (xy 92 95.6)
        (xy 92 93.6)
        (xy 94.4 93.6)
        (xy 96.6 91.4)
        (xy 98.8 91.4)
      )
    )
  )
  (zone (net 44) (net_name "LOAD_2") (layer "F.Cu") (hatch edge 0.508)
    (priority 1)
    (connect_pads yes (clearance 0.2))
    (min_thickness 0.254) (filled_areas_thickness no)
    (fill yes (thermal_gap 0.508) (thermal_bridge_width 0.508))
    (polygon
      (pts
        (xy 138.779952 77.669973)
        (xy 136.002827 77.671257)
        (xy 135.998596 82.062484)
        (xy 131.420769 82.061227)
        (xy 131.420769 59.461227)
        (xy 138.780721 59.4612)
      )
    )
  )
  (zone (net 0) (net_name "") (layer "F.Cu") (hatch edge 0.508)
    (connect_pads yes (clearance 0))
    (min_thickness 0.254) (filled_areas_thickness no)
    (keepout (tracks not_allowed) (vias not_allowed) (pads not_allowed) (copperpour not_allowed) (footprints allowed))
    (fill (thermal_gap 0.508) (thermal_bridge_width 0.508))
    (polygon
      (pts
        (xy 152 106)
        (xy 152 119.9)
        (xy 151.35 119.9)
        (xy 151.4 106.65)
      )
    )
  )
  (zone (net 0) (net_name "") (layer "F.Cu") (hatch edge 0.508)
    (connect_pads yes (clearance 0))
    (min_thickness 0.254) (filled_areas_thickness no)
    (keepout (tracks not_allowed) (vias not_allowed) (pads not_allowed) (copperpour not_allowed) (footprints allowed))
    (fill (thermal_gap 0.508) (thermal_bridge_width 0.508))
    (polygon
      (pts
        (xy 152 119.9)
        (xy 155.15 128.55)
        (xy 154.5 128.55)
        (xy 151.35 119.9)
      )
    )
  )
  (zone (net 11) (net_name "VCC12V0") (layer "F.Cu") (hatch edge 0.508)
    (priority 2)
    (connect_pads yes (clearance 0.254))
    (min_thickness 0.254) (filled_areas_thickness no)
    (fill yes (thermal_gap 0.508) (thermal_bridge_width 0.508))
    (polygon
      (pts
        (xy 93 73.45)
        (xy 98.75 73.4)
        (xy 98.7 80.2)
        (xy 101.775341 80.190545)
        (xy 101.75 82.3)
        (xy 100 82.3)
        (xy 99.9 85.3)
        (xy 97.7 85.4)
        (xy 97.660974 84.198779)
        (xy 95.55 82.4)
        (xy 93 80.1)
        (xy 92.9 73.5)
        (xy 92.9 73.45)
      )
    )
  )
  (zone (net 0) (net_name "") (layer "F.Cu") (hatch edge 0.508)
    (connect_pads yes (clearance 0))
    (min_thickness 0.254) (filled_areas_thickness no)
    (keepout (tracks not_allowed) (vias not_allowed) (pads not_allowed) (copperpour not_allowed) (footprints allowed))
    (fill (thermal_gap 0.508) (thermal_bridge_width 0.508))
    (polygon
      (pts
        (xy 189.9 128.6)
        (xy 154.5 128.6)
        (xy 154.5 127.95)
        (xy 189.9 127.95)
      )
    )
  )
  (zone (net 11) (net_name "VCC12V0") (layer "F.Cu") (hatch edge 0.508)
    (priority 2)
    (connect_pads yes (clearance 0.254))
    (min_thickness 0.254) (filled_areas_thickness no)
    (fill yes (thermal_gap 0.508) (thermal_bridge_width 0.508))
    (polygon
      (pts
        (xy 113 105.8)
        (xy 109.4 105.8)
        (xy 109.4 102)
        (xy 108.6 102)
        (xy 107.6 101)
        (xy 107.6 99.4)
        (xy 113 99.4)
      )
    )
  )
  (zone (net 42) (net_name "LOAD_3") (layer "F.Cu") (hatch edge 0.508)
    (priority 1)
    (connect_pads yes (clearance 0.2))
    (min_thickness 0.254) (filled_areas_thickness no)
    (fill yes (thermal_gap 0.508) (thermal_bridge_width 0.508))
    (polygon
      (pts
        (xy 156.17 77.62)
        (xy 152.752827 77.621257)
        (xy 152.748596 82.012484)
        (xy 148.170769 82.011227)
        (xy 148.170769 59.411227)
        (xy 156.170769 59.411227)
      )
    )
  )
  (zone (net 4) (net_name "GND") (layer "F.Cu") (hatch edge 0.508)
    (priority 3)
    (connect_pads yes (clearance 0.2))
    (min_thickness 0.254) (filled_areas_thickness no)
    (fill yes (thermal_gap 0.508) (thermal_bridge_width 0.508))
    (polygon
      (pts
        (xy 105.007132 97.606324)
        (xy 106.707132 99.306324)
        (xy 106.707132 105.106324)
        (xy 105.107132 105.106324)
        (xy 105.107132 100.006324)
        (xy 101.007132 100.006324)
        (xy 101.007132 97.606324)
      )
    )
  )
  (zone (net 11) (net_name "VCC12V0") (layer "F.Cu") (hatch edge 0.508)
    (priority 1)
    (connect_pads yes (clearance 0.2))
    (min_thickness 0.254) (filled_areas_thickness no)
    (fill yes (thermal_gap 0.508) (thermal_bridge_width 0.508))
    (polygon
      (pts
        (xy 154.9 92.6)
        (xy 147 92.6)
        (xy 147 88.1)
        (xy 152.35 88.1)
        (xy 152.35 87.1)
        (xy 154.9 87.1)
      )
    )
  )
  (zone (net 4) (net_name "GND") (layer "F.Cu") (hatch edge 0.508)
    (priority 2)
    (connect_pads yes (clearance 0.2))
    (min_thickness 0.254) (filled_areas_thickness no)
    (fill yes (thermal_gap 0.508) (thermal_bridge_width 0.508))
    (polygon
      (pts
        (xy 100.5 88)
        (xy 98.7 88)
        (xy 98.7 90.5)
        (xy 92.2 90.5)
        (xy 92.2 89.3)
        (xy 97.5 89.3)
        (xy 97.5 86.1)
        (xy 99.3 86.1)
        (xy 100.5 87.2)
      )
    )
  )
  (zone (net 0) (net_name "") (layer "F.Cu") (hatch edge 0.508)
    (connect_pads yes (clearance 0))
    (min_thickness 0.254) (filled_areas_thickness no)
    (keepout (tracks allowed) (vias allowed) (pads allowed) (copperpour not_allowed) (footprints allowed))
    (fill (thermal_gap 0.508) (thermal_bridge_width 0.508))
    (polygon
      (pts
        (xy 102 94.3)
        (xy 98.9 94.3)
        (xy 98.9 91.6)
        (xy 102 91.6)
      )
    )
  )
  (zone (net 11) (net_name "VCC12V0") (layer "F.Cu") (hatch edge 0.508)
    (priority 1)
    (connect_pads yes (clearance 0.2))
    (min_thickness 0.254) (filled_areas_thickness no)
    (fill yes (thermal_gap 0.508) (thermal_bridge_width 0.508))
    (polygon
      (pts
        (xy 171.8 92.6)
        (xy 163.9 92.6)
        (xy 163.9 88.1)
        (xy 169.35 88.1)
        (xy 169.35 87.1)
        (xy 171.8 87.1)
      )
    )
  )
  (zone (net 11) (net_name "VCC12V0") (layer "F.Cu") (hatch edge 0.508)
    (priority 1)
    (connect_pads yes (clearance 0.2))
    (min_thickness 0.254) (filled_areas_thickness no)
    (fill yes (thermal_gap 0.508) (thermal_bridge_width 0.508))
    (polygon
      (pts
        (xy 138.3 92.5)
        (xy 130.4 92.5)
        (xy 130.4 88.4)
        (xy 135.9 88.4)
        (xy 135.9 87)
        (xy 138.3 87)
      )
    )
  )
  (zone (net 4) (net_name "GND") (layer "In1.Cu") (hatch edge 0.508)
    (connect_pads yes (clearance 0.3))
    (min_thickness 0.254) (filled_areas_thickness no)
    (fill yes (thermal_gap 0.508) (thermal_bridge_width 0.508))
    (polygon
      (pts
        (xy 190 150)
        (xy 90 150)
        (xy 90 50)
        (xy 190 50)
      )
    )
  )
  (zone (net 76) (net_name "VCC3V3_USB") (layer "In2.Cu") (hatch edge 0.508)
    (priority 3)
    (connect_pads yes (clearance 0.254))
    (min_thickness 0.254) (filled_areas_thickness no)
    (fill yes (thermal_gap 0.508) (thermal_bridge_width 0.508))
    (polygon
      (pts
        (xy 181.2 126.6)
        (xy 161.8 126.6)
        (xy 161.785247 126.591746)
        (xy 155.8 126.541746)
        (xy 153.558458 121.143256)
        (xy 153.5 106.8)
        (xy 181.200049 106.8)
      )
    )
  )
  (zone (net 4) (net_name "GND") (layer "In2.Cu") (hatch edge 0.508)
    (connect_pads yes (clearance 0.3))
    (min_thickness 0.254) (filled_areas_thickness no)
    (fill yes (thermal_gap 0.508) (thermal_bridge_width 0.508))
    (polygon
      (pts
        (xy 190 150)
        (xy 90 150)
        (xy 90 50)
        (xy 190 50)
      )
    )
  )
  (zone (net 1) (net_name "VCC3V3") (layer "In2.Cu") (hatch edge 0.508)
    (priority 1)
    (connect_pads yes (clearance 0.254))
    (min_thickness 0.254) (filled_areas_thickness no)
    (fill yes (thermal_gap 0.508) (thermal_bridge_width 0.508) (smoothing fillet) (radius 0.5))
    (polygon
      (pts
        (xy 181 106.8)
        (xy 151.6 106.8)
        (xy 147.172501 104.200332)
        (xy 147.135773 101.160899)
        (xy 153.5 94.3)
        (xy 172 94.3)
        (xy 172 89.2)
        (xy 169.6 86.8)
        (xy 176.2 86.05)
        (xy 179.6 86.05)
        (xy 179.6 90)
        (xy 181 92)
      )
    )
  )
  (zone (net 11) (net_name "VCC12V0") (layer "In2.Cu") (hatch edge 0.508)
    (priority 2)
    (connect_pads yes (clearance 0.254))
    (min_thickness 0.254) (filled_areas_thickness no)
    (fill yes (thermal_gap 0.508) (thermal_bridge_width 0.508))
    (polygon
      (pts
        (xy 189.8 136)
        (xy 150.4 136)
        (xy 150.4 132.2)
        (xy 148.8 130.4)
        (xy 137.413385 130.382875)
        (xy 109.8 108.8)
        (xy 109.8 87)
        (xy 170 87)
        (xy 172.2 89.2)
        (xy 172.203244 93.999982)
        (xy 153.4 94.1)
        (xy 147 101.1)
        (xy 147 104.3)
        (xy 151.5 106.9)
        (xy 153.5 106.9)
        (xy 153.6 121.3)
        (xy 155.8 126.6)
        (xy 171.4 126.6)
        (xy 181.2 126.6)
        (xy 181.2 92)
        (xy 179.8 90)
        (xy 179.8 86)
        (xy 189.8 86)
      )
    )
  )
  (zone (net 1) (net_name "VCC3V3") (layer "In2.Cu") (hatch edge 0.508)
    (priority 3)
    (connect_pads yes (clearance 0.254))
    (min_thickness 0.254) (filled_areas_thickness no)
    (fill yes (thermal_gap 0.508) (thermal_bridge_width 0.508))
    (polygon
      (pts
        (xy 91.9 59.15)
        (xy 103.1 59.15)
        (xy 103.1 64.45)
        (xy 91.9 64.45)
      )
    )
  )
  (zone (net 1) (net_name "VCC3V3") (layer "In2.Cu") (hatch edge 0.508)
    (priority 3)
    (connect_pads yes (clearance 0.254))
    (min_thickness 0.254) (filled_areas_thickness no)
    (fill yes (thermal_gap 0.508) (thermal_bridge_width 0.508))
    (polygon
      (pts
        (xy 105.1 59.1)
        (xy 105.1 82.05)
        (xy 101.4 82.05)
        (xy 101.4 59.1)
      )
    )
  )
  (zone (net 1) (net_name "VCC3V3") (layer "In2.Cu") (hatch edge 0.508)
    (priority 3)
    (connect_pads yes (clearance 0.254))
    (min_thickness 0.254) (filled_areas_thickness no)
    (fill yes (thermal_gap 0.508) (thermal_bridge_width 0.508))
    (polygon
      (pts
        (xy 175.8 87.2)
        (xy 100.1 87.2)
        (xy 100.1 81.6)
        (xy 175.8 81.6)
      )
    )
  )
  (zone (net 77) (net_name "GNDD") (layer "In2.Cu") (hatch edge 0.508)
    (priority 4)
    (connect_pads yes (clearance 0.2))
    (min_thickness 0.254) (filled_areas_thickness no)
    (fill yes (thermal_gap 0.508) (thermal_bridge_width 0.508))
    (polygon
      (pts
        (xy 180.1 118.55)
        (xy 177.9 120.75)
        (xy 173.1 115.95)
        (xy 173.15 111.95)
        (xy 175.35 111.95)
        (xy 175.3 113.75)
      )
    )
  )
  (zone (net 4) (net_name "GND") (layer "B.Cu") (hatch edge 0.508)
    (priority 1)
    (connect_pads yes (clearance 0.254))
    (min_thickness 0.254) (filled_areas_thickness no)
    (fill yes (thermal_gap 0.508) (thermal_bridge_width 0.508) (smoothing fillet) (radius 0.5))
    (polygon
      (pts
        (xy 150.55 138.55)
        (xy 141.05 138.55)
        (xy 141.05 135.7)
        (xy 140.4 135.7)
        (xy 140.4 138.55)
        (xy 130.9 138.55)
        (xy 130.9 130)
        (xy 150.55 130)
      )
    )
  )
  (zone (net 51) (net_name "PSU_ON") (layer "B.Cu") (hatch edge 0.508)
    (priority 1)
    (connect_pads yes (clearance 0.25))
    (min_thickness 0.254) (filled_areas_thickness no)
    (fill yes (thermal_gap 0.508) (thermal_bridge_width 0.508))
    (polygon
      (pts
        (xy 112.25 146)
        (xy 108.75 146)
        (xy 108.75 139.5)
        (xy 112.25 139.5)
      )
    )
  )
  (zone (net 11) (net_name "VCC12V0") (layer "B.Cu") (hatch edge 0.508)
    (connect_pads yes (clearance 0.3))
    (min_thickness 0.254) (filled_areas_thickness no)
    (fill yes (thermal_gap 0.508) (thermal_bridge_width 0.508))
    (polygon
      (pts
        (xy 190 150)
        (xy 90 150)
        (xy 90 50)
        (xy 190 50)
      )
    )
  )
  (zone (net 21) (net_name "C_MEAS_1") (layer "B.Cu") (hatch edge 0.508)
    (priority 1)
    (connect_pads yes (clearance 0.4))
    (min_thickness 0.254) (filled_areas_thickness no)
    (fill yes (thermal_gap 0.508) (thermal_bridge_width 0.508))
    (polygon
      (pts
        (xy 125.41436 92.421242)
        (xy 121.96436 92.396242)
        (xy 121.96436 87.146242)
        (xy 111.11436 87.146242)
        (xy 111.11436 59.046242)
        (xy 119.80436 59.046242)
        (xy 119.889337 59.012821)
        (xy 125.474337 59.037821)
      )
    )
  )
  (zone (net 27) (net_name "C_MEAS_4") (layer "B.Cu") (hatch edge 0.508)
    (priority 1)
    (connect_pads yes (clearance 0.4))
    (min_thickness 0.254) (filled_areas_thickness no)
    (fill yes (thermal_gap 0.508) (thermal_bridge_width 0.508))
    (polygon
      (pts
        (xy 175.825 92.725)
        (xy 172.4 92.7)
        (xy 172.4 87.35)
        (xy 161.55 87.35)
        (xy 161.55 58.95)
        (xy 170.24 58.95)
        (xy 170.326142 59.056339)
        (xy 175.825 59.1)
      )
    )
  )
  (zone (net 28) (net_name "C_MEAS_3") (layer "B.Cu") (hatch edge 0.508)
    (priority 1)
    (connect_pads yes (clearance 0.4))
    (min_thickness 0.254) (filled_areas_thickness no)
    (fill yes (thermal_gap 0.508) (thermal_bridge_width 0.508))
    (polygon
      (pts
        (xy 159.25 92.575)
        (xy 155.8 92.55)
        (xy 155.8 87.25)
        (xy 144.95 87.25)
        (xy 144.95 58.95)
        (xy 153.64 58.95)
        (xy 153.725673 59.011045)
        (xy 159.310673 59.036045)
      )
    )
  )
  (zone (net 25) (net_name "C_MEAS_5") (layer "B.Cu") (hatch edge 0.508)
    (priority 1)
    (connect_pads yes (clearance 0.4))
    (min_thickness 0.254) (filled_areas_thickness no)
    (fill yes (thermal_gap 0.508) (thermal_bridge_width 0.508))
    (polygon
      (pts
        (xy 189.89673 92.826314)
        (xy 187.15 92.8)
        (xy 187.15 87.95)
        (xy 176.3 87.95)
        (xy 176.3 58.9)
        (xy 184.99 58.9)
        (xy 185.095214 58.932098)
        (xy 189.976944 58.958412)
      )
    )
  )
  (zone (net 22) (net_name "C_MEAS_2") (layer "B.Cu") (hatch edge 0.508)
    (priority 1)
    (connect_pads yes (clearance 0.4))
    (min_thickness 0.254) (filled_areas_thickness no)
    (fill yes (thermal_gap 0.508) (thermal_bridge_width 0.508))
    (polygon
      (pts
        (xy 142.25 92.325)
        (xy 138.8 92.3)
        (xy 138.8 87.15)
        (xy 127.95 87.15)
        (xy 127.95 59.05)
        (xy 136.64 59.05)
        (xy 136.724405 59.044383)
        (xy 142.309405 59.069383)
      )
    )
  )
)
